G04 ================== begin FILE IDENTIFICATION RECORD ==================*
G04 Layout Name:  15126-1b.brd*
G04 Film Name:    TSILK*
G04 File Format:  Gerber RS274X*
G04 File Origin:  Cadence Allegro 16.6-2015-S079*
G04 Origin Date:  Fri Feb 10 17:21:52 2017*
G04 *
G04 Layer:  REF DES/ASSEMBLY_TOP*
G04 Layer:  PACKAGE GEOMETRY/SILKSCREEN_TOP*
G04 Layer:  DRAWING FORMAT/LAYER_SILK_T*
G04 Layer:  BOARD GEOMETRY/SILKSCREEN_TOP*
G04 Layer:  VIA CLASS/FILMMASKTOP*
G04 Layer:  DRAWING FORMAT/LAYER_PCB_STORY*
G04 *
G04 Offset:    (0.00 0.00)*
G04 Mirror:    No*
G04 Mode:      Positive*
G04 Rotation:  0*
G04 FullContactRelief:  No*
G04 UndefLineWidth:     6.00*
G04 ================== end FILE IDENTIFICATION RECORD ====================*
%FSLAX35Y35*MOIN*%
%IR0*IPPOS*OFA0.00000B0.00000*MIA0B0*SFA1.00000B1.00000*%
%ADD10C,.024*%
%ADD11C,.01*%
%ADD12C,.02*%
%ADD13C,.03*%
%ADD14C,.012*%
%ADD15C,.013*%
%ADD16C,.015*%
%ADD17C,.025*%
%ADD18C,.016*%
%ADD19C,.018*%
%ADD20C,.002*%
%ADD21C,.003*%
%ADD22C,.005*%
%ADD23C,.006*%
%ADD24C,.008*%
%ADD25C,.00598*%
%ADD26R,.049X.399*%
%ADD27R,.55006X.65159*%
G75*
%LPD*%
G75*
G36*
G01X-23622Y164980D02*
X45555D01*
Y92580D01*
X-23622D01*
Y164980D01*
G37*
G36*
G01Y240531D02*
Y191831D01*
X50776D01*
Y240531D01*
X-23622D01*
G37*
G36*
G01Y349665D02*
Y300965D01*
X50776D01*
Y349665D01*
X-23622D01*
G37*
G36*
G01Y421121D02*
X45555D01*
Y348721D01*
X-23622D01*
Y421121D01*
G37*
G36*
G01X-17072Y474250D02*
Y466250D01*
X-7972D01*
Y474250D01*
X-17072D01*
G37*
G36*
G01X5789Y25577D02*
X8939D01*
X5789Y28727D01*
Y25577D01*
G37*
G36*
G01X6114Y56944D02*
X9264D01*
X6114Y60094D01*
Y56944D01*
G37*
G36*
G01X47037Y443787D02*
X44537Y446287D01*
Y441287D01*
X47037Y443787D01*
G37*
G36*
G01X20150Y515850D02*
X16050D01*
X20150Y511750D01*
Y515850D01*
G37*
G36*
G01X-4311Y532233D02*
X-1161D01*
X-4311Y535383D01*
Y532233D01*
G37*
G36*
G01Y568233D02*
X-1161D01*
X-4311Y571383D01*
Y568233D01*
G37*
G36*
G01X100419Y10937D02*
X104419D01*
X102419Y15937D01*
X100419Y10937D01*
G37*
G36*
G01X51550Y-13025D02*
Y-8925D01*
X47450Y-13025D01*
X51550D01*
G37*
G36*
G01X100508Y48915D02*
X104508D01*
X102508Y53915D01*
X100508Y48915D01*
G37*
G36*
G01X66537Y94333D02*
X70537D01*
X68537Y99333D01*
X66537Y94333D01*
G37*
G36*
G01X53100Y159240D02*
X55100Y164240D01*
X57100Y159240D01*
X53100D01*
G37*
G36*
G01X83150Y286350D02*
Y289650D01*
X79850Y286350D01*
X83150D01*
G37*
G36*
G01X62700Y377800D02*
Y373200D01*
X67300Y377800D01*
X62700D01*
G37*
G36*
G01X58762Y487944D02*
X62762D01*
X60762Y482944D01*
X58762Y487944D01*
G37*
G36*
G01X115111Y-26626D02*
X119111D01*
X117111Y-21626D01*
X115111Y-26626D01*
G37*
G36*
G01X115335Y117961D02*
X114693D01*
Y126945D01*
X115335D01*
Y117961D01*
G37*
G36*
G01X119813Y212766D02*
X122963D01*
X119813Y215916D01*
Y212766D01*
G37*
G36*
G01Y276766D02*
X122963D01*
X119813Y279916D01*
Y276766D01*
G37*
G36*
G01Y244766D02*
X122963D01*
X119813Y247916D01*
Y244766D01*
G37*
G36*
G01Y340766D02*
X122963D01*
X119813Y343916D01*
Y340766D01*
G37*
G36*
G01Y308766D02*
X122963D01*
X119813Y311916D01*
Y308766D01*
G37*
G36*
G01Y372766D02*
X122963D01*
X119813Y375916D01*
Y372766D01*
G37*
G36*
G01X115111Y512151D02*
X119111D01*
X117111Y517151D01*
X115111Y512151D01*
G37*
G36*
G01X114519Y587573D02*
X118519D01*
X116519Y592573D01*
X114519Y587573D01*
G37*
G36*
G01X114815Y550128D02*
X118815D01*
X116815Y555128D01*
X114815Y550128D01*
G37*
G36*
G01X574550Y179450D02*
X565550D01*
X574550Y188450D01*
Y179450D01*
G37*
G36*
G01X634927Y174117D02*
X629927Y176117D01*
Y172117D01*
X634927Y174117D01*
G37*
G36*
G01X647319Y299048D02*
X650919D01*
X647319Y302648D01*
Y299048D01*
G37*
G36*
G01X648280Y461467D02*
X650280Y466467D01*
X646280D01*
X648280Y461467D01*
G37*
G36*
G01X676954Y8200D02*
Y11200D01*
X673954Y8200D01*
X676954D01*
G37*
G36*
G01X715316Y91546D02*
X714674D01*
Y100530D01*
X715316D01*
Y91546D01*
G37*
G36*
G01X685850Y38850D02*
X689600D01*
X685850Y42600D01*
Y38850D01*
G37*
G36*
G01X678150Y275050D02*
X674050D01*
X678150Y270950D01*
Y275050D01*
G37*
G36*
G01X712311Y225767D02*
X709161D01*
X712311Y222617D01*
Y225767D01*
G37*
G36*
G01X711700Y288800D02*
Y284200D01*
X716300Y288800D01*
X711700D01*
G37*
G36*
G01X685850Y525100D02*
X689600D01*
X685850Y528850D01*
Y525100D01*
G37*
G36*
G01X711806Y583796D02*
X714806D01*
X711806Y586796D01*
Y583796D01*
G37*
G36*
G01X677353Y572193D02*
Y575193D01*
X674353Y572193D01*
X677353D01*
G37*
G36*
G01X764721Y-26626D02*
X768721D01*
X766721Y-21626D01*
X764721Y-26626D01*
G37*
G36*
G01X750030Y10967D02*
X754030D01*
X752030Y15967D01*
X750030Y10967D01*
G37*
G36*
G01X729237Y10906D02*
X726237D01*
X729237Y7906D01*
Y10906D01*
G37*
G36*
G01X750058Y48856D02*
X754058D01*
X752058Y53856D01*
X750058Y48856D01*
G37*
G36*
G01X769421Y212766D02*
X772571D01*
X769421Y215916D01*
Y212766D01*
G37*
G36*
G01Y244766D02*
X772571D01*
X769421Y247916D01*
Y244766D01*
G37*
G36*
G01Y276766D02*
X772571D01*
X769421Y279916D01*
Y276766D01*
G37*
G36*
G01Y308766D02*
X772571D01*
X769421Y311916D01*
Y308766D01*
G37*
G36*
G01Y340766D02*
X772571D01*
X769421Y343916D01*
Y340766D01*
G37*
G36*
G01X769371Y372766D02*
X772521D01*
X769371Y375916D01*
Y372766D01*
G37*
G36*
G01X764721Y512151D02*
X768721D01*
X766721Y517151D01*
X764721Y512151D01*
G37*
G36*
G01X732158Y495253D02*
X731516D01*
Y504237D01*
X732158D01*
Y495253D01*
G37*
G36*
G01X767827Y502814D02*
X767888Y502327D01*
X767948Y502267D01*
X768009Y501537D01*
X768070Y501476D01*
X768131Y500685D01*
X768192Y500624D01*
X768253Y499894D01*
X768313Y499834D01*
X768374Y499104D01*
X768435Y499043D01*
X768496Y498313D01*
X768557Y498252D01*
X768617Y497522D01*
X768678Y497462D01*
X768739Y496671D01*
X768800Y496610D01*
X768861Y495880D01*
X768922Y495820D01*
X768982Y495090D01*
X769043Y495029D01*
X769104Y494299D01*
X769165Y494238D01*
X769226Y493509D01*
X769287Y493448D01*
X769347Y492718D01*
X769408Y492657D01*
X769469Y491867D01*
X769530Y491806D01*
X769591Y491076D01*
X769652Y491015D01*
X769712Y490589D01*
X774152D01*
X774335Y490832D01*
X774456Y491137D01*
X774639Y491380D01*
X774760Y491684D01*
X774943Y491927D01*
X775004Y492109D01*
X775186Y492353D01*
X775307Y492657D01*
X775490Y492900D01*
X775612Y493204D01*
X775794Y493448D01*
X775916Y493752D01*
X776098Y493995D01*
X776159Y494178D01*
X776341Y494421D01*
X776463Y494725D01*
X776646Y494968D01*
X776767Y495272D01*
X776950Y495515D01*
X777071Y495820D01*
X777254Y496063D01*
X777376Y496367D01*
X777558Y496610D01*
X777619Y496793D01*
X777801Y497036D01*
X777923Y497340D01*
X778105Y497583D01*
X778227Y497887D01*
X778409Y498131D01*
Y498192D01*
X778531Y498313D01*
X778592Y498252D01*
X778653Y497157D01*
X778713Y497097D01*
X778774Y496002D01*
X778835Y495941D01*
X778896Y494846D01*
X778957Y494786D01*
X779018Y493630D01*
X779078Y493569D01*
X779139Y492474D01*
X779200Y492414D01*
X779261Y491319D01*
X779322Y491258D01*
X779382Y490589D01*
X783822D01*
X783944Y490893D01*
X784126Y491137D01*
X784187Y491319D01*
X784370Y491562D01*
X784430Y491745D01*
X784613Y491988D01*
X784674Y492170D01*
X784856Y492414D01*
X784978Y492718D01*
X785160Y492961D01*
X785221Y493144D01*
X785404Y493387D01*
X785465Y493569D01*
X785647Y493813D01*
X785707Y493995D01*
X785890Y494238D01*
X785951Y494421D01*
X786133Y494664D01*
X786194Y494846D01*
X786377Y495090D01*
X786437Y495272D01*
X786620Y495515D01*
X786681Y495698D01*
X786863Y495941D01*
X786924Y496124D01*
X787107Y496367D01*
X787228Y496671D01*
X787411Y496914D01*
X787471Y497097D01*
X787654Y497340D01*
X787715Y497522D01*
X787897Y497766D01*
X787958Y497948D01*
X788141Y498192D01*
X788201Y498374D01*
X788384Y498617D01*
X788444Y498800D01*
X788627Y499043D01*
X788688Y499226D01*
X788870Y499469D01*
X788931Y499651D01*
X789113Y499894D01*
X789174Y500077D01*
X789357Y500320D01*
X789478Y500624D01*
X789661Y500868D01*
X789722Y501050D01*
X789904Y501293D01*
X789965Y501476D01*
X790148Y501719D01*
X790208Y501902D01*
X790391Y502145D01*
X790452Y502327D01*
X790634Y502570D01*
X790695Y502753D01*
X790877Y502996D01*
X790938Y503179D01*
X791120Y503422D01*
Y503483D01*
X791181Y503544D01*
X786072D01*
X786012Y503300D01*
X785769Y502875D01*
X785707Y502631D01*
X785525Y502327D01*
X785465Y502084D01*
X785343Y501902D01*
X785282Y501658D01*
X785100Y501354D01*
X785039Y501111D01*
X784856Y500807D01*
X784795Y500563D01*
X784674Y500381D01*
X784613Y500138D01*
X784430Y499834D01*
X784370Y499591D01*
X784187Y499286D01*
X784126Y499043D01*
X784005Y498861D01*
X783944Y498617D01*
X783761Y498313D01*
X783701Y498070D01*
X783518Y497766D01*
X783457Y497522D01*
X783336Y497340D01*
X783275Y497097D01*
X783093Y496793D01*
X783031Y496550D01*
X782849Y496245D01*
X782788Y496002D01*
X782667Y495820D01*
X782606Y495576D01*
X782484Y495455D01*
X782424Y495515D01*
X782363Y496732D01*
X782302Y496793D01*
X782241Y498070D01*
X782180Y498131D01*
X782119Y499408D01*
X782059Y499469D01*
X781998Y500807D01*
X781937Y500868D01*
X781876Y502145D01*
X781815Y502206D01*
X781754Y503483D01*
X781694Y503544D01*
X777193D01*
X777011Y503118D01*
X776828Y502875D01*
X776646Y502449D01*
X776463Y502206D01*
X776281Y501780D01*
X776098Y501537D01*
X775916Y501111D01*
X775733Y500868D01*
X775612Y500563D01*
X775429Y500320D01*
X775247Y499894D01*
X775064Y499651D01*
X774882Y499226D01*
X774699Y498982D01*
X774578Y498678D01*
X774395Y498435D01*
X774213Y498009D01*
X774030Y497766D01*
X773848Y497340D01*
X773665Y497097D01*
X773483Y496671D01*
X773300Y496428D01*
X773179Y496124D01*
X772996Y495880D01*
X772814Y495455D01*
X772693Y495333D01*
X772631Y495394D01*
X772571Y497340D01*
X772510Y497401D01*
X772449Y499408D01*
X772388Y499469D01*
X772328Y501476D01*
X772267Y501537D01*
X772206Y503544D01*
X767705D01*
X767827Y502814D01*
G37*
G36*
G01X763181Y550247D02*
X767181D01*
X765181Y555247D01*
X763181Y550247D01*
G37*
G36*
G01X763032Y588136D02*
X767032D01*
X765032Y593136D01*
X763032Y588136D01*
G37*
G36*
G01X807100Y133200D02*
Y128200D01*
X827100D01*
Y133200D01*
X807100D01*
G37*
G36*
G01X802700Y172900D02*
X808300D01*
Y174700D01*
X802700D01*
Y172900D01*
G37*
G36*
G01X805500Y168300D02*
X804605Y168390D01*
X803740Y168650D01*
X802945Y169075D01*
X802245Y169645D01*
X801675Y170345D01*
X801250Y171140D01*
X800990Y172005D01*
X800900Y172900D01*
X800990Y173795D01*
X801250Y174660D01*
X801675Y175455D01*
X802245Y176155D01*
X802945Y176725D01*
X803740Y177150D01*
X804605Y177410D01*
X805500Y177500D01*
X806395Y177410D01*
X807260Y177150D01*
X808055Y176725D01*
X808755Y176155D01*
X809325Y175455D01*
X809750Y174660D01*
X810010Y173795D01*
X810100Y172900D01*
X808300D01*
X808245Y173445D01*
X808085Y173970D01*
X807830Y174455D01*
X807480Y174880D01*
X807055Y175230D01*
X806570Y175485D01*
X806045Y175645D01*
X805500Y175700D01*
X804955Y175645D01*
X804430Y175485D01*
X803945Y175230D01*
X803520Y174880D01*
X803170Y174455D01*
X802915Y173970D01*
X802755Y173445D01*
X802700Y172900D01*
X802755Y172355D01*
X802915Y171830D01*
X803170Y171345D01*
X803520Y170920D01*
X803945Y170570D01*
X804430Y170315D01*
X804955Y170155D01*
X805500Y170100D01*
X806045Y170155D01*
X806570Y170315D01*
X807055Y170570D01*
X807480Y170920D01*
X807830Y171345D01*
X808000Y171670D01*
X809325Y170345D01*
X808755Y169645D01*
X808055Y169075D01*
X807260Y168650D01*
X806395Y168390D01*
X805500Y168300D01*
G37*
G36*
G01X813100Y168100D02*
Y174900D01*
X812500Y174300D01*
X811200Y175600D01*
X813300Y177700D01*
X814900D01*
Y168100D01*
X813100D01*
G37*
G36*
G01X847439Y503787D02*
X846709Y503726D01*
X846648Y503665D01*
X846283Y503604D01*
X846223Y503544D01*
X845919Y503483D01*
X845858Y503422D01*
X845615Y503361D01*
X845554Y503300D01*
X845311Y503239D01*
X845067Y503118D01*
X844824Y502935D01*
X844763D01*
X844459Y502692D01*
X844398D01*
X843912Y502267D01*
X843851D01*
X843182Y501597D01*
X843121Y501658D01*
X843182Y502145D01*
X843243Y502206D01*
X843304Y502692D01*
X843364Y502753D01*
X843425Y503239D01*
X843486Y503300D01*
Y503544D01*
X838864D01*
X838803Y503118D01*
X838742Y503057D01*
X838681Y502510D01*
X838620Y502449D01*
X838559Y501962D01*
X838499Y501902D01*
X838438Y501415D01*
X838377Y501354D01*
X838316Y500807D01*
X838256Y500746D01*
X838194Y500259D01*
X838134Y500198D01*
X838073Y499712D01*
X838012Y499651D01*
X837951Y499165D01*
X837891Y499104D01*
X837830Y498556D01*
X837769Y498496D01*
X837708Y498009D01*
X837647Y497948D01*
X837587Y497462D01*
X837526Y497401D01*
X837465Y496854D01*
X837404Y496793D01*
X837343Y496306D01*
X837282Y496245D01*
X837222Y495759D01*
X837161Y495698D01*
X837100Y495150D01*
X837039Y495090D01*
X836978Y494603D01*
X836917Y494543D01*
X836857Y494056D01*
X836796Y493995D01*
X836735Y493509D01*
X836674Y493448D01*
X836613Y492900D01*
X836552Y492839D01*
X836492Y492353D01*
X836431Y492292D01*
X836370Y491806D01*
X836309Y491745D01*
X836248Y491197D01*
X836187Y491137D01*
X836127Y490650D01*
X836066Y490589D01*
X841114D01*
X841175Y491137D01*
X841235Y491197D01*
X841296Y491684D01*
X841357Y491745D01*
X841418Y492231D01*
X841479Y492292D01*
X841540Y492779D01*
X841600Y492839D01*
X841661Y493326D01*
X841722Y493387D01*
X841783Y493934D01*
X841844Y493995D01*
X841905Y494481D01*
X841965Y494543D01*
X842026Y495029D01*
X842087Y495090D01*
X842148Y495576D01*
X842209Y495637D01*
X842270Y496124D01*
X842330Y496185D01*
X842391Y496671D01*
X842452Y496732D01*
X842513Y497097D01*
X842574Y497157D01*
X842634Y497462D01*
X842695Y497522D01*
X842756Y497827D01*
X843182Y498678D01*
X843425Y498982D01*
Y499043D01*
X843972Y499651D01*
X844276Y499894D01*
X844763Y500138D01*
X845250Y500198D01*
X845311Y500259D01*
X845919Y500198D01*
X846283Y499894D01*
X846405Y499712D01*
X846466Y499226D01*
X846405Y498435D01*
X846344Y498374D01*
X846283Y497827D01*
X846223Y497766D01*
X846162Y497219D01*
X846101Y497157D01*
X846040Y496610D01*
X845980Y496550D01*
X845919Y496063D01*
X845858Y496002D01*
X845797Y495455D01*
X845736Y495394D01*
X845675Y494907D01*
X845615Y494846D01*
X845554Y494360D01*
X845493Y494299D01*
X845432Y493752D01*
X845371Y493691D01*
X845311Y493204D01*
X845250Y493144D01*
X845189Y492596D01*
X845128Y492535D01*
X845067Y492049D01*
X845006Y491988D01*
X844946Y491502D01*
X844885Y491441D01*
X844824Y490893D01*
X844763Y490832D01*
Y490589D01*
X849689D01*
X849750Y490893D01*
X849811Y490954D01*
X849872Y491502D01*
X849933Y491562D01*
X849994Y492049D01*
X850054Y492109D01*
X850115Y492657D01*
X850176Y492718D01*
X850237Y493204D01*
X850298Y493265D01*
X850358Y493752D01*
X850419Y493813D01*
X850480Y494360D01*
X850541Y494421D01*
X850602Y494907D01*
X850663Y494968D01*
X850723Y495515D01*
X850784Y495576D01*
X850845Y496063D01*
X850906Y496124D01*
X850967Y496610D01*
X851028Y496671D01*
X851088Y497219D01*
X851149Y497279D01*
X851210Y497766D01*
X851271Y497827D01*
X851331Y498374D01*
X851393Y498435D01*
X851453Y499043D01*
X851514Y499104D01*
X851575Y499773D01*
X851636Y499834D01*
X851696Y500807D01*
X851636Y501537D01*
X851575Y501597D01*
X851514Y501902D01*
X851453Y501962D01*
X851393Y502206D01*
X851210Y502449D01*
Y502510D01*
X850784Y502996D01*
X850358Y503361D01*
X849994Y503544D01*
X849750Y503604D01*
X849689Y503665D01*
X849264Y503726D01*
X849203Y503787D01*
X848230Y503848D01*
X847500D01*
X847439Y503787D01*
G37*
G36*
G01X832721Y503300D02*
X832539Y503057D01*
X832478Y502875D01*
X832295Y502631D01*
X832234Y502449D01*
X832052Y502206D01*
X831991Y502023D01*
X831809Y501780D01*
X831687Y501476D01*
X831504Y501233D01*
X831444Y501050D01*
X831261Y500807D01*
X831200Y500624D01*
X831018Y500381D01*
X830957Y500198D01*
X830775Y499955D01*
X830653Y499651D01*
X830470Y499408D01*
X830410Y499226D01*
X830227Y498982D01*
X830167Y498800D01*
X829984Y498556D01*
X829923Y498374D01*
X829741Y498131D01*
X829680Y497948D01*
X829498Y497705D01*
X829376Y497401D01*
X829193Y497157D01*
X829133Y496975D01*
X828950Y496732D01*
X828889Y496550D01*
X828707Y496306D01*
Y496245D01*
X828585Y496124D01*
X828524Y496185D01*
X828463Y497157D01*
X828403Y497219D01*
X828342Y498374D01*
X828281Y498435D01*
X828220Y499651D01*
X828159Y499712D01*
X828099Y500868D01*
X828038Y500928D01*
X827977Y502145D01*
X827916Y502206D01*
X827856Y503361D01*
X827794Y503422D01*
Y503544D01*
X822929D01*
X822990Y503483D01*
X823051Y502875D01*
X823111Y502814D01*
X823172Y502206D01*
X823233Y502145D01*
X823294Y501597D01*
X823355Y501537D01*
X823416Y500928D01*
X823476Y500868D01*
X823537Y500259D01*
X823598Y500198D01*
X823659Y499651D01*
X823720Y499591D01*
X823780Y498982D01*
X823841Y498921D01*
X823902Y498313D01*
X823963Y498252D01*
X824024Y497705D01*
X824085Y497644D01*
X824145Y497036D01*
X824206Y496975D01*
X824267Y496367D01*
X824328Y496306D01*
X824389Y495759D01*
X824450Y495698D01*
X824510Y495090D01*
X824571Y495029D01*
X824632Y494421D01*
X824693Y494360D01*
X824754Y493813D01*
X824815Y493752D01*
X824875Y493144D01*
X824936Y493083D01*
X824997Y492474D01*
X825057Y492414D01*
X825119Y491867D01*
X825179Y491806D01*
X825240Y491197D01*
X825301Y491137D01*
X825362Y490528D01*
X825422Y490467D01*
X825301Y490224D01*
X825119Y489981D01*
X824997Y489677D01*
X824815Y489433D01*
X824754Y489251D01*
X824571Y489008D01*
X824510Y488826D01*
X824328Y488582D01*
X824267Y488400D01*
X824085Y488156D01*
X823963Y487852D01*
X823780Y487609D01*
X823720Y487426D01*
X823537Y487183D01*
X823476Y487001D01*
X823294Y486757D01*
X823233Y486575D01*
X823051Y486332D01*
X822929Y486028D01*
X822746Y485784D01*
X822686Y485602D01*
X822503Y485359D01*
X822443Y485176D01*
X822260Y484933D01*
X822199Y484750D01*
X822017Y484507D01*
X821895Y484203D01*
X821774Y484081D01*
X826882D01*
X826943Y484264D01*
X827126Y484507D01*
X827186Y484690D01*
X827369Y484933D01*
X827430Y485115D01*
X827612Y485359D01*
X827734Y485663D01*
X827916Y485906D01*
X827977Y486089D01*
X828159Y486332D01*
X828220Y486514D01*
X828403Y486757D01*
X828463Y486940D01*
X828646Y487183D01*
X828768Y487487D01*
X828950Y487731D01*
X829011Y487913D01*
X829193Y488156D01*
X829254Y488339D01*
X829437Y488582D01*
X829498Y488765D01*
X829680Y489008D01*
X829741Y489190D01*
X829923Y489433D01*
X830045Y489738D01*
X830227Y489981D01*
X830288Y490163D01*
X830470Y490407D01*
X830531Y490589D01*
X830714Y490832D01*
X830775Y491015D01*
X830957Y491258D01*
X831079Y491562D01*
X831261Y491806D01*
X831322Y491988D01*
X831504Y492231D01*
X831565Y492414D01*
X831748Y492657D01*
X831809Y492839D01*
X831991Y493083D01*
X832113Y493387D01*
X832295Y493630D01*
X832356Y493813D01*
X832539Y494056D01*
X832599Y494238D01*
X832782Y494481D01*
X832843Y494664D01*
X833025Y494907D01*
X833086Y495090D01*
X833268Y495333D01*
X833390Y495637D01*
X833572Y495880D01*
X833633Y496063D01*
X833816Y496306D01*
X833876Y496489D01*
X834059Y496732D01*
X834120Y496914D01*
X834302Y497157D01*
X834424Y497462D01*
X834606Y497705D01*
X834667Y497887D01*
X834850Y498131D01*
X834910Y498313D01*
X835093Y498556D01*
X835154Y498739D01*
X835336Y498982D01*
X835458Y499286D01*
X835640Y499530D01*
X835701Y499712D01*
X835883Y499955D01*
X835944Y500138D01*
X836127Y500381D01*
X836187Y500563D01*
X836370Y500807D01*
X836492Y501111D01*
X836674Y501354D01*
X836735Y501537D01*
X836917Y501780D01*
X836978Y501962D01*
X837161Y502206D01*
X837222Y502388D01*
X837404Y502631D01*
X837465Y502814D01*
X837647Y503057D01*
X837769Y503361D01*
X837891Y503483D01*
Y503604D01*
X832843D01*
X832721Y503300D01*
G37*
G36*
G01X798541Y502996D02*
X798601Y502935D01*
X798662Y502145D01*
X798723Y502084D01*
X798784Y501354D01*
X798844Y501293D01*
X798906Y500563D01*
X798966Y500503D01*
X799027Y499773D01*
X799088Y499712D01*
X799149Y498982D01*
X799209Y498921D01*
X799270Y498192D01*
X799331Y498131D01*
X799392Y497340D01*
X799453Y497279D01*
X799514Y496550D01*
X799574Y496489D01*
X799635Y495759D01*
X799696Y495698D01*
X799757Y494968D01*
X799818Y494907D01*
X799878Y494178D01*
X799939Y494117D01*
X800000Y493387D01*
X800061Y493326D01*
X800122Y492535D01*
X800183Y492474D01*
X800243Y491745D01*
X800304Y491684D01*
X800365Y490954D01*
X800426Y490893D01*
Y490589D01*
X804926D01*
X805048Y490832D01*
X805231Y491076D01*
X805352Y491380D01*
X805535Y491623D01*
X805656Y491927D01*
X805839Y492170D01*
X805961Y492474D01*
X806143Y492718D01*
X806265Y493022D01*
X806447Y493265D01*
X806569Y493569D01*
X806751Y493813D01*
X806812Y493995D01*
X806994Y494238D01*
X807116Y494543D01*
X807298Y494786D01*
X807420Y495090D01*
X807603Y495333D01*
X807724Y495637D01*
X807907Y495880D01*
X808028Y496185D01*
X808211Y496428D01*
X808332Y496732D01*
X808515Y496975D01*
X808576Y497157D01*
X808758Y497401D01*
X808880Y497705D01*
X809062Y497948D01*
X809245Y498313D01*
X809306Y498252D01*
X809366Y497766D01*
X809427Y497036D01*
X809488Y496671D01*
X809549Y495820D01*
X809609Y495759D01*
X809670Y494664D01*
X809731Y494603D01*
X809792Y493509D01*
X809853Y493448D01*
X809914Y492292D01*
X809974Y492231D01*
X810035Y491137D01*
X810096Y491076D01*
Y490589D01*
X814536D01*
X814657Y490832D01*
X814840Y491076D01*
X814901Y491258D01*
X815083Y491502D01*
X815144Y491684D01*
X815327Y491927D01*
X815387Y492109D01*
X815570Y492353D01*
X815631Y492535D01*
X815813Y492779D01*
X815874Y492961D01*
X816056Y493204D01*
X816117Y493387D01*
X816300Y493630D01*
X816361Y493813D01*
X816543Y494056D01*
X816604Y494238D01*
X816786Y494481D01*
X816908Y494786D01*
X817091Y495029D01*
X817151Y495211D01*
X817333Y495455D01*
X817394Y495637D01*
X817577Y495880D01*
X817638Y496063D01*
X817820Y496306D01*
X817881Y496489D01*
X818063Y496732D01*
X818124Y496914D01*
X818307Y497157D01*
X818368Y497340D01*
X818550Y497583D01*
X818611Y497766D01*
X818793Y498009D01*
X818854Y498192D01*
X819037Y498435D01*
X819097Y498617D01*
X819280Y498861D01*
X819402Y499165D01*
X819584Y499408D01*
X819645Y499591D01*
X819827Y499834D01*
X819888Y500016D01*
X820070Y500259D01*
X820131Y500442D01*
X820314Y500685D01*
X820374Y500868D01*
X820557Y501111D01*
X820618Y501293D01*
X820800Y501537D01*
X820861Y501719D01*
X821044Y501962D01*
X821104Y502145D01*
X821287Y502388D01*
X821348Y502570D01*
X821530Y502814D01*
X821652Y503118D01*
X821834Y503361D01*
X821895Y503483D01*
Y503544D01*
X816847D01*
X816604Y503057D01*
X816543Y502814D01*
X816361Y502510D01*
X816300Y502267D01*
X816178Y502084D01*
X816117Y501841D01*
X815935Y501537D01*
X815874Y501293D01*
X815691Y500989D01*
X815631Y500746D01*
X815509Y500563D01*
X815448Y500320D01*
X815266Y500016D01*
X815205Y499773D01*
X815022Y499469D01*
X814962Y499226D01*
X814840Y499043D01*
X814779Y498800D01*
X814597Y498496D01*
X814536Y498252D01*
X814354Y497948D01*
X814293Y497705D01*
X814171Y497522D01*
X814110Y497279D01*
X813928Y496975D01*
X813867Y496732D01*
X813685Y496428D01*
X813624Y496185D01*
X813502Y496002D01*
X813441Y495759D01*
X813259Y495455D01*
X813198Y495515D01*
X813137Y496489D01*
X813076Y496854D01*
X813015Y497827D01*
X812955Y498192D01*
X812894Y499165D01*
X812833Y499530D01*
X812772Y500503D01*
X812711Y500868D01*
X812650Y501841D01*
X812590Y502206D01*
X812529Y503179D01*
X812468Y503544D01*
X807967D01*
Y503483D01*
X807785Y503239D01*
X807603Y502814D01*
X807420Y502570D01*
X807238Y502145D01*
X807055Y501902D01*
X806873Y501476D01*
X806690Y501233D01*
X806569Y500928D01*
X806386Y500685D01*
X806204Y500259D01*
X806021Y500016D01*
X805839Y499591D01*
X805656Y499347D01*
X805474Y498921D01*
X805291Y498678D01*
X805170Y498374D01*
X804987Y498131D01*
X804805Y497705D01*
X804622Y497462D01*
X804440Y497036D01*
X804257Y496793D01*
X804075Y496367D01*
X803893Y496124D01*
X803771Y495820D01*
X803589Y495576D01*
X803467Y495333D01*
X803406Y495394D01*
X803345Y496732D01*
X803284Y497462D01*
X803224Y498800D01*
X803163Y499530D01*
X803102Y500868D01*
X803041Y501719D01*
X802980Y502935D01*
X802920Y503544D01*
X798480D01*
X798541Y502996D01*
G37*
G36*
G01X795621Y509991D02*
X795135Y509930D01*
X794952Y509808D01*
X794709Y509747D01*
X794466Y509626D01*
X794161Y509382D01*
X794101D01*
X793432Y508652D01*
Y508592D01*
X793249Y508348D01*
X793128Y508105D01*
X793067Y507801D01*
X793006Y507740D01*
X792945Y507132D01*
X793006Y506341D01*
X793067Y506280D01*
X793128Y506037D01*
X793310Y505794D01*
Y505733D01*
X793857Y505246D01*
X793918D01*
X794040Y505125D01*
X794283Y505064D01*
X794344Y505003D01*
X794831Y504943D01*
X794891Y504881D01*
X795865Y504943D01*
X795925Y505003D01*
X796230Y505064D01*
X796290Y505125D01*
X796533Y505186D01*
X796777Y505307D01*
X797142Y505611D01*
X797202D01*
X797872Y506341D01*
X797932Y506524D01*
X798115Y506767D01*
X798176Y507010D01*
X798237Y507071D01*
X798297Y507558D01*
X798358Y507619D01*
X798297Y508531D01*
X798237Y508592D01*
X798176Y508835D01*
X798054Y509078D01*
X797628Y509565D01*
X797385Y509747D01*
X797020Y509930D01*
X796594Y509991D01*
X796533Y510051D01*
X795682D01*
X795621Y509991D01*
G37*
G36*
G01X792094Y503179D02*
X792033Y503118D01*
X791972Y502631D01*
X791911Y502570D01*
X791850Y502084D01*
X791790Y502023D01*
X791729Y501476D01*
X791668Y501415D01*
X791607Y500928D01*
X791546Y500868D01*
X791485Y500381D01*
X791425Y500320D01*
X791364Y499773D01*
X791303Y499712D01*
X791242Y499226D01*
X791181Y499165D01*
X791120Y498678D01*
X791060Y498617D01*
X790999Y498070D01*
X790938Y498009D01*
X790877Y497522D01*
X790817Y497462D01*
X790756Y496975D01*
X790695Y496914D01*
X790634Y496367D01*
X790573Y496306D01*
X790512Y495820D01*
X790452Y495759D01*
X790391Y495272D01*
X790330Y495211D01*
X790269Y494664D01*
X790208Y494603D01*
X790148Y494117D01*
X790087Y494056D01*
X790026Y493569D01*
X789965Y493509D01*
X789904Y492961D01*
X789843Y492900D01*
X789783Y492414D01*
X789722Y492353D01*
X789661Y491867D01*
X789600Y491806D01*
X789539Y491258D01*
X789478Y491197D01*
X789418Y490711D01*
X789357Y490650D01*
Y490589D01*
X794709D01*
X794770Y490954D01*
X794831Y491015D01*
X794891Y491502D01*
X794952Y491562D01*
X795013Y492109D01*
X795074Y492170D01*
X795135Y492657D01*
X795195Y492718D01*
X795256Y493204D01*
X795317Y493265D01*
X795378Y493813D01*
X795439Y493873D01*
X795500Y494360D01*
X795560Y494421D01*
X795621Y494907D01*
X795682Y494968D01*
X795743Y495515D01*
X795804Y495576D01*
X795865Y496063D01*
X795925Y496124D01*
X795986Y496610D01*
X796047Y496671D01*
X796108Y497219D01*
X796169Y497279D01*
X796230Y497766D01*
X796290Y497827D01*
X796351Y498313D01*
X796412Y498374D01*
X796473Y498861D01*
X796533Y498921D01*
X796594Y499469D01*
X796655Y499530D01*
X796716Y500016D01*
X796777Y500077D01*
X796837Y500563D01*
X796898Y500624D01*
X796959Y501172D01*
X797020Y501233D01*
X797081Y501719D01*
X797142Y501780D01*
X797202Y502267D01*
X797263Y502327D01*
X797324Y502875D01*
X797385Y502935D01*
X797446Y503422D01*
X797507Y503483D01*
Y503544D01*
X792154D01*
X792094Y503179D01*
G37*
G36*
G01X821203Y477740D02*
G02I-7573J0D01*
G37*
G36*
G01X870185Y506037D02*
X870307Y505794D01*
X869760D01*
X869699Y505855D01*
X869517Y506280D01*
X869334Y506524D01*
Y506645D01*
X869152Y506706D01*
X868726Y506767D01*
Y505794D01*
X868300D01*
Y507590D01*
X868726D01*
Y507132D01*
X869030D01*
X869638Y507193D01*
X869699Y507375D01*
X869638Y507740D01*
X869456D01*
X869395Y507801D01*
X868726D01*
Y507591D01*
X868300D01*
Y508166D01*
X869456D01*
X869820Y508105D01*
X870064Y507922D01*
X870125Y507680D01*
X870185Y507619D01*
X870125Y507254D01*
X869881Y506950D01*
X869638Y506889D01*
X869577Y506828D01*
X869699Y506706D01*
X869760D01*
X869820Y506645D01*
X869942Y506463D01*
X870003Y506280D01*
X870185Y506037D01*
G37*
G36*
G01X870672Y505307D02*
X870368Y505064D01*
X870125Y505003D01*
X869942Y504881D01*
X868908Y504821D01*
X868848Y504881D01*
X868483Y504943D01*
X868118Y505125D01*
X867874Y505307D01*
X867449Y505794D01*
X867206Y506280D01*
X867144Y507193D01*
X867145Y507199D01*
X867530D01*
X867509Y507010D01*
X867570Y506402D01*
X867692Y506159D01*
X867935Y505855D01*
Y505794D01*
X868361Y505429D01*
X868604Y505307D01*
X869030Y505246D01*
X869091Y505186D01*
X869820Y505246D01*
X869881Y505307D01*
X870125Y505368D01*
X870490Y505672D01*
X870915Y506159D01*
X870976Y506402D01*
X871037Y506463D01*
X871098Y506889D01*
X871037Y507497D01*
X870976Y507558D01*
X870915Y507801D01*
X870611Y508166D01*
Y508287D01*
X870490D01*
X870125Y508592D01*
X870003D01*
X869942Y508652D01*
X869577Y508713D01*
X869517Y508774D01*
X868787Y508713D01*
X868726Y508652D01*
X868483Y508592D01*
X868239Y508409D01*
X868178D01*
X867753Y507922D01*
X867570Y507558D01*
X867530Y507200D01*
X867145D01*
X867206Y507680D01*
X867449Y508166D01*
X867631Y508409D01*
X868118Y508835D01*
X868483Y509017D01*
X868848Y509078D01*
X868908Y509139D01*
X869699D01*
X869760Y509078D01*
X870125Y509017D01*
X870368Y508896D01*
X870672Y508652D01*
X870733D01*
X871159Y508166D01*
X871280Y507922D01*
X871341Y507680D01*
X871402Y507619D01*
X871463Y506524D01*
X871402Y506463D01*
X871341Y506159D01*
X871159Y505794D01*
X870733Y505307D01*
X870672D01*
G37*
G36*
G01X862887Y503787D02*
X862157Y503726D01*
X862096Y503665D01*
X861671Y503604D01*
X861610Y503544D01*
X861306Y503483D01*
X861124Y503361D01*
X860880Y503300D01*
X860272Y502996D01*
X859968Y502753D01*
X859907D01*
X859542Y502449D01*
X859481D01*
X858569Y501537D01*
X858508Y501597D01*
X858569Y502023D01*
X858630Y502084D01*
X858691Y502570D01*
X858752Y502631D01*
X858812Y503118D01*
X858873Y503179D01*
X858934Y503483D01*
Y503544D01*
X854312D01*
X854251Y503483D01*
X854190Y502996D01*
X854129Y502935D01*
X854069Y502388D01*
X854007Y502327D01*
X853947Y501841D01*
X853886Y501780D01*
X853825Y501293D01*
X853764Y501233D01*
X853704Y500685D01*
X853643Y500624D01*
X853582Y500138D01*
X853521Y500077D01*
X853460Y499591D01*
X853399Y499530D01*
X853339Y499043D01*
X853278Y498982D01*
X853217Y498435D01*
X853156Y498374D01*
X853095Y497887D01*
X853035Y497827D01*
X852974Y497340D01*
X852913Y497279D01*
X852852Y496732D01*
X852791Y496671D01*
X852730Y496185D01*
X852670Y496124D01*
X852609Y495637D01*
X852548Y495576D01*
X852487Y495029D01*
X852426Y494968D01*
X852365Y494481D01*
X852305Y494421D01*
X852244Y493934D01*
X852183Y493873D01*
X852122Y493387D01*
X852061Y493326D01*
X852000Y492779D01*
X851940Y492718D01*
X851879Y492231D01*
X851818Y492170D01*
X851757Y491684D01*
X851696Y491623D01*
X851636Y491076D01*
X851575Y491015D01*
X851514Y490589D01*
X856501D01*
X856562Y490954D01*
X856623Y491015D01*
X856683Y491562D01*
X856744Y491623D01*
X856805Y492109D01*
X856866Y492170D01*
X856927Y492657D01*
X856988Y492718D01*
X857048Y493204D01*
X857109Y493265D01*
X857170Y493752D01*
X857231Y493813D01*
X857292Y494360D01*
X857353Y494421D01*
X857413Y494907D01*
X857474Y494968D01*
X857535Y495455D01*
X857596Y495515D01*
X857657Y496002D01*
X857718Y496063D01*
X857778Y496550D01*
X857839Y496610D01*
X857900Y497036D01*
X857961Y497097D01*
X858022Y497401D01*
X858083Y497462D01*
X858143Y497705D01*
X858204Y497766D01*
X858265Y498009D01*
X858326Y498070D01*
X858387Y498313D01*
X858569Y498556D01*
X858630Y498739D01*
X858873Y499043D01*
Y499104D01*
X859299Y499591D01*
X859360D01*
X859785Y499955D01*
X860150Y500138D01*
X860637Y500198D01*
X860698Y500259D01*
X861306Y500198D01*
X861549Y500016D01*
X861671D01*
Y499894D01*
X861793Y499773D01*
X861853Y499408D01*
X861914Y499347D01*
X861853Y498617D01*
X861793Y498556D01*
X861731Y497948D01*
X861671Y497887D01*
X861610Y497340D01*
X861549Y497279D01*
X861488Y496793D01*
X861428Y496732D01*
X861367Y496185D01*
X861306Y496124D01*
X861245Y495637D01*
X861184Y495576D01*
X861124Y495090D01*
X861063Y495029D01*
X861002Y494481D01*
X860941Y494421D01*
X860880Y493934D01*
X860819Y493873D01*
X860759Y493326D01*
X860698Y493265D01*
X860637Y492779D01*
X860576Y492718D01*
X860515Y492231D01*
X860454Y492170D01*
X860394Y491623D01*
X860333Y491562D01*
X860272Y491076D01*
X860211Y491015D01*
X860150Y490589D01*
X865137D01*
X865198Y491076D01*
X865259Y491137D01*
X865320Y491623D01*
X865381Y491684D01*
X865442Y492231D01*
X865502Y492292D01*
X865563Y492779D01*
X865624Y492839D01*
X865685Y493387D01*
X865746Y493448D01*
X865807Y493934D01*
X865867Y493995D01*
X865928Y494481D01*
X865989Y494543D01*
X866050Y495090D01*
X866111Y495150D01*
X866171Y495637D01*
X866232Y495698D01*
X866293Y496245D01*
X866354Y496306D01*
X866415Y496793D01*
X866476Y496854D01*
X866536Y497401D01*
X866597Y497462D01*
X866658Y497948D01*
X866719Y498009D01*
X866780Y498556D01*
X866841Y498617D01*
X866901Y499226D01*
X866962Y499286D01*
X867023Y500016D01*
X867084Y500077D01*
X867023Y501658D01*
X866962Y501719D01*
X866901Y501962D01*
X866841Y502023D01*
Y502145D01*
X866658Y502388D01*
Y502449D01*
X866232Y502935D01*
X865746Y503361D01*
X865259Y503604D01*
X864955Y503665D01*
X864894Y503726D01*
X864286Y503787D01*
X864225Y503848D01*
X862948D01*
X862887Y503787D01*
G37*
G36*
G01X1215150Y179450D02*
X1224150Y188450D01*
Y179450D01*
X1221568D01*
G03X1219592I-988J360D01*
G01X1215150D01*
G37*
G36*
G01X1297807Y178987D02*
X1299807Y183987D01*
X1295807D01*
X1297807Y178987D01*
G37*
G36*
G01Y461467D02*
X1299807Y466467D01*
X1295807D01*
X1297807Y461467D01*
G37*
G36*
G01X1340850Y509400D02*
X1344600D01*
X1340850Y513150D01*
Y509400D01*
G37*
G36*
G01X1377400Y4943D02*
X1374250D01*
X1377400Y1793D01*
Y4943D01*
G37*
G36*
G01X1369050Y72550D02*
X1364950D01*
X1369050Y68450D01*
Y72550D01*
G37*
G36*
G01X1377711Y36967D02*
X1374561D01*
X1377711Y33817D01*
Y36967D01*
G37*
G36*
G01X1346050Y98800D02*
X1349800D01*
X1346050Y102550D01*
Y98800D01*
G37*
G36*
G01X1380018Y395835D02*
X1376868D01*
X1380018Y392685D01*
Y395835D01*
G37*
G36*
G01X1402510Y531905D02*
X1406610D01*
X1402510Y536005D01*
Y531905D01*
G37*
G36*
G01X1381711Y583823D02*
X1378561D01*
X1381711Y580673D01*
Y583823D01*
G37*
G36*
G01Y615023D02*
X1378561D01*
X1381711Y611873D01*
Y615023D01*
G37*
G36*
G01X1441978Y-21750D02*
X1443978Y-26750D01*
X1439978D01*
X1441978Y-21750D01*
G37*
G36*
G01X1499760Y20433D02*
Y27519D01*
X1406422D01*
Y20433D01*
X1499760D01*
G37*
G36*
G01X1502221Y-10786D02*
X1500221Y-5786D01*
X1504221D01*
X1502221Y-10786D01*
G37*
G36*
G01X1498926Y39108D02*
X1501426Y41608D01*
X1496426D01*
X1498926Y39108D01*
G37*
G36*
G01X1502719Y83869D02*
X1500219Y86369D01*
Y81369D01*
X1502719Y83869D01*
G37*
G36*
G01X1469962Y617482D02*
Y614332D01*
X1473112Y617482D01*
X1469962D01*
G37*
G36*
G01X1505500Y618750D02*
Y615600D01*
X1508650Y618750D01*
X1505500D01*
G37*
G36*
G01X1535765Y274735D02*
Y271735D01*
X1538765Y274735D01*
X1535765D01*
G37*
G36*
G01X1577404Y582142D02*
X1580404D01*
X1577404Y585142D01*
Y582142D01*
G37*
G36*
G01X1546150Y593450D02*
X1550250D01*
X1546150Y597550D01*
Y593450D01*
G37*
G36*
G01X1611384Y263470D02*
X1609263Y268420D01*
X1606435Y265592D01*
X1611384Y263470D01*
G37*
G36*
G01X1629393Y522483D02*
X1624393Y520483D01*
Y524483D01*
X1629393Y522483D01*
G37*
G36*
G01X1703481Y-21750D02*
X1705481Y-26750D01*
X1701481D01*
X1703481Y-21750D01*
G37*
G36*
G01X1700820Y50500D02*
Y64500D01*
X1681820D01*
Y50500D01*
X1700820D01*
G37*
G36*
G01X1651450Y433410D02*
Y425410D01*
X1660550D01*
Y433410D01*
X1651450D01*
G37*
G36*
G01X1696378Y628128D02*
X1692378D01*
X1694378Y623128D01*
X1696378Y628128D01*
G37*
G36*
G01X1769482Y-21750D02*
X1771482Y-26750D01*
X1767482D01*
X1769482Y-21750D01*
G37*
G36*
G01X1724541Y177632D02*
X1720541D01*
X1722541Y182632D01*
X1724541Y177632D01*
G37*
G36*
G01X1732499Y215000D02*
X1736499D01*
X1734499Y220000D01*
X1732499Y215000D01*
G37*
G36*
G01X1782294Y97237D02*
Y94237D01*
X1785294Y97237D01*
X1782294D01*
G37*
G36*
G01X1812594Y167737D02*
Y164737D01*
X1815594Y167737D01*
X1812594D01*
G37*
G36*
G01X1832006Y530936D02*
Y534936D01*
X1827006Y532936D01*
X1832006Y530936D01*
G37*
G36*
G01X1868218Y44422D02*
X1864218D01*
X1866218Y39422D01*
X1868218Y44422D01*
G37*
G36*
G01X1865980Y106000D02*
X1869880D01*
X1865980Y109900D01*
Y106000D01*
G37*
G36*
G01X1842463Y150094D02*
X1845463D01*
X1842463Y153094D01*
Y150094D01*
G37*
G36*
G01X1892498Y502884D02*
X1896498D01*
X1894498Y507884D01*
X1892498Y502884D01*
G37*
G36*
G01X1865676Y559033D02*
Y563033D01*
X1860676Y561033D01*
X1865676Y559033D01*
G37*
G36*
G01X1841402Y533548D02*
Y529548D01*
X1846402Y531548D01*
X1841402Y533548D01*
G37*
G36*
G01X1886400Y565200D02*
X1885000Y563800D01*
X1887800D01*
X1886400Y565200D01*
G37*
G36*
G01X1893500Y552000D02*
X1894900Y550600D01*
Y553400D01*
X1893500Y552000D01*
G37*
G36*
G01X1880603Y594258D02*
Y598258D01*
X1885603Y596258D01*
X1880603Y594258D01*
G37*
G36*
G01X1951374Y143967D02*
X1948918Y146423D01*
Y141511D01*
X1951374Y143967D01*
G37*
G36*
G01X1926200Y153400D02*
Y156800D01*
X1922800Y153400D01*
X1926200D01*
G37*
G36*
G01X1921925Y471318D02*
X1917925D01*
X1919925Y466318D01*
X1921925Y471318D01*
G37*
G36*
G01X1902570Y505490D02*
X1906570D01*
X1904570Y500490D01*
X1902570Y505490D01*
G37*
G36*
G01X1958191Y483069D02*
X1956691Y481569D01*
Y484569D01*
X1958191Y483069D01*
G37*
G36*
G01X1959381Y141455D02*
X1975387D01*
Y194135D01*
X1959381D01*
Y141455D01*
G37*
G36*
G01X1971406Y557488D02*
Y561504D01*
X1966406Y559496D01*
X1971406Y557488D01*
G37*
%LPC*%
G75*
G36*
G01X-14824Y201281D02*
Y236181D01*
X44433D01*
Y196181D01*
X38433D01*
Y201281D01*
X-14824D01*
G37*
G36*
G01Y310415D02*
Y345315D01*
X44433D01*
Y305315D01*
X38433D01*
Y310415D01*
X-14824D01*
G37*
G36*
G01X812585Y479459D02*
X811001Y481043D01*
X811716D01*
G02X812585Y479459I-500J-1305D01*
G37*
G36*
G01X811748Y478446D02*
X810064Y478445D01*
Y478446D01*
X810062Y480720D01*
X812115Y478668D01*
G02X811748Y478446I-898J1070D01*
G37*
G36*
G01X818080Y476567D02*
G02X816805Y475241I-1263J-62D01*
G01X815553Y476492D01*
G02Y476499I1264J3D01*
G01X815552Y478119D01*
Y478121D01*
G02X818058Y477531I1115J-883D01*
G01X818080Y476567D01*
G37*
G36*
G01X809177Y482868D02*
G02X818758Y473288I4455J-5126D01*
G01X817623Y474423D01*
G03X819044Y476463I-1003J2214D01*
G01X819036Y477557D01*
G03X815552Y479347I-2357J-302D01*
G01Y481943D01*
X814528D01*
Y477517D01*
X813343Y478702D01*
G03X811505Y482067I-2104J1035D01*
G01X809975Y482069D01*
X809192Y482852D01*
X809177Y482868D01*
G37*
G36*
G01X818130Y472654D02*
G02X808544Y482239I-4500J5086D01*
G01X809057Y481726D01*
X809059Y474237D01*
X810064D01*
Y477437D01*
X811703Y477438D01*
G03X812798Y477985I-464J2299D01*
G01X814528Y476254D01*
Y474237D01*
X815552D01*
Y474490D01*
G03X816211Y474241I1198J2175D01*
G03X816575Y474207I407J2396D01*
G01X818107Y472675D01*
X818130Y472654D01*
G37*
G54D26*
X40605Y129130D03*
Y385271D03*
G54D27*
X9055Y131101D03*
Y387242D03*
%LPD*%
G75*
G36*
G01X-15291Y160480D02*
G02Y162480I0J1000D01*
G01X-10291D01*
G02Y160480I0J-1000D01*
G01X-15291D01*
G37*
G36*
G01Y416621D02*
G02Y418621I0J1000D01*
G01X-10291D01*
G02Y416621I0J-1000D01*
G01X-15291D01*
G37*
G36*
G01X17781Y160480D02*
G02Y162480I0J1000D01*
G01X22781D01*
G02Y160480I0J-1000D01*
G01X17781D01*
G37*
G36*
G01X28805D02*
G02Y162480I0J1000D01*
G01X33805D01*
G02Y160480I0J-1000D01*
G01X28805D01*
G37*
G36*
G01X-4267D02*
G02Y162480I0J1000D01*
G01X733D01*
G02Y160480I0J-1000D01*
G01X-4267D01*
G37*
G36*
G01X6757D02*
G02Y162480I0J1000D01*
G01X11757D01*
G02Y160480I0J-1000D01*
G01X6757D01*
G37*
G36*
G01X-13118Y232181D02*
G02Y234181I0J1000D01*
G01X-10118D01*
G02Y232181I0J-1000D01*
G01X-13118D01*
G37*
G36*
G01X-5244D02*
G02Y234181I0J1000D01*
G01X-2244D01*
G02Y232181I0J-1000D01*
G01X-5244D01*
G37*
G36*
G01X2630D02*
G02Y234181I0J1000D01*
G01X5630D01*
G02Y232181I0J-1000D01*
G01X2630D01*
G37*
G36*
G01X18378D02*
G02Y234181I0J1000D01*
G01X21378D01*
G02Y232181I0J-1000D01*
G01X18378D01*
G37*
G36*
G01X26252D02*
G02Y234181I0J1000D01*
G01X29252D01*
G02Y232181I0J-1000D01*
G01X26252D01*
G37*
G36*
G01X34126D02*
G02Y234181I0J1000D01*
G01X37126D01*
G02Y232181I0J-1000D01*
G01X34126D01*
G37*
G36*
G01X-13118Y341315D02*
G02Y343315I0J1000D01*
G01X-10118D01*
G02Y341315I0J-1000D01*
G01X-13118D01*
G37*
G36*
G01X-5244D02*
G02Y343315I0J1000D01*
G01X-2244D01*
G02Y341315I0J-1000D01*
G01X-5244D01*
G37*
G36*
G01X2630D02*
G02Y343315I0J1000D01*
G01X5630D01*
G02Y341315I0J-1000D01*
G01X2630D01*
G37*
G36*
G01X18378D02*
G02Y343315I0J1000D01*
G01X21378D01*
G02Y341315I0J-1000D01*
G01X18378D01*
G37*
G36*
G01X26252D02*
G02Y343315I0J1000D01*
G01X29252D01*
G02Y341315I0J-1000D01*
G01X26252D01*
G37*
G36*
G01X34126D02*
G02Y343315I0J1000D01*
G01X37126D01*
G02Y341315I0J-1000D01*
G01X34126D01*
G37*
G36*
G01X17781Y416621D02*
G02Y418621I0J1000D01*
G01X22781D01*
G02Y416621I0J-1000D01*
G01X17781D01*
G37*
G36*
G01X28805D02*
G02Y418621I0J1000D01*
G01X33805D01*
G02Y416621I0J-1000D01*
G01X28805D01*
G37*
G36*
G01X-4267D02*
G02Y418621I0J1000D01*
G01X733D01*
G02Y416621I0J-1000D01*
G01X-4267D01*
G37*
G36*
G01X6757D02*
G02Y418621I0J1000D01*
G01X11757D01*
G02Y416621I0J-1000D01*
G01X6757D01*
G37*
G54D10*
X24591Y479139D03*
X1358500Y338400D03*
X1370200D03*
X1364300Y338300D03*
X1370300Y350200D03*
X1358300Y344200D03*
X1358400Y350100D03*
X1370200Y343900D03*
X1364100Y350200D03*
X1812452Y538501D03*
Y533601D03*
X1807852D03*
X1807752Y538501D03*
X1808152Y591601D03*
X1812852Y596401D03*
X1808252D03*
X1812852Y591601D03*
X1875100Y51300D03*
G54D20*
G01X810270Y138290D02*
X809610D01*
G01X809710Y138380D02*
X810370D01*
G01X810460Y138490D02*
X809810D01*
G01X809910Y138580D02*
X810560D01*
G01X810660Y138690D02*
X810000D01*
G01X810100Y138790D02*
X810750D01*
G01X810850Y138880D02*
X810200D01*
G01X810290Y138990D02*
X810950D01*
G01X811040Y139080D02*
X810390D01*
G01X810480Y139190D02*
X811140D01*
G01X811240Y139290D02*
X810580D01*
G01X810680Y139380D02*
X811330D01*
G01X811430Y139490D02*
X810785D01*
G01X810780D02*
X810830D01*
G01X810870Y139580D02*
X810910D01*
G01X810870D02*
X811520D01*
G01X811620Y139690D02*
X810970D01*
G01X811070Y139790D02*
X811720D01*
G01X811820Y139880D02*
X811160D01*
G01X811260Y139990D02*
X811910D01*
G01X812010Y140080D02*
X811350D01*
G01X811450Y140190D02*
X812110D01*
G01X812200Y140290D02*
X811550D01*
G01X811650Y140380D02*
X812300D01*
G01X812390Y140490D02*
X811740D01*
G01X811840Y140580D02*
X812490D01*
G01X812590Y140690D02*
X811930D01*
G01X812030Y140790D02*
X812690D01*
G01X812780Y140880D02*
X812130D01*
G01X812220Y140990D02*
X812880D01*
G01X813070Y141190D02*
X812420D01*
G01X812610Y141380D02*
X813260D01*
G01X807970Y155800D02*
X808000Y155820D01*
G01X807970Y155260D02*
Y155800D01*
G01X807980Y155240D02*
X807970Y155260D01*
G01X808030Y155130D02*
X807980Y155240D01*
G01X808040Y155120D02*
X808030Y155130D01*
G01X813220Y149530D02*
X808040Y155120D01*
G01X807970Y155790D02*
X808030D01*
G01X807970Y155690D02*
X808120D01*
G01X808210Y155580D02*
X807970D01*
G01Y155490D02*
X808310D01*
G01X808400Y155380D02*
X807970D01*
G01Y155290D02*
X808490D01*
G01X808590Y155190D02*
X808000D01*
G01X808070Y155080D02*
X808680D01*
G01X808770Y154990D02*
X808160D01*
G01X808250Y154880D02*
X808860D01*
G01X808960Y154790D02*
X808350D01*
G01X808440Y154690D02*
X809050D01*
G01X809140Y154580D02*
X808530D01*
G01X808620Y154490D02*
X809240D01*
G01X809330Y154380D02*
X808720D01*
G01X808810Y154290D02*
X809420D01*
G01X809520Y154190D02*
X808900D01*
G01X809000Y154080D02*
X809610D01*
G01X809700Y153990D02*
X809090D01*
G01X809180Y153880D02*
X809800D01*
G01X809890Y153790D02*
X809280D01*
G01X809370Y153690D02*
X809980D01*
G01X810080Y153580D02*
X809460D01*
G01X809550Y153490D02*
X810170D01*
G01X810260Y153380D02*
X809650D01*
G01X809740Y153290D02*
X810350D01*
G01X810450Y153190D02*
X809830D01*
G01X809930Y153080D02*
X810540D01*
G01X810630Y152990D02*
X810020D01*
G01X810110Y152880D02*
X810720D01*
G01X810820Y152790D02*
X810210D01*
G01X810300Y152690D02*
X810910D01*
G01X811000Y152580D02*
X810390D01*
G01X810480Y152490D02*
X811100D01*
G01X811190Y152380D02*
X810580D01*
G01X810670Y152290D02*
X811280D01*
G01X811380Y152190D02*
X810760D01*
G01X810850Y152080D02*
X811470D01*
G01X811560Y151990D02*
X810950D01*
G01X811040Y151880D02*
X811660D01*
G01X811750Y151790D02*
X811130D01*
G01X811220Y151690D02*
X811840D01*
G01X811940Y151580D02*
X811320D01*
G01X811410Y151490D02*
X812030D01*
G01X812120Y151380D02*
X811500D01*
G01X811590Y151290D02*
X812220D01*
G01X812310Y151190D02*
X811690D01*
G01X811780Y151080D02*
X812400D01*
G01X812490Y150990D02*
X811870D01*
G01X811970Y150880D02*
X812590D01*
G01X812680Y150790D02*
X812060D01*
G01X812150Y150690D02*
X812770D01*
G01X812870Y150580D02*
X812250D01*
G01X812430Y150380D02*
X813670D01*
G01X813680Y150190D02*
X812620D01*
G01X812370Y152480D02*
X812880D01*
G01X812330Y152440D02*
X812370Y152480D01*
G01X812330Y151980D02*
Y152440D01*
G01X812370Y151940D02*
X812330Y151980D01*
G01Y152380D02*
X822580D01*
G01X822510Y152190D02*
X812330D01*
G01Y151990D02*
X822350D01*
G01X814980Y153290D02*
X813550D01*
G01X812970Y152550D02*
X812880Y152480D01*
G01X812990Y152600D02*
X812970Y152550D01*
G01X812990Y152610D02*
Y152600D01*
G01X813110Y152860D02*
X812990Y152610D01*
G01X813130Y152870D02*
X813110Y152860D01*
G01X813560Y153290D02*
X813130Y152870D01*
G01X812890Y152490D02*
X813620D01*
G01X813730Y152820D02*
X813840Y152890D01*
G01X813560Y152650D02*
X813730Y152820D01*
G01X813540Y152540D02*
X813560Y152650D01*
G01X813630Y152480D02*
X813540Y152540D01*
G01X813700Y152790D02*
X813080D01*
G01X813030Y152690D02*
X813600D01*
G01X813550Y152580D02*
X812980D01*
G01X813240Y152990D02*
X814920D01*
G01Y153190D02*
X813450D01*
G01X813800Y149590D02*
X817030Y146110D01*
G01X813790Y149590D02*
X813800D01*
G01X813750Y149640D02*
X813790Y149590D01*
G01X813720Y149700D02*
X813750Y149640D01*
G01X813540Y151830D02*
X813720Y149700D01*
G01X813640Y151940D02*
X813540Y151830D01*
G01X814060Y145790D02*
X813590D01*
G01X813580Y145990D02*
X814040D01*
G01X814020Y146190D02*
X813560D01*
G01X813540Y146380D02*
X814010D01*
G01X813990Y146580D02*
X813520D01*
G01X813500Y146790D02*
X813970D01*
G01X813960Y146990D02*
X813490D01*
G01X813470Y147190D02*
X813940D01*
G01X813920Y147380D02*
X813450D01*
G01X813440Y147580D02*
X813910D01*
G01X813890Y147790D02*
X813420D01*
G01X813400Y147990D02*
X813870D01*
G01X813850Y148190D02*
X813390D01*
G01X813370Y148380D02*
X813840D01*
G01X813820Y148580D02*
X813350D01*
G01X813340Y148690D02*
X813850D01*
G01X814350Y148990D02*
X813320D01*
G01X813300Y149190D02*
X814170D01*
G01X813240Y149500D02*
X813220Y149530D01*
G01X813280Y149400D02*
X813240Y149500D01*
G01X813280Y149390D02*
Y149400D01*
G01Y149380D02*
Y149390D01*
G01X813980Y149380D02*
X813280D01*
G01X813180Y149580D02*
X813800D01*
G01X813730Y149690D02*
X813080D01*
G01X812990Y149790D02*
X813720D01*
G01X813710Y149880D02*
X812900D01*
G01X812800Y149990D02*
X813700D01*
G01X813690Y150080D02*
X812710D01*
G01X812520Y150290D02*
X813670D01*
G01X813660Y150490D02*
X813180D01*
G01X812970Y151940D02*
X812370D01*
G01X813070Y151850D02*
X812970Y151940D01*
G01X813190Y150500D02*
X813070Y151850D01*
G01X813030Y151880D02*
X813590D01*
G01X813540Y151790D02*
X813080D01*
G01X813090Y151690D02*
X813560D01*
G01Y151580D02*
X813090D01*
G01X813100Y151490D02*
X813570D01*
G01X813580Y151380D02*
X813110D01*
G01X813120Y151290D02*
X813590D01*
G01X813600Y151190D02*
X813130D01*
G01X813140Y151080D02*
X813610D01*
G01Y150990D02*
X813150D01*
G01Y150880D02*
X813620D01*
G01X813630Y150790D02*
X813170D01*
G01Y150690D02*
X813640D01*
G01X813650Y150580D02*
X813180D01*
G01X813020Y150430D02*
X808000Y155820D01*
G01X813130Y150400D02*
X813020Y150430D01*
G01X813190Y150500D02*
X813130Y150400D01*
G01X812340Y150490D02*
X812960D01*
G01X813280Y149380D02*
X813720Y144230D01*
G01X813730Y144190D02*
X814200D01*
G01X814210Y143990D02*
X813740D01*
G01X813760Y143790D02*
X814230D01*
G01X814250Y143580D02*
X813780D01*
G01X813800Y143380D02*
X814270D01*
G01X814310Y143290D02*
X813810D01*
G01X813820Y142640D02*
X813720Y142530D01*
G01X813850Y142710D02*
X813820Y142640D01*
G01X813670Y142490D02*
X814360D01*
G01Y142290D02*
X813480D01*
G01X813290Y142080D02*
X814380D01*
G01X813740Y141880D02*
X813090D01*
G01X813000Y141790D02*
X813650D01*
G01X813550Y141690D02*
X812900D01*
G01X812800Y141580D02*
X813460D01*
G01X813360Y141490D02*
X812710D01*
G01X812520Y141290D02*
X813170D01*
G01X812970Y141080D02*
X812320D01*
G01X813700Y144490D02*
X814170D01*
G01X814150Y144690D02*
X813690D01*
G01X813670Y144880D02*
X814140D01*
G01X814120Y145080D02*
X813650D01*
G01X813630Y145290D02*
X814100D01*
G01X814090Y145490D02*
X813620D01*
G01X813610Y145580D02*
X814080D01*
G01X814070Y145690D02*
X813600D01*
G01X813580Y145880D02*
X814050D01*
G01X814040Y146080D02*
X813570D01*
G01X813550Y146290D02*
X814020D01*
G01X814000Y146490D02*
X813530D01*
G01X813520Y146690D02*
X813980D01*
G01X813960Y146880D02*
X813500D01*
G01X813480Y147080D02*
X813950D01*
G01X813930Y147290D02*
X813460D01*
G01X813450Y147490D02*
X813910D01*
G01X813900Y147690D02*
X813430D01*
G01X813410Y147880D02*
X813880D01*
G01X813860Y148080D02*
X813390D01*
G01X813380Y148290D02*
X813840D01*
G01X813830Y148490D02*
X813360D01*
G01X813990Y148710D02*
X816720Y145770D01*
G01X813870Y148730D02*
X813990Y148710D01*
G01X813820Y148630D02*
X813870Y148730D01*
G01X814090Y145380D02*
X813630D01*
G01X813640Y145190D02*
X814110D01*
G01X814130Y144990D02*
X813660D01*
G01X813680Y144790D02*
X814150D01*
G01X814160Y144580D02*
X813690D01*
G01X813710Y144380D02*
X814180D01*
G01X814190Y144290D02*
X813720D01*
G01X813850Y142770D02*
Y142710D01*
G01X813720Y144230D02*
X813850Y142770D01*
G01X813840Y142690D02*
X814520D01*
G01X814370Y142510D02*
X814350Y142440D01*
G01X814420Y142590D02*
X814370Y142510D01*
G01X814350Y142380D02*
X813580D01*
G01X813390Y142190D02*
X814370D01*
G01X814390Y141880D02*
X813890D01*
G01X813860Y141920D02*
X813760Y141900D01*
G01X814130Y139480D02*
X814240D01*
G01X814130Y139490D02*
Y139480D01*
G01X813930Y141840D02*
X814130Y139490D01*
G01X813860Y141920D02*
X813930Y141840D01*
G01X814230Y139580D02*
X814120D01*
G01X814125D02*
X819720D01*
G01X819785Y139490D02*
X814130D01*
G01X814370Y138440D02*
X815260D01*
G01X814330Y138480D02*
X814370Y138440D01*
G01X814330Y139160D02*
Y138480D01*
G01X814300Y139230D02*
X814330Y139160D01*
G01X814150Y139390D02*
X814300Y139230D01*
G01X814140Y139410D02*
X814150Y139390D01*
G01X814130Y139470D02*
X814140Y139410D01*
G01X815300Y138490D02*
X814330D01*
G01Y138690D02*
X815300D01*
G01Y138880D02*
X814330D01*
G01Y139080D02*
X815300D01*
G01X814580Y139790D02*
X814110D01*
G01X814090Y139880D02*
X814560D01*
G01X814550Y140080D02*
X814080D01*
G01X814060Y140290D02*
X814530D01*
G01X814510Y140490D02*
X814040D01*
G01X814030Y140690D02*
X814500D01*
G01X814480Y140880D02*
X814010D01*
G01X813990Y141080D02*
X814460D01*
G01X814450Y141290D02*
X813980D01*
G01X813960Y141490D02*
X814430D01*
G01X814410Y141690D02*
X813950D01*
G01X813840Y142880D02*
X814710D01*
G01X814900Y143080D02*
X813820D01*
G01X813790Y143490D02*
X814260D01*
G01X814270Y143340D02*
X813820Y148630D01*
G01X814010Y148690D02*
X814630D01*
G01X814820Y148490D02*
X814200D01*
G01X814380Y148290D02*
X815000D01*
G01X814260Y149080D02*
X813310D01*
G01X813290Y149290D02*
X814080D01*
G01X813890Y149490D02*
X813250D01*
G01X813950Y152900D02*
X813840Y152890D01*
G01X814000Y152810D02*
X813950Y152900D01*
G01X814000Y152580D02*
Y152810D01*
G01X813900Y152480D02*
X814000Y152580D01*
G01X813630Y152480D02*
X813900D01*
G01X813830Y152880D02*
X813140D01*
G01X814010Y153870D02*
X814040Y153890D01*
G01X814000Y153840D02*
X814010Y153870D01*
G01X814000Y153640D02*
Y153840D01*
G01X813990Y153600D02*
X814000Y153640D01*
G01X813970Y153550D02*
X813990Y153600D01*
G01X813920Y153490D02*
X813970Y153550D01*
G01X813830Y153450D02*
X813920Y153490D01*
G01X813560Y153290D02*
X813830Y153450D01*
G01X814040Y153880D02*
X814870D01*
G01X814000Y153690D02*
X816890D01*
G01X816880Y153490D02*
X813900D01*
G01X813950Y152880D02*
X814920D01*
G01Y152690D02*
X814000D01*
G01X813910Y152490D02*
X815020D01*
G01X814210Y144080D02*
X813740D01*
G01X813750Y143880D02*
X814220D01*
G01X814240Y143690D02*
X813770D01*
G01X814340Y143250D02*
X814440Y143280D01*
G01X814270Y143340D02*
X814340Y143250D01*
G01X814250Y139290D02*
X820030D01*
G01X814570Y139860D02*
X814350Y142440D01*
G01X814570Y139790D02*
Y139860D01*
G01X814670Y139700D02*
X814570Y139790D01*
G01X818770Y139700D02*
X814670D01*
G01X814420Y142580D02*
X813770D01*
G01X813850Y142790D02*
X814610D01*
G01X814430Y142590D02*
X814420D01*
G01X814430Y142600D02*
Y142590D01*
G01Y142600D02*
X817020Y145290D01*
G01X816830Y145080D02*
X816190D01*
G01X815990Y144880D02*
X816640D01*
G01X816450Y144690D02*
X815800D01*
G01X815610Y144490D02*
X816250D01*
G01X816160Y144380D02*
X815510D01*
G01X815560Y144440D02*
X814440Y143280D01*
G01X814450Y143290D02*
X815090D01*
G01X815000Y143190D02*
X813820D01*
G01X813830Y142990D02*
X814810D01*
G01X814550Y143380D02*
X815190D01*
G01X815290Y143490D02*
X814650D01*
G01X814740Y143580D02*
X815390D01*
G01X815480Y143690D02*
X814840D01*
G01X814930Y143790D02*
X815580D01*
G01X815670Y143880D02*
X815030D01*
G01X815130Y143990D02*
X815770D01*
G01X815870Y144080D02*
X815220D01*
G01X815320Y144190D02*
X815960D01*
G01X816060Y144290D02*
X815410D01*
G01X816240Y146290D02*
X816870D01*
G01X816680Y146490D02*
X816060D01*
G01X815870Y146690D02*
X816490D01*
G01X816310Y146880D02*
X815680D01*
G01X815590Y146990D02*
X816210D01*
G01X816120Y147080D02*
X815500D01*
G01X815410Y147190D02*
X816030D01*
G01X815930Y147290D02*
X815310D01*
G01X815220Y147380D02*
X815840D01*
G01X815750Y147490D02*
X815130D01*
G01X815030Y147580D02*
X815660D01*
G01X815560Y147690D02*
X814940D01*
G01X814850Y147790D02*
X815470D01*
G01X815380Y147880D02*
X814750D01*
G01X814660Y147990D02*
X815280D01*
G01X815190Y148080D02*
X814570D01*
G01X814480Y148190D02*
X815100D01*
G01X814910Y148380D02*
X814290D01*
G01X814100Y148580D02*
X814720D01*
G01X814540Y148790D02*
X813340D01*
G01X813330Y148880D02*
X814450D01*
G01X816300Y148160D02*
X816340Y148120D01*
G01X814920Y152580D02*
X814000D01*
G01X815020Y152480D02*
X814920Y152580D01*
G01X814000Y152790D02*
X814920D01*
G01X816250Y153490D02*
X816360Y153380D01*
G01X815980Y153460D02*
X816250Y153490D01*
G01X815700Y153430D02*
X815980Y153460D01*
G01X815580Y153420D02*
X815700Y153430D01*
G01X815480Y153400D02*
X815580Y153420D01*
G01X815230Y153360D02*
X815480Y153400D01*
G01X815220Y153360D02*
X815230D01*
G01X815130Y153340D02*
X815220Y153360D01*
G01X815120Y153340D02*
X815130D01*
G01X815000Y153320D02*
X815120Y153340D01*
G01X814920Y153220D02*
X815000Y153320D01*
G01X814920Y152580D02*
Y153220D01*
G01X814860Y153890D02*
X814040D01*
G01X814880Y153880D02*
X814860Y153890D01*
G01X814910Y153870D02*
X814880Y153880D01*
G01X814940Y153850D02*
X814910Y153870D01*
G01X815020Y153830D02*
X814940Y153850D01*
G01X815040Y153840D02*
X815020Y153830D01*
G01X815280Y153880D02*
X815040Y153840D01*
G01X815780Y153950D02*
X815280Y153880D01*
G01X815900Y153960D02*
X815780Y153950D01*
G01X815960Y153960D02*
X815900D01*
G01X816120Y153980D02*
X815960Y153960D01*
G01X816260Y153990D02*
X816120Y153980D01*
G01X813720Y153380D02*
X815370D01*
G01X814920Y153080D02*
X813350D01*
G01X815020Y152480D02*
X820860D01*
G01X818930Y153990D02*
X816240D01*
G01X816260D02*
X816360Y154090D01*
G01X814390Y141990D02*
X813190D01*
G01X813930Y141790D02*
X814400D01*
G01X814420Y141580D02*
X813950D01*
G01X813970Y141380D02*
X814440D01*
G01X814450Y141190D02*
X813980D01*
G01X814000Y140990D02*
X814470D01*
G01X814490Y140790D02*
X814020D01*
G01X814040Y140580D02*
X814500D01*
G01X814520Y140380D02*
X814060D01*
G01X814070Y140190D02*
X814540D01*
G01X814560Y139990D02*
X814090D01*
G01X814320Y139190D02*
X815370D01*
G01X815300Y138480D02*
X815260Y138440D01*
G01X815300Y139120D02*
Y138480D01*
G01X815400Y139220D02*
X815300Y139120D01*
G01Y138580D02*
X814330D01*
G01Y138790D02*
X815300D01*
G01Y138990D02*
X814330D01*
G01X818870Y140170D02*
Y140180D01*
G01X818860Y140100D02*
X818870Y140170D01*
G01X818860Y139840D02*
Y140100D01*
G01X818870Y139820D02*
X818860Y139840D01*
G01X818770Y139700D02*
X818870Y139820D01*
G01Y140190D02*
X819640D01*
G01X819600Y139990D02*
X818860D01*
G01X818840Y139790D02*
X819640D01*
G01X817480Y145620D02*
Y145760D01*
G01X820180Y142720D02*
X817480Y145620D01*
G01X817500Y145790D02*
X816710D01*
G01X816720Y145630D02*
X815560Y144440D01*
G01X816720Y145770D02*
Y145630D01*
G01X815710Y144580D02*
X816350D01*
G01X816540Y144790D02*
X815900D01*
G01X816090Y144990D02*
X816740D01*
G01X816930Y145190D02*
X816280D01*
G01X817170Y145290D02*
X818850Y143470D01*
G01X817020Y145290D02*
X817170D01*
G01X816380D02*
X817020D01*
G01X818840Y143490D02*
X819470D01*
G01X819280Y143690D02*
X818650D01*
G01X818470Y143880D02*
X819100D01*
G01X818910Y144080D02*
X818280D01*
G01X818190Y144190D02*
X818820D01*
G01X818720Y144290D02*
X818090D01*
G01X818000Y144380D02*
X818630D01*
G01X818540Y144490D02*
X817910D01*
G01X817820Y144580D02*
X818450D01*
G01X818350Y144690D02*
X817720D01*
G01X817630Y144790D02*
X818260D01*
G01X818170Y144880D02*
X817540D01*
G01X817450Y144990D02*
X818080D01*
G01X817980Y145080D02*
X817350D01*
G01X817260Y145190D02*
X817890D01*
G01X817800Y145290D02*
X817150D01*
G01X817520Y145580D02*
X816670D01*
G01X816720Y145690D02*
X817480D01*
G01X817600Y145880D02*
X816610D01*
G01X816520Y145990D02*
X817700D01*
G01X817800Y146080D02*
X816430D01*
G01X816340Y146190D02*
X816960D01*
G01X817170Y146110D02*
X818600Y147580D01*
G01X817030Y146110D02*
X817170D01*
G01X818500Y147490D02*
X819140D01*
G01X818950Y147290D02*
X818310D01*
G01X818220Y147190D02*
X818850D01*
G01X818760Y147080D02*
X818120D01*
G01X818020Y146990D02*
X818660D01*
G01X818570Y146880D02*
X817930D01*
G01X817830Y146790D02*
X818470D01*
G01X818370Y146690D02*
X817730D01*
G01X817640Y146580D02*
X818280D01*
G01X818180Y146490D02*
X817540D01*
G01X817450Y146380D02*
X818080D01*
G01X817990Y146290D02*
X817350D01*
G01X817250Y146190D02*
X817890D01*
G01X817610Y145490D02*
X816580D01*
G01X816480Y145380D02*
X817700D01*
G01X816770Y146380D02*
X816150D01*
G01X815960Y146580D02*
X816590D01*
G01X816400Y146790D02*
X815780D01*
G01X816390Y148120D02*
X818880D01*
G01X816340D02*
X816390D01*
G01X818890Y147880D02*
X819530D01*
G01X819340Y147690D02*
X818700D01*
G01X819820Y148190D02*
X816300D01*
G01X816340Y149150D02*
X816390D01*
G01X816300Y149110D02*
X816340Y149150D01*
G01X816300Y148160D02*
Y149110D01*
G01Y148990D02*
X819560D01*
G01X819590Y148790D02*
X816300D01*
G01Y148580D02*
X820210D01*
G01X820010Y148380D02*
X816300D01*
G01X816360Y153040D02*
Y153380D01*
G01X816400Y152990D02*
X816360Y153040D01*
G01X816350Y153380D02*
X818980D01*
G01X818850Y152990D02*
X816400D01*
G01X818900Y153040D02*
X818850Y152990D01*
G01X818900Y153320D02*
Y153040D01*
G01X816360Y153080D02*
X818900D01*
G01Y153190D02*
X816360D01*
G01Y153290D02*
X818900D01*
G01X818450Y153600D02*
Y153560D01*
G01X818350Y153700D02*
X818450Y153600D01*
G01X816910Y153700D02*
X818350D01*
G01X816810Y153600D02*
X816910Y153700D01*
G01X816810Y153560D02*
Y153600D01*
G01X816910Y153450D02*
X816810Y153560D01*
G01X818350Y153450D02*
X816910D01*
G01X818450Y153560D02*
X818350Y153450D01*
G01X818450Y153580D02*
X820420D01*
G01X820130Y153690D02*
X818360D01*
G01X816360Y154120D02*
Y154090D01*
G01X816400Y154160D02*
X816360Y154120D01*
G01X818850Y154160D02*
X816400D01*
G01X818900Y154120D02*
X818850Y154160D01*
G01X818900Y154020D02*
Y154120D01*
G01X816350Y154080D02*
X818900D01*
G01X816810Y153580D02*
X813980D01*
G01X814000Y153790D02*
X819760D01*
G01X818980Y153920D02*
X818900Y154020D01*
G01X819030Y153920D02*
X818980D01*
G01X819590Y153830D02*
X819030Y153920D01*
G01X819770Y153790D02*
X819590Y153830D01*
G01X819210Y153880D02*
X815340D01*
G01X819410Y153350D02*
X819820Y153260D01*
G01X819120Y153400D02*
X819410Y153350D01*
G01X819090Y153400D02*
X819120D01*
G01X819010Y153420D02*
X819090Y153400D01*
G01X818900Y153320D02*
X819010Y153420D01*
G01X819200Y153380D02*
X820790D01*
G01X819510Y149150D02*
X816390D01*
G01X816300Y149080D02*
X819560D01*
G01X819550Y149110D02*
X819510Y149150D01*
G01X819730Y148760D02*
X819930Y148960D01*
G01X819620Y148730D02*
X819730Y148760D01*
G01X819560Y148830D02*
X819620Y148730D01*
G01X819560Y149010D02*
Y148830D01*
G01Y149020D02*
Y149010D01*
G01X819550Y149110D02*
X819560Y149020D01*
G01X819760Y148790D02*
X820400D01*
G01X819560Y148880D02*
X816300D01*
G01X818410Y147380D02*
X819050D01*
G01X818970Y148060D02*
X818880Y148120D01*
G01X818950Y147950D02*
X818970Y148060D01*
G01X818600Y147580D02*
X818950Y147950D01*
G01X819240Y147580D02*
X818600D01*
G01X818930Y148080D02*
X819720D01*
G01X819630Y147990D02*
X818960D01*
G01X818800Y147790D02*
X819430D01*
G01X819000Y143990D02*
X818370D01*
G01X818560Y143790D02*
X819190D01*
G01X819370Y143580D02*
X818740D01*
G01X818930Y143380D02*
X819560D01*
G01X819650Y143290D02*
X819020D01*
G01X819110Y143190D02*
X819750D01*
G01X819840Y143080D02*
X819210D01*
G01X819300Y142990D02*
X819930D01*
G01X820120Y142790D02*
X819490D01*
G01X819670Y142580D02*
X820810D01*
G01X820800Y142490D02*
X819770D01*
G01X818910Y140360D02*
X818870Y140180D01*
G01X818910Y140370D02*
Y140360D01*
G01X819020Y140680D02*
X818910Y140370D01*
G01X819030Y140690D02*
X819020Y140680D01*
G01X819240Y141000D02*
X819030Y140690D01*
G01X819250Y141010D02*
X819240Y141000D01*
G01X819490Y141230D02*
X819250Y141010D01*
G01X819500Y141230D02*
X819490D01*
G01X819620Y141310D02*
X819500Y141230D01*
G01X819630Y141320D02*
X819620Y141310D01*
G01X819690Y141350D02*
X819630Y141320D01*
G01X819850Y141420D02*
X819690Y141350D01*
G01X818860Y140080D02*
X819620D01*
G01X819660Y139690D02*
X814110D01*
G01X819650Y139710D02*
X819660Y139690D01*
G01X819600Y139970D02*
X819650Y139710D01*
G01X819600Y139980D02*
Y139970D01*
G01Y140000D02*
Y139980D01*
G01X814150Y139380D02*
X819890D01*
G01X819810Y139450D02*
X819750Y139540D01*
G01X819820Y139440D02*
X819810Y139450D01*
G01X819830Y139430D02*
X819820Y139440D01*
G01X819670Y139680D02*
X819660Y139690D01*
G01X819750Y139550D02*
X819670Y139680D01*
G01X819620Y139880D02*
X818860D01*
G01X818890Y140290D02*
X819660D01*
G01X819650Y140260D02*
X819600Y140000D01*
G01X819660Y140280D02*
X819650Y140260D01*
G01X819880Y140010D02*
X819890Y140030D01*
G01X819830Y140540D02*
X820050Y140700D01*
G01X819820Y140530D02*
X819830Y140540D01*
G01X819810Y140510D02*
X819820Y140530D01*
G01X819670Y140300D02*
X819810Y140510D01*
G01X819660Y140280D02*
X819670Y140300D01*
G01X819890Y140580D02*
X818990D01*
G01X818950Y140490D02*
X819790D01*
G01X819720Y140380D02*
X818910D01*
G01X819090Y140790D02*
X820350D01*
G01X819760Y141380D02*
X821430D01*
G01X821520Y141290D02*
X819580D01*
G01X819340Y141080D02*
X821710D01*
G01X821890Y140880D02*
X819170D01*
G01X819750Y139490D02*
X819790D01*
G01X819830Y139430D02*
X820050Y139270D01*
G01X819620Y138690D02*
X821170D01*
G01X821330Y138790D02*
X819440D01*
G01X819000Y139220D02*
X815400D01*
G01X819080Y139190D02*
X819000Y139220D01*
G01X819090Y139180D02*
X819080Y139190D01*
G01X819090Y139170D02*
Y139180D01*
G01X819130Y139100D02*
X819090Y139170D01*
G01X819140Y139100D02*
X819130D01*
G01X819150Y139090D02*
X819140Y139100D01*
G01X819220Y138990D02*
X819150Y139090D01*
G01X819230Y138980D02*
X819220Y138990D01*
G01X819460Y138760D02*
X819230Y138980D01*
G01Y138990D02*
X821570D01*
G01X819480Y138750D02*
X819460Y138760D01*
G01X820280Y138450D02*
X820620Y138460D01*
G01X820270Y138450D02*
X820280D01*
G01X820260D02*
X820270D01*
G01X820100Y138470D02*
X820260Y138450D01*
G01X820080Y138470D02*
X820100D01*
G01X819480Y138750D02*
X820080Y138470D01*
G01X820730Y138490D02*
X820060D01*
G01Y139260D02*
X820050Y139270D01*
G01X820080Y139260D02*
X820060D01*
G01X820250Y139200D02*
X820080Y139260D01*
G01X820470Y139190D02*
X820490D01*
G01X820340D02*
X820470D01*
G01X820270Y139200D02*
X820340Y139190D01*
G01X820250Y139200D02*
X820270D01*
G01X819910Y139820D02*
X819880Y140010D01*
G01X819920Y139790D02*
X819910Y139820D01*
G01X820090Y139570D02*
X819920Y139790D01*
G01X820110Y139560D02*
X820090Y139570D01*
G01X820280Y139480D02*
X820110Y139560D01*
G01X820290Y139480D02*
X820280D01*
G01X820330Y139470D02*
X820290Y139480D01*
G01X820390Y139470D02*
X820330D01*
G01X820410D02*
X820390D01*
G01X820440Y140500D02*
X820450D01*
G01X820350D02*
X820440D01*
G01X820330Y140490D02*
X820350Y140500D01*
G01X820020Y140330D02*
X820330Y140490D01*
G01X820000Y140310D02*
X820020Y140330D01*
G01X819890Y140030D02*
X820000Y140310D01*
G01X820060Y140710D02*
X820050Y140700D01*
G01X820080Y140710D02*
X820060D01*
G01X820250Y140770D02*
X820080Y140710D01*
G01X820270Y140770D02*
X820250D01*
G01X820340Y140780D02*
X820270Y140770D01*
G01X820360Y140790D02*
X820340Y140780D01*
G01X820420Y140790D02*
X820360D01*
G01X820450Y140780D02*
X820420Y140790D01*
G01X820030Y140690D02*
X819030D01*
G01X819940Y140170D02*
X820880D01*
G01X820900Y139970D02*
X819890D01*
G01X819940Y139770D02*
X820850D01*
G01X820670Y139570D02*
X820100D01*
G01X820410Y139470D02*
X820540Y139490D01*
G01X820740Y140360D02*
X820090D01*
G01X820490Y140780D02*
X820690Y140730D01*
G01X820450Y140780D02*
X820490D01*
G01X819940Y141450D02*
X819850Y141420D01*
G01X819950Y141460D02*
X819940Y141450D01*
G01X820090Y141490D02*
X819950Y141460D01*
G01X820170Y141510D02*
X820090Y141490D01*
G01X819950Y142290D02*
X818850Y143470D01*
G01X820210Y142010D02*
X819950Y142290D01*
G01X820240Y141960D02*
X820210Y142010D01*
G01X820270Y141810D02*
X820240Y141960D01*
G01X820280Y141790D02*
X820270Y141810D01*
G01X820280Y141770D02*
Y141790D01*
G01X820260Y141600D02*
X820280Y141770D01*
G01X820260Y141590D02*
Y141600D01*
G01X820170Y141510D02*
X820260Y141590D01*
G01X819390Y142880D02*
X820030D01*
G01X820350Y142780D02*
X820860Y149010D01*
G01X820290Y142700D02*
X820350Y142780D01*
G01X820180Y142720D02*
X820290Y142700D01*
G01X819950Y148990D02*
X819930Y148960D01*
G01X820590Y148990D02*
X819950D01*
G01D02*
X820760Y149830D01*
G01X820340Y149380D02*
X822600D01*
G01Y149190D02*
X820150D01*
G01X819850Y148880D02*
X820490D01*
G01X820300Y148690D02*
X816300D01*
G01Y148490D02*
X820110D01*
G01X819910Y148290D02*
X816300D01*
G01X820520Y144790D02*
X820980D01*
G01X820970Y144580D02*
X820500D01*
G01X820480Y144380D02*
X820950D01*
G01X820940Y144190D02*
X820470D01*
G01X820450Y143990D02*
X820920D01*
G01X820910Y143790D02*
X820440D01*
G01X820420Y143580D02*
X820890D01*
G01X820870Y143380D02*
X820410D01*
G01X820390Y143190D02*
X820850D01*
G01X820840Y142990D02*
X820370D01*
G01X820350Y142790D02*
X820820D01*
G01X820780Y142290D02*
X819950D01*
G01X820140Y142080D02*
X820780D01*
G01X820960Y141880D02*
X820260D01*
G01X820270Y141690D02*
X821150D01*
G01X820100Y153180D02*
X819820Y153260D01*
G01X820110Y153170D02*
X820100Y153180D01*
G01X820220Y153140D02*
X820110Y153170D01*
G01X820220Y153130D02*
Y153140D01*
G01X820330Y153090D02*
X820220Y153130D01*
G01X820340Y153080D02*
X820330Y153090D01*
G01X821200Y153080D02*
X820340D01*
G01X820060Y153190D02*
X821090D01*
G01X819890Y153750D02*
X819770Y153790D01*
G01X820000Y153730D02*
X819890Y153750D01*
G01X820240Y153650D02*
X820000Y153730D01*
G01X820350Y153610D02*
X820240Y153650D01*
G01X820410Y153590D02*
X820350Y153610D01*
G01X819700Y153290D02*
X820950D01*
G01X820630Y153490D02*
X818380D01*
G01X820950Y152530D02*
X820860Y152480D01*
G01X820940Y152630D02*
X820950Y152530D01*
G01X820870Y152740D02*
X820940Y152630D01*
G01X820850Y152760D02*
X820870Y152740D01*
G01X820550Y152980D02*
X820850Y152760D01*
G01X820540Y152990D02*
X820550Y152980D01*
G01X820530Y152990D02*
X820540D01*
G01X820340Y153080D02*
X820530Y152990D01*
G01X820870Y152490D02*
X822590D01*
G01X822570Y152690D02*
X820910D01*
G01X820680Y152880D02*
X822490D01*
G01X822600Y150880D02*
X820820D01*
G01X820790Y149860D02*
X820760Y149830D01*
G01X820820Y149920D02*
X820790Y149860D01*
G01X820820Y150940D02*
Y149920D01*
G01X820720Y149790D02*
X821390D01*
G01X821560Y149990D02*
X820820D01*
G01Y150190D02*
X821750D01*
G01X821940Y150380D02*
X820820D01*
G01Y150490D02*
X822600D01*
G01Y150690D02*
X820820D01*
G01X820930Y151020D02*
X821030Y151120D01*
G01X820860Y151020D02*
X820930D01*
G01X820820Y150980D02*
X820860Y151020D01*
G01X820820Y150940D02*
Y150980D01*
G01X820530Y149580D02*
X822600D01*
G01X821320Y148880D02*
X820850D01*
G01X820690Y149090D02*
X817480Y145760D01*
G01X820800Y149110D02*
X820690Y149090D01*
G01X820860Y149010D02*
X820800Y149110D01*
G01X820580Y145580D02*
X821050D01*
G01X821060Y145690D02*
X820590D01*
G01X820610Y145880D02*
X821080D01*
G01X821090Y146080D02*
X820630D01*
G01X820640Y146290D02*
X821110D01*
G01X821120Y146490D02*
X820660D01*
G01X820670Y146690D02*
X821140D01*
G01X821160Y146880D02*
X820690D01*
G01X820710Y147080D02*
X821170D01*
G01X821190Y147290D02*
X820720D01*
G01X820740Y147490D02*
X821210D01*
G01X821220Y147690D02*
X820760D01*
G01X820770Y147880D02*
X821240D01*
G01X821250Y148080D02*
X820790D01*
G01X820800Y148290D02*
X821270D01*
G01X821290Y148490D02*
X820820D01*
G01X820840Y148690D02*
X821300D01*
G01X820690Y149080D02*
X820050D01*
G01X820570Y145380D02*
X821040D01*
G01X821020Y145190D02*
X820550D01*
G01X820540Y144990D02*
X821000D01*
G01X820990Y144880D02*
X820530D01*
G01X820510Y144690D02*
X820980D01*
G01X820960Y144490D02*
X820490D01*
G01X820480Y144290D02*
X820950D01*
G01X820930Y144080D02*
X820460D01*
G01X820450Y143880D02*
X820910D01*
G01X820900Y143690D02*
X820430D01*
G01X820410Y143490D02*
X820880D01*
G01X820860Y143290D02*
X820400D01*
G01X820380Y143080D02*
X820850D01*
G01X820830Y142880D02*
X820360D01*
G01X820820Y142690D02*
X819580D01*
G01X819860Y142380D02*
X820790D01*
G01X820780Y142190D02*
X820050D01*
G01X820220Y141990D02*
X820860D01*
G01X820800Y142050D02*
X821760Y141030D01*
G01X822080Y140690D02*
X820750D01*
G01X820730Y140710D02*
X820690Y140730D01*
G01X820730Y140710D02*
X821040Y140450D01*
G01X820810Y140270D02*
X819980D01*
G01X819900Y140070D02*
X820890D01*
G01X820700Y140400D02*
X820450Y140500D01*
G01X820720Y140390D02*
X820700Y140400D01*
G01X820870Y140190D02*
X820720Y140390D01*
G01X820880Y140160D02*
X820870Y140190D01*
G01X820540Y140470D02*
X820270D01*
G01X820560Y139490D02*
X820540D01*
G01X820780Y139630D02*
X820560Y139490D01*
G01X820790Y139650D02*
X820780Y139630D01*
G01X820900Y139880D02*
X820790Y139650D01*
G01X820910Y139900D02*
X820900Y139880D01*
G01X820880Y140160D02*
X820910Y139900D01*
G01X820750Y139290D02*
X821770D01*
G01X820630Y138460D02*
X820620D01*
G01X820920Y138530D02*
X820630Y138460D01*
G01X820930Y138540D02*
X820920Y138530D01*
G01X821440Y138850D02*
X820930Y138540D01*
G01X820690Y139240D02*
X820730Y139260D01*
G01X820490Y139190D02*
X820690Y139240D01*
G01X820800Y139670D02*
X820020D01*
G01X819900Y139860D02*
X820900D01*
G01X820790Y142070D02*
X820770Y142140D01*
G01X820800Y142060D02*
X820790Y142070D01*
G01X820800Y142050D02*
Y142060D01*
G01X820560Y153530D02*
X820410Y153590D01*
G01X820570Y153520D02*
X820560Y153530D01*
G01X821820Y153240D02*
X821880Y153250D01*
G01X821810Y153240D02*
X821820D01*
G01X821700Y153210D02*
X821810Y153240D01*
G01X821690Y153210D02*
X821700D01*
G01X821560Y153160D02*
X821690Y153210D01*
G01X821560Y153150D02*
Y153160D01*
G01X821500Y153120D02*
X821560Y153150D01*
G01X821480Y153100D02*
X821500Y153120D01*
G01X821420Y153050D02*
X821480Y153100D01*
G01X821400Y153030D02*
X821420Y153050D01*
G01X821260Y153030D02*
X821400D01*
G01X821080Y153200D02*
X821260Y153030D01*
G01X821070Y153210D02*
X821080Y153200D01*
G01X820570Y153520D02*
X821070Y153210D01*
G01X821630Y153190D02*
X822150D01*
G01X822200Y151880D02*
X821040D01*
G01X821090Y151830D02*
X821030Y151120D01*
G01X821000Y151080D02*
X821550D01*
G01X821840Y151810D02*
X821870Y151800D01*
G01X821760Y151820D02*
X821840Y151810D01*
G01X821690Y151840D02*
X821760Y151820D01*
G01X821680Y151840D02*
X821690D01*
G01X821550Y151750D02*
X821680Y151840D01*
G01X821500Y151140D02*
X821550Y151750D01*
G01X821600Y151030D02*
X821500Y151140D01*
G01X821600Y151790D02*
X821090D01*
G01X820990Y151940D02*
X813640D01*
G01X821090Y151830D02*
X820990Y151940D01*
G01X820630Y149690D02*
X821450D01*
G01X821420Y149840D02*
X821970Y150420D01*
G01X821390Y149790D02*
X821420Y149840D01*
G01X821390Y149750D02*
Y149790D01*
G01X821490Y149640D02*
X821390Y149750D01*
G01X821850Y150290D02*
X820820D01*
G01Y150080D02*
X821650D01*
G01X821460Y149880D02*
X820800D01*
G01X820820Y149080D02*
X821350D01*
G01X821340Y149070D02*
X820770Y142140D01*
G01X821050Y141790D02*
X820280D01*
G01X820250Y141580D02*
X821240D01*
G01X821330Y141490D02*
X820060D01*
G01X819450Y141190D02*
X821610D01*
G01X821800Y140990D02*
X819230D01*
G01X819080Y139190D02*
X821710D01*
G01X821530Y138940D02*
X821440Y138850D01*
G01X821590Y139010D02*
X821530Y138940D01*
G01X821720Y139200D02*
X821590Y139010D01*
G01X821480Y138880D02*
X819330D01*
G01X819150Y139080D02*
X821640D01*
G01X821840Y139450D02*
X821900Y139620D01*
G01X821800Y139350D02*
X821840Y139450D01*
G01X821800Y139340D02*
Y139350D01*
G01X821730Y139210D02*
X821800Y139340D01*
G01X821720Y139200D02*
X821730Y139210D01*
G01X821890Y139580D02*
X821075D01*
G01X821080D02*
X821140D01*
G01X821040Y139520D02*
X820730Y139260D01*
G01X821070Y139570D02*
X821040Y139520D01*
G01X820870Y139380D02*
X821820D01*
G01X821850Y139490D02*
X821060D01*
G01X821820D02*
X821850D01*
G01X821070Y140400D02*
X821040Y140450D01*
G01X821190Y140010D02*
X821070Y140400D01*
G01X821190Y139950D02*
Y140010D01*
G01X821070Y139570D02*
X821190Y139950D01*
G01X821000Y140490D02*
X822260D01*
G01X822450Y140290D02*
X821110D01*
G01X821170Y140080D02*
X822630D01*
G01X821930Y139880D02*
X821170D01*
G01X821110Y139690D02*
X821910D01*
G01X821000Y138580D02*
X819840D01*
G01X820540Y145080D02*
X821010D01*
G01X821030Y145290D02*
X820560D01*
G01X820580Y145490D02*
X821040D01*
G01X821070Y145790D02*
X820600D01*
G01X820610Y145990D02*
X821080D01*
G01X821100Y146190D02*
X820630D01*
G01X820650Y146380D02*
X821110D01*
G01X821130Y146580D02*
X820670D01*
G01X820680Y146790D02*
X821150D01*
G01X821170Y146990D02*
X820700D01*
G01X820710Y147190D02*
X821180D01*
G01X821200Y147380D02*
X820730D01*
G01X820750Y147580D02*
X821210D01*
G01X821230Y147790D02*
X820760D01*
G01X820780Y147990D02*
X821240D01*
G01X821260Y148190D02*
X820800D01*
G01X820810Y148380D02*
X821280D01*
G01X821300Y148580D02*
X820830D01*
G01X820840Y148790D02*
X821310D01*
G01X821330Y148990D02*
X820860D01*
G01X821340Y149070D02*
X821430Y149160D01*
G01X821760Y151020D02*
X821880D01*
G01X821600Y151030D02*
X821760Y151020D01*
G01X821510Y151190D02*
X821040D01*
G01X821050Y151290D02*
X821520D01*
G01Y151380D02*
X821060D01*
G01Y151490D02*
X821530D01*
G01X821540Y151580D02*
X821070D01*
G01X821080Y151690D02*
X821550D01*
G01X821950Y153250D02*
X821880D01*
G01X821960Y153240D02*
X821950Y153250D01*
G01X822220Y153170D02*
X821960Y153240D01*
G01X822230Y153160D02*
X822220Y153170D01*
G01X822430Y152990D02*
X822230Y153160D01*
G01X822440Y152980D02*
X822430Y152990D01*
G01X822560Y152750D02*
X822440Y152980D01*
G01X822570Y152730D02*
X822560Y152750D01*
G01X822590Y152450D02*
X822570Y152730D01*
G01X822590Y152440D02*
Y152450D01*
G01X822510Y152180D02*
X822590Y152440D01*
G01X822500Y152170D02*
X822510Y152180D01*
G01X822340Y151970D02*
X822500Y152170D01*
G01X822330Y151950D02*
X822340Y151970D01*
G01X822100Y151830D02*
X822330Y151950D01*
G01X822080Y151830D02*
X822100D01*
G01X821960Y151810D02*
X822080Y151830D01*
G01X821950Y151810D02*
X821960D01*
G01X821890Y151800D02*
X821950Y151810D01*
G01X821870Y151800D02*
X821890D01*
G01X821460Y153080D02*
X822320D01*
G01X822430Y152990D02*
X820540D01*
G01X820820Y152790D02*
X822540D01*
G01X822580Y152580D02*
X820950D01*
G01X822440Y152080D02*
X812330D01*
G01Y152290D02*
X822540D01*
G01X822850Y151990D02*
X823480D01*
G01X823580Y152080D02*
X822950D01*
G01X823040Y152190D02*
X823680D01*
G01X823770Y152290D02*
X823140D01*
G01X823240Y152380D02*
X823870D01*
G01X823960Y152490D02*
X823340D01*
G01X823430Y152580D02*
X824060D01*
G01X824160Y152690D02*
X823530D01*
G01X823630Y152790D02*
X824260D01*
G01X824450Y152990D02*
X823820D01*
G01X824010Y153190D02*
X824640D01*
G01X823390Y151880D02*
X822760D01*
G01X822660Y151790D02*
X823290D01*
G01X823190Y151690D02*
X822560D01*
G01X822460Y151580D02*
X823100D01*
G01X823000Y151490D02*
X822370D01*
G01X822270Y151380D02*
X822910D01*
G01X822810Y151290D02*
X822180D01*
G01X822080Y151190D02*
X822710D01*
G01X822560Y149160D02*
X821430D01*
G01X822600Y149180D02*
X822560Y149160D01*
G01X822600Y149190D02*
Y149180D01*
G01Y151010D02*
Y149190D01*
G01Y151020D02*
Y151010D01*
G01X822630Y151100D02*
X822600Y151020D01*
G01X822080Y150440D02*
X821970Y150420D01*
G01X822140Y150340D02*
X822080Y150440D01*
G01X822140Y149740D02*
Y150340D01*
G01X822040Y149640D02*
X822140Y149740D01*
G01X821490Y149640D02*
X822040D01*
G01X822110Y150380D02*
X822600D01*
G01Y150290D02*
X822140D01*
G01Y150190D02*
X822600D01*
G01Y150080D02*
X822140D01*
G01Y149990D02*
X822600D01*
G01Y149880D02*
X822140D01*
G01Y149790D02*
X822600D01*
G01Y149690D02*
X822090D01*
G01X822600Y149490D02*
X820430D01*
G01X820240Y149290D02*
X822600D01*
G01Y150580D02*
X820820D01*
G01Y150790D02*
X822600D01*
G01Y150990D02*
X820820D01*
G01X821880Y151020D02*
X821950Y151050D01*
G01X821980Y151080D02*
X822620D01*
G01X821980Y140790D02*
X820430D01*
G01X820870Y140580D02*
X822170D01*
G01X822350Y140380D02*
X821080D01*
G01X821130Y140190D02*
X822540D01*
G01X822730Y139990D02*
X822040D01*
G01X821900Y139640D02*
Y139620D01*
G01X821940Y139910D02*
X821900Y139640D01*
G01X822000Y139990D02*
X821940Y139910D01*
G01X821920Y139790D02*
X821140D01*
G01X822000Y139990D02*
X822110Y139970D01*
G01X821190Y139990D02*
X822000D01*
G01X822190Y139880D02*
X822820D01*
G01X822910Y139790D02*
X822280D01*
G01X822370Y139690D02*
X823010D01*
G01X823060Y139580D02*
X823100D01*
G01X823110D02*
X822470D01*
G01X822560Y139490D02*
X823195D01*
G01X823190D02*
X823140D01*
G01X823295Y139380D02*
X822650D01*
G01X822740Y139290D02*
X823380D01*
G01X823470Y139190D02*
X822835D01*
G01X822935Y139080D02*
X823570D01*
G01X823660Y138990D02*
X823020D01*
G01X823125Y138880D02*
X823750D01*
G01X823850Y138790D02*
X823210D01*
G01X823300Y138690D02*
X823940D01*
G01X824030Y138580D02*
X823390D01*
G01X823480Y138490D02*
X824130D01*
G01X824310Y138290D02*
X823670D01*
G01X823580Y138380D02*
X824220D01*
G01X824400Y138190D02*
X823760D01*
G01X823860Y138080D02*
X824500D01*
G01X824590Y137990D02*
X823950D01*
G01X824040Y137880D02*
X824680D01*
G01X824780Y137790D02*
X824130D01*
G01X824230Y137690D02*
X824870D01*
G01X824960Y137580D02*
X824320D01*
G01X824410Y137490D02*
X825060D01*
G01X825150Y137380D02*
X824510D01*
G01X824600Y137290D02*
X825240D01*
G01X825430Y137080D02*
X824790D01*
G01X824970Y136880D02*
X825580D01*
G01X825570Y136940D02*
X821760Y141030D01*
G01X825240Y136600D02*
X825260Y136580D01*
G01X822110Y139970D02*
X825240Y136600D01*
G01X825160Y136690D02*
X825380D01*
G01X808300Y136920D02*
X813720Y142530D01*
G01X808270Y136890D02*
X808300Y136920D01*
G01X808280Y136870D02*
X808270Y136890D01*
G01X808590Y136600D02*
X808280Y136870D01*
G01X808620Y136590D02*
X808590Y136600D01*
G01X808640D02*
X808620Y136590D01*
G01X813760Y141900D02*
X808640Y136600D01*
G01X808720Y136690D02*
X808490D01*
G01X808370Y136790D02*
X808820D01*
G01X808920Y136880D02*
X808270D01*
G01X808360Y136990D02*
X809020D01*
G01X809110Y137080D02*
X808460D01*
G01X808550Y137190D02*
X809210D01*
G01X809300Y137290D02*
X808650D01*
G01X808740Y137380D02*
X809400D01*
G01X809500Y137490D02*
X808840D01*
G01X808940Y137580D02*
X809590D01*
G01X809690Y137690D02*
X809040D01*
G01X809130Y137790D02*
X809790D01*
G01X809880Y137880D02*
X809230D01*
G01X809330Y137990D02*
X809980D01*
G01X810080Y138080D02*
X809420D01*
G01X809520Y138190D02*
X810170D01*
G01X821950Y151050D02*
X826530Y155790D01*
G01X826560Y155180D02*
X822630Y151100D01*
G01X823720Y152880D02*
X824350D01*
G01X824540Y153080D02*
X823910D01*
G01X824110Y153290D02*
X824740D01*
G01X824840Y153380D02*
X824210D01*
G01X824300Y153490D02*
X824930D01*
G01X825030Y153580D02*
X824400D01*
G01X824500Y153690D02*
X825120D01*
G01X825220Y153790D02*
X824590D01*
G01X824780Y153990D02*
X825410D01*
G01X825610Y154190D02*
X824980D01*
G01X825170Y154380D02*
X825800D01*
G01X825700Y154290D02*
X825080D01*
G01X825270Y154490D02*
X825890D01*
G01X825990Y154580D02*
X825360D01*
G01X825460Y154690D02*
X826090D01*
G01X826190Y154790D02*
X825560D01*
G01X825650Y154880D02*
X826280D01*
G01X826380Y154990D02*
X825750D01*
G01X825850Y155080D02*
X826470D01*
G01X826580Y155290D02*
X826040D01*
G01X826570Y155210D02*
X826580Y155290D01*
G01X826560Y155180D02*
X826570Y155210D01*
G01X825950Y155190D02*
X826560D01*
G01X826580Y155780D02*
X826530Y155790D01*
G01X826580Y155290D02*
Y155780D01*
G01X826520Y155790D02*
X826560D01*
G01X826580Y155690D02*
X826430D01*
G01X826330Y155580D02*
X826580D01*
G01Y155490D02*
X826230D01*
G01X826140Y155380D02*
X826580D01*
G01X825510Y154080D02*
X824880D01*
G01X824690Y153880D02*
X825320D01*
G01X825340Y137190D02*
X824690D01*
G01X824880Y136990D02*
X825520D01*
G01X825290Y136600D02*
X825260Y136580D01*
G01X825580Y136890D02*
X825290Y136600D01*
G01X825590Y136910D02*
X825580Y136890D01*
G01Y136920D02*
X825590Y136910D01*
G01X825570Y136940D02*
X825580Y136920D01*
G01X825060Y136790D02*
X825480D01*
G54D11*
G01X9493Y25340D02*
G03I-500J0D01*
G01X9818Y56707D02*
G03I-500J0D01*
G01X0Y278000D02*
G03I-500J0D01*
G01X21340Y263651D02*
G03I-500J0D01*
G01X17422Y263132D02*
G03I-500J0D01*
G01X17484Y516547D02*
G03I-500J0D01*
G01X-607Y531996D02*
G03I-500J0D01*
G01Y567996D02*
G03I-500J0D01*
G01X52747Y-9859D02*
G03I-500J0D01*
G01X85200Y161590D02*
G03I-500J0D01*
G01X86186Y244427D02*
G03I-500J0D01*
G01X89092Y223893D02*
G03I-500J0D01*
G01X97386Y268808D02*
G03I-500J0D01*
G01X97117Y335159D02*
G03I-500J0D01*
G01X82737Y323750D02*
G03I-500J0D01*
G01X71550Y335841D02*
G03I-500J0D01*
G01X95550Y300150D02*
G03I-500J0D01*
G01X85169Y291327D02*
G03I-500J0D01*
G01X62228Y372719D02*
G03I-500J0D01*
G01X140920Y141452D02*
G03I-500J0D01*
G01X123517Y212529D02*
G03I-500J0D01*
G01Y276529D02*
G03I-500J0D01*
G01Y244529D02*
G03I-500J0D01*
G01Y340529D02*
G03I-500J0D01*
G01Y308529D02*
G03I-500J0D01*
G01Y372529D02*
G03I-500J0D01*
G01X206400Y485400D02*
X212800D01*
G01X206400Y485200D02*
X212400D01*
G01X206200Y485000D02*
X212200D01*
G01X206200Y484800D02*
X212000D01*
G01X206200Y484600D02*
X211800D01*
G01X206000Y484400D02*
X211600D01*
G01X206000Y484200D02*
X211400D01*
G01X206000Y484000D02*
X211400D01*
G01X206000Y483800D02*
X211400D01*
G01X205800Y483600D02*
X211200D01*
G01X205800Y483400D02*
X211200D01*
G01X205800Y483200D02*
X211200D01*
G01X205800Y483000D02*
X211000D01*
G01X205800Y482800D02*
X211000D01*
G01X205800Y482600D02*
X211000D01*
G01X205600Y482400D02*
X211000D01*
G01X205600Y482200D02*
X211000D01*
G01X205600Y482000D02*
X211000D01*
G01X205600Y481800D02*
X211000D01*
G01X205600Y481600D02*
X210800D01*
G01X205600Y481400D02*
X210800D01*
G01X205600Y481200D02*
X210800D01*
G01X205600Y481000D02*
X210800D01*
G01X205600Y480800D02*
X210800D01*
G01X205600Y480600D02*
X210800D01*
G01X205600Y480400D02*
X211000D01*
G01X205600Y480200D02*
X211000D01*
G01X205600Y480000D02*
X211000D01*
G01X205600Y479800D02*
X211000D01*
G01X205800Y479600D02*
X211000D01*
G01X205800Y479400D02*
X211000D01*
G01X205800Y479200D02*
X211000D01*
G01X205800Y479000D02*
X211200D01*
G01X205800Y478800D02*
X211200D01*
G01X205800Y478600D02*
X211200D01*
G01X206000Y478400D02*
X211400D01*
G01X206000Y478200D02*
X211400D01*
G01X206000Y478000D02*
X211600D01*
G01X206000Y477800D02*
X211600D01*
G01X206200Y477600D02*
X211800D01*
G01X206200Y477400D02*
X212000D01*
G01X206200Y477200D02*
X212200D01*
G01X206400Y477000D02*
X212400D01*
G01X206400Y476800D02*
X212800D01*
G01X210000Y489200D02*
X218600D01*
G01X209800Y489000D02*
X219000D01*
G01X209400Y488800D02*
X219400D01*
G01X209000Y488600D02*
X219600D01*
G01X208800Y488400D02*
X220000D01*
G01X208600Y488200D02*
X220200D01*
G01X208400Y488000D02*
X220400D01*
G01X208200Y487800D02*
X220600D01*
G01X208000Y487600D02*
X220800D01*
G01X207800Y487400D02*
X221000D01*
G01X207600Y487200D02*
X221000D01*
G01X207400Y487000D02*
X221200D01*
G01X207200Y486800D02*
X221400D01*
G01X207200Y486600D02*
X221400D01*
G01X207000Y486400D02*
X221600D01*
G01X206800Y486200D02*
X221600D01*
G01X206800Y486000D02*
X221800D01*
G01X206600Y485800D02*
X221800D01*
G01X206600Y485600D02*
X213200D01*
G01X206600Y476600D02*
X213400D01*
G01X206600Y476400D02*
X222000D01*
G01X206800Y476200D02*
X221800D01*
G01X206800Y476000D02*
X221800D01*
G01X207000Y475800D02*
X221600D01*
G01X207200Y475600D02*
X221600D01*
G01X207200Y475400D02*
X221400D01*
G01X207400Y475200D02*
X221200D01*
G01X207600Y475000D02*
X221200D01*
G01X207800Y474800D02*
X221000D01*
G01X208000Y474600D02*
X220800D01*
G01X208200Y474400D02*
X220600D01*
G01X208400Y474200D02*
X220400D01*
G01X208600Y474000D02*
X220200D01*
G01X208800Y473800D02*
X220000D01*
G01X209000Y473600D02*
X219600D01*
G01X209400Y473400D02*
X219400D01*
G01X209800Y473200D02*
X219000D01*
G01X211800Y489800D02*
X217000D01*
G01X211000Y489600D02*
X217600D01*
G01X210600Y489400D02*
X218200D01*
G01X212800Y490000D02*
X215800D01*
G01X210200Y473000D02*
X218600D01*
G01X210600Y472800D02*
X218200D01*
G01X211200Y472600D02*
X217600D01*
G01X211800Y472400D02*
X217000D01*
G01X213000Y472200D02*
X216000D01*
G01X215400Y485600D02*
X222000D01*
G01X216000Y485400D02*
X222000D01*
G01X216400Y485200D02*
X222000D01*
G01X216600Y485000D02*
X222200D01*
G01X216800Y484800D02*
X222200D01*
G01X217000Y484600D02*
X222200D01*
G01X217000Y484400D02*
X222200D01*
G01X217200Y484200D02*
X222400D01*
G01X217200Y484000D02*
X222400D01*
G01X217400Y483800D02*
X222400D01*
G01X217400Y483600D02*
X222400D01*
G01X217400Y483400D02*
X222400D01*
G01X217400Y483200D02*
X222400D01*
G01X217600Y479200D02*
X222600D01*
G01X217600Y479000D02*
X222600D01*
G01X217600Y478800D02*
X222600D01*
G01X217400Y478600D02*
X222400D01*
G01X217400Y478400D02*
X222400D01*
G01X217400Y478200D02*
X222400D01*
G01X217200Y478000D02*
X222400D01*
G01X217200Y477800D02*
X222400D01*
G01X217000Y477600D02*
X222200D01*
G01X216800Y477400D02*
X222200D01*
G01X216600Y477200D02*
X222200D01*
G01X216400Y477000D02*
X222200D01*
G01X216000Y476800D02*
X222000D01*
G01X215600Y476600D02*
X222000D01*
G01X225200Y475200D02*
X230400D01*
G01X225200Y481600D02*
X240200D01*
G01X225200Y489600D02*
X234400D01*
G01X225200Y489400D02*
X235800D01*
G01X225200Y489200D02*
X236600D01*
G01X225200Y489000D02*
X237200D01*
G01X225200Y488800D02*
X237600D01*
G01X225200Y488600D02*
X238000D01*
G01X225200Y488400D02*
X238200D01*
G01X225200Y488200D02*
X238400D01*
G01X225200Y488000D02*
X238600D01*
G01X225200Y487800D02*
X238800D01*
G01X225200Y487600D02*
X239000D01*
G01X225200Y487400D02*
X239200D01*
G01X225200Y487200D02*
X239400D01*
G01X225200Y487000D02*
X239600D01*
G01X225200Y486800D02*
X239600D01*
G01X225200Y486600D02*
X239800D01*
G01X225200Y486400D02*
X239800D01*
G01X225200Y486200D02*
X240000D01*
G01X225200Y486000D02*
X240000D01*
G01X225200Y485800D02*
X240000D01*
G01X225200Y485600D02*
X240200D01*
G01X225200Y485400D02*
X230400D01*
G01X225200Y485200D02*
X230400D01*
G01X225200Y485000D02*
X230400D01*
G01X225200Y484800D02*
X230400D01*
G01X225200Y484600D02*
X230400D01*
G01X225200Y484400D02*
X230400D01*
G01X225200Y484200D02*
X230400D01*
G01X225200Y484000D02*
X230400D01*
G01X225200Y483800D02*
X230400D01*
G01X225200Y483600D02*
X230400D01*
G01X225200Y483400D02*
X230400D01*
G01X225200Y483200D02*
X230400D01*
G01X225200Y483000D02*
X230400D01*
G01X225200Y482800D02*
X230400D01*
G01X225200Y482600D02*
X230400D01*
G01X225200Y482400D02*
X230400D01*
G01X225200Y482200D02*
X230400D01*
G01X225200Y482000D02*
X230400D01*
G01X225200Y481800D02*
X240200D01*
G01X225200Y481400D02*
X240000D01*
G01X225200Y481200D02*
X240000D01*
G01X225200Y481000D02*
X239800D01*
G01X225200Y480800D02*
X239800D01*
G01X225200Y480600D02*
X239800D01*
G01X225200Y480400D02*
X239600D01*
G01X225200Y480200D02*
X239400D01*
G01X225200Y480000D02*
X239400D01*
G01X225200Y479800D02*
X239200D01*
G01X225200Y479600D02*
X239000D01*
G01X225200Y479400D02*
X238800D01*
G01X225200Y479200D02*
X238600D01*
G01X225200Y479000D02*
X238400D01*
G01X225200Y478800D02*
X238000D01*
G01X225200Y478600D02*
X237800D01*
G01X225200Y478400D02*
X237400D01*
G01X225200Y478200D02*
X237000D01*
G01X225200Y478000D02*
X236200D01*
G01X225200Y477800D02*
X235200D01*
G01X225200Y477600D02*
X230400D01*
G01X225200Y477400D02*
X230400D01*
G01X225200Y477200D02*
X230400D01*
G01X225200Y477000D02*
X230400D01*
G01X225200Y476800D02*
X230400D01*
G01X225200Y476600D02*
X230400D01*
G01X225200Y476400D02*
X230400D01*
G01X225200Y476200D02*
X230400D01*
G01X225200Y476000D02*
X230400D01*
G01X225200Y475800D02*
X230400D01*
G01X225200Y475600D02*
X230400D01*
G01X225200Y475400D02*
X230400D01*
G01X225200Y475000D02*
X230400D01*
G01X225200Y474800D02*
X230400D01*
G01X225200Y474600D02*
X230400D01*
G01X225200Y474400D02*
X230400D01*
G01X225200Y474200D02*
X230400D01*
G01X225200Y474000D02*
X230400D01*
G01X225200Y473800D02*
X230400D01*
G01X225200Y473600D02*
X230400D01*
G01X225200Y473400D02*
X230400D01*
G01X225200Y473200D02*
X230400D01*
G01X225200Y473000D02*
X230400D01*
G01X225200Y472800D02*
X230400D01*
G01X225200Y472600D02*
X230400D01*
G01X243000Y489600D02*
X248200D01*
G01X243000Y489400D02*
X248200D01*
G01X243000Y489200D02*
X248200D01*
G01X243000Y489000D02*
X248200D01*
G01X243000Y488800D02*
X248200D01*
G01X243000Y488600D02*
X248200D01*
G01X243000Y488400D02*
X248200D01*
G01X243000Y488200D02*
X248200D01*
G01X243000Y488000D02*
X248200D01*
G01X243000Y487800D02*
X248200D01*
G01X243000Y487600D02*
X248200D01*
G01X243000Y487400D02*
X248200D01*
G01X243000Y487200D02*
X248200D01*
G01X243000Y487000D02*
X248200D01*
G01X243000Y486800D02*
X248200D01*
G01X243000Y486600D02*
X248200D01*
G01X243000Y486400D02*
X248200D01*
G01X243000Y486200D02*
X248200D01*
G01X243000Y486000D02*
X248200D01*
G01X243000Y485800D02*
X248200D01*
G01X243000Y485600D02*
X248200D01*
G01X243000Y485400D02*
X248200D01*
G01X243000Y485200D02*
X248200D01*
G01X243000Y485000D02*
X248200D01*
G01X243000Y484800D02*
X248200D01*
G01X243000Y484600D02*
X248200D01*
G01X243000Y484400D02*
X248200D01*
G01X243000Y484200D02*
X248200D01*
G01X243000Y484000D02*
X248200D01*
G01X243000Y483800D02*
X248200D01*
G01X243000Y483600D02*
X248200D01*
G01X243000Y483400D02*
X248200D01*
G01X243000Y483200D02*
X248200D01*
G01X243000Y483000D02*
X248200D01*
G01X243000Y482800D02*
X248200D01*
G01X243000Y482600D02*
X248200D01*
G01X243000Y482400D02*
X248200D01*
G01X243000Y482200D02*
X248200D01*
G01X243000Y482000D02*
X248200D01*
G01X243000Y481800D02*
X248200D01*
G01X243000Y481600D02*
X248200D01*
G01X243000Y481400D02*
X248200D01*
G01X243000Y481200D02*
X248200D01*
G01X243000Y481000D02*
X248200D01*
G01X243000Y480800D02*
X248200D01*
G01X243000Y480600D02*
X248200D01*
G01X243000Y480400D02*
X248200D01*
G01X243000Y480200D02*
X248200D01*
G01X243000Y480000D02*
X248200D01*
G01X243000Y479800D02*
X248200D01*
G01X243000Y479600D02*
X248200D01*
G01X243000Y479400D02*
X248200D01*
G01X243000Y479200D02*
X248200D01*
G01X243000Y479000D02*
X248200D01*
G01X243000Y478800D02*
X248200D01*
G01X243000Y478600D02*
X248200D01*
G01X243000Y478400D02*
X248200D01*
G01X243000Y478200D02*
X248400D01*
G01X243000Y478000D02*
X248400D01*
G01X253600D02*
X259000D01*
G01X243000Y477800D02*
X248400D01*
G01X253600D02*
X259000D01*
G01X243000Y477600D02*
X248600D01*
G01X253600D02*
X259000D01*
G01X243000Y477400D02*
X248600D01*
G01X253400D02*
X259000D01*
G01X243200Y477200D02*
X248800D01*
G01X253200D02*
X259000D01*
G01X243200Y477000D02*
X249000D01*
G01X253000D02*
X258800D01*
G01X243200Y476800D02*
X249200D01*
G01X252800D02*
X258800D01*
G01X243200Y476600D02*
X249800D01*
G01X252200D02*
X258800D01*
G01X243400Y476400D02*
X258800D01*
G01X243400Y476200D02*
X258600D01*
G01X243400Y476000D02*
X258600D01*
G01X243600Y475800D02*
X258400D01*
G01X243600Y475600D02*
X258400D01*
G01X243800Y475400D02*
X258200D01*
G01X243800Y475200D02*
X258200D01*
G01X244000Y475000D02*
X258000D01*
G01X244200Y474800D02*
X258000D01*
G01X244400Y474600D02*
X257800D01*
G01X244400Y474400D02*
X257600D01*
G01X244600Y474200D02*
X257400D01*
G01X244800Y474000D02*
X257200D01*
G01X245200Y473800D02*
X257000D01*
G01X245400Y473600D02*
X256600D01*
G01X245600Y473400D02*
X256400D01*
G01X246000Y473200D02*
X256000D01*
G01X246400Y473000D02*
X255600D01*
G01X246800Y472800D02*
X255200D01*
G01X247400Y472600D02*
X254600D01*
G01X248200Y472400D02*
X253800D01*
G01X249400Y472200D02*
X252800D01*
G01X234000Y485400D02*
X240200D01*
G01X234600Y485200D02*
X240200D01*
G01X235000Y485000D02*
X240200D01*
G01X235200Y484800D02*
X240400D01*
G01X235200Y484600D02*
X240400D01*
G01X235400Y484400D02*
X240400D01*
G01X235400Y484200D02*
X240400D01*
G01X235400Y484000D02*
X240400D01*
G01X235400Y483800D02*
X240400D01*
G01X235400Y483600D02*
X240400D01*
G01X235400Y483400D02*
X240400D01*
G01X235400Y483200D02*
X240400D01*
G01X235400Y483000D02*
X240400D01*
G01X235200Y482800D02*
X240400D01*
G01X235200Y482600D02*
X240400D01*
G01X235000Y482400D02*
X240200D01*
G01X234600Y482200D02*
X240200D01*
G01X234000Y482000D02*
X240200D01*
G01X266800Y486600D02*
X271800D01*
G01X266600Y486400D02*
X271800D01*
G01X266200Y486200D02*
X271800D01*
G01X265600Y486000D02*
X271800D01*
G01X264800Y485800D02*
X271800D01*
G01X263400Y485600D02*
X271800D01*
G01X263400Y485400D02*
X271800D01*
G01X263400Y485200D02*
X271800D01*
G01X263400Y485000D02*
X271800D01*
G01X263400Y484800D02*
X271800D01*
G01X263400Y484600D02*
X271800D01*
G01X263400Y484400D02*
X271800D01*
G01X263400Y484200D02*
X271800D01*
G01X263400Y484000D02*
X271800D01*
G01X263400Y483800D02*
X271800D01*
G01X263400Y483600D02*
X271800D01*
G01X263400Y483400D02*
X271800D01*
G01X263400Y483200D02*
X271800D01*
G01X263400Y483000D02*
X271800D01*
G01X263400Y482800D02*
X271800D01*
G01X263400Y482600D02*
X271800D01*
G01X263400Y482400D02*
X271800D01*
G01X268200Y489200D02*
X271800D01*
G01X268200Y489000D02*
X271800D01*
G01X268200Y488800D02*
X271800D01*
G01X268200Y488600D02*
X271800D01*
G01X268000Y488400D02*
X271800D01*
G01X268000Y488200D02*
X271800D01*
G01X268000Y488000D02*
X271800D01*
G01X267800Y487800D02*
X271800D01*
G01X267800Y487600D02*
X271800D01*
G01X267600Y487400D02*
X271800D01*
G01X267400Y487200D02*
X271800D01*
G01X267400Y487000D02*
X271800D01*
G01X267200Y486800D02*
X271800D01*
G01X267200Y482200D02*
X271800D01*
G01X267200Y482000D02*
X271800D01*
G01X267200Y481800D02*
X271800D01*
G01X267200Y481600D02*
X271800D01*
G01X267200Y481400D02*
X271800D01*
G01X267200Y481200D02*
X271800D01*
G01X267200Y481000D02*
X271800D01*
G01X267200Y480800D02*
X271800D01*
G01X267200Y480600D02*
X271800D01*
G01X267200Y480400D02*
X271800D01*
G01X267200Y480200D02*
X271800D01*
G01X267200Y480000D02*
X271800D01*
G01X267200Y479800D02*
X271800D01*
G01X267200Y479600D02*
X271800D01*
G01X267200Y479400D02*
X271800D01*
G01X267200Y479200D02*
X271800D01*
G01X267200Y479000D02*
X271800D01*
G01X267200Y478800D02*
X271800D01*
G01X267200Y478600D02*
X271800D01*
G01X267200Y478400D02*
X271800D01*
G01X267200Y478200D02*
X271800D01*
G01X267200Y478000D02*
X271800D01*
G01X267200Y477800D02*
X271800D01*
G01X267200Y477600D02*
X271800D01*
G01X267200Y477400D02*
X271800D01*
G01X267200Y477200D02*
X271800D01*
G01X267200Y477000D02*
X271800D01*
G01X267200Y476800D02*
X271800D01*
G01X267200Y476600D02*
X271800D01*
G01X267200Y476400D02*
X271800D01*
G01X267200Y476200D02*
X271800D01*
G01X267200Y476000D02*
X271800D01*
G01X267200Y475800D02*
X271800D01*
G01X267200Y475600D02*
X271800D01*
G01X267200Y475400D02*
X271800D01*
G01X267200Y475200D02*
X271800D01*
G01X267200Y475000D02*
X271800D01*
G01X267200Y474800D02*
X271800D01*
G01X267200Y474600D02*
X271800D01*
G01X267200Y474400D02*
X271800D01*
G01X267200Y474200D02*
X271800D01*
G01X267200Y474000D02*
X271800D01*
G01X267200Y473800D02*
X271800D01*
G01X267200Y473600D02*
X271800D01*
G01X267200Y473400D02*
X271800D01*
G01X267200Y473200D02*
X271800D01*
G01X267200Y473000D02*
X271800D01*
G01X267200Y472800D02*
X271800D01*
G01X267200Y472600D02*
X271800D01*
G01X253800Y489600D02*
X259000D01*
G01X253800Y489400D02*
X259000D01*
G01X253800Y489200D02*
X259000D01*
G01X253800Y489000D02*
X259000D01*
G01X253800Y488800D02*
X259000D01*
G01X253800Y488600D02*
X259000D01*
G01X253800Y488400D02*
X259000D01*
G01X253800Y488200D02*
X259000D01*
G01X253800Y488000D02*
X259000D01*
G01X253800Y487800D02*
X259000D01*
G01X253800Y487600D02*
X259000D01*
G01X253800Y487400D02*
X259000D01*
G01X253800Y487200D02*
X259000D01*
G01X253800Y487000D02*
X259000D01*
G01X253800Y486800D02*
X259000D01*
G01X253800Y486600D02*
X259000D01*
G01X253800Y486400D02*
X259000D01*
G01X253800Y486200D02*
X259000D01*
G01X253800Y486000D02*
X259000D01*
G01X253800Y485800D02*
X259000D01*
G01X253800Y485600D02*
X259000D01*
G01X253800Y485400D02*
X259000D01*
G01X253800Y485200D02*
X259000D01*
G01X253800Y485000D02*
X259000D01*
G01X253800Y484800D02*
X259000D01*
G01X253800Y484600D02*
X259000D01*
G01X253800Y484400D02*
X259000D01*
G01X253800Y484200D02*
X259000D01*
G01X253800Y484000D02*
X259000D01*
G01X253800Y483800D02*
X259000D01*
G01X253800Y483600D02*
X259000D01*
G01X253800Y483400D02*
X259000D01*
G01X253800Y483200D02*
X259000D01*
G01X253800Y483000D02*
X259000D01*
G01X253800Y482800D02*
X259000D01*
G01X253800Y482600D02*
X259000D01*
G01X253800Y482400D02*
X259000D01*
G01X253800Y482200D02*
X259000D01*
G01X253800Y482000D02*
X259000D01*
G01X253800Y481800D02*
X259000D01*
G01X253800Y481600D02*
X259000D01*
G01X253800Y481400D02*
X259000D01*
G01X253800Y481200D02*
X259000D01*
G01X253800Y481000D02*
X259000D01*
G01X253800Y480800D02*
X259000D01*
G01X253800Y480600D02*
X259000D01*
G01X253800Y480400D02*
X259000D01*
G01X253800Y480200D02*
X259000D01*
G01X253800Y480000D02*
X259000D01*
G01X253800Y479800D02*
X259000D01*
G01X253800Y479600D02*
X259000D01*
G01X253800Y479400D02*
X259000D01*
G01X253800Y479200D02*
X259000D01*
G01X253800Y479000D02*
X259000D01*
G01X253800Y478800D02*
X259000D01*
G01X253800Y478600D02*
X259000D01*
G01X253800Y478400D02*
X259000D01*
G01X253800Y478200D02*
X259000D01*
G01X582611Y125463D02*
G03I-500J0D01*
G01X659941Y8796D02*
G03I-500J0D01*
G01X603062Y189900D02*
G03I-499J0D01*
G01X603063D02*
G03I-500J0D01*
G01X652379Y296970D02*
G03I-500J0D01*
G01X643730Y493350D02*
G03I-500J0D01*
G01X611704Y489241D02*
G03I-500J0D01*
G01X680488Y10857D02*
G03I-500J0D01*
G01X687793Y37076D02*
G03I-500J0D01*
G01X675484Y275747D02*
G03I-500J0D01*
G01X709607Y226004D02*
G03I-500J0D01*
G01X676235Y292696D02*
G03I-500J0D01*
G01X711228Y283719D02*
G03I-500J0D01*
G01X677651Y372829D02*
G03I-500J0D01*
G01X688150Y501970D02*
G03I-500J0D01*
G01X687793Y523326D02*
G03I-500J0D01*
G01X714962Y580762D02*
G03I-499J0D01*
G01X680887Y574850D02*
G03I-500J0D01*
G01X727079Y13940D02*
G03I-499J0D01*
G01X773125Y212529D02*
G03I-500J0D01*
G01Y244529D02*
G03I-500J0D01*
G01Y276529D02*
G03I-500J0D01*
G01Y308529D02*
G03I-500J0D01*
G01X771228Y339285D02*
G03I-500J0D01*
G01X773075Y372529D02*
G03I-500J0D01*
G01X905100Y472400D02*
X919500D01*
G01X904900Y473000D02*
X919700D01*
G01X904900Y472800D02*
X919700D01*
G01X905100Y472600D02*
X919500D01*
G01X905300Y472200D02*
X919300D01*
G01X905500Y472000D02*
X919300D01*
G01X905700Y471800D02*
X919100D01*
G01X905700Y471600D02*
X918900D01*
G01X905900Y471400D02*
X918700D01*
G01X906100Y471200D02*
X918500D01*
G01X906500Y471000D02*
X918300D01*
G01X906700Y470800D02*
X917900D01*
G01X906900Y470600D02*
X917700D01*
G01X907300Y470400D02*
X917300D01*
G01X904300Y486800D02*
X909500D01*
G01X904300Y486600D02*
X909500D01*
G01X904300Y486400D02*
X909500D01*
G01X904300Y486200D02*
X909500D01*
G01X904300Y486000D02*
X909500D01*
G01X904300Y485800D02*
X909500D01*
G01X904300Y485600D02*
X909500D01*
G01X904300Y485400D02*
X909500D01*
G01X904300Y485200D02*
X909500D01*
G01X904300Y485000D02*
X909500D01*
G01X904300Y484800D02*
X909500D01*
G01X904300Y484600D02*
X909500D01*
G01X904300Y484400D02*
X909500D01*
G01X904300Y484200D02*
X909500D01*
G01X904300Y484000D02*
X909500D01*
G01X904300Y483800D02*
X909500D01*
G01X904300Y483600D02*
X909500D01*
G01X904300Y483400D02*
X909500D01*
G01X904300Y483200D02*
X909500D01*
G01X904300Y483000D02*
X909500D01*
G01X904300Y482800D02*
X909500D01*
G01X904300Y482600D02*
X909500D01*
G01X904300Y482400D02*
X909500D01*
G01X904300Y482200D02*
X909500D01*
G01X904300Y482000D02*
X909500D01*
G01X904300Y481800D02*
X909500D01*
G01X904300Y481600D02*
X909500D01*
G01X904300Y481400D02*
X909500D01*
G01X904300Y481200D02*
X909500D01*
G01X904300Y481000D02*
X909500D01*
G01X904300Y480800D02*
X909500D01*
G01X904300Y480600D02*
X909500D01*
G01X904300Y480400D02*
X909500D01*
G01X904300Y480200D02*
X909500D01*
G01X904300Y480000D02*
X909500D01*
G01X904300Y479800D02*
X909500D01*
G01X904300Y479600D02*
X909500D01*
G01X904300Y479400D02*
X909500D01*
G01X904300Y479200D02*
X909500D01*
G01X904300Y479000D02*
X909500D01*
G01X904300Y478800D02*
X909500D01*
G01X904300Y478600D02*
X909500D01*
G01X904300Y478400D02*
X909500D01*
G01X904300Y478200D02*
X909500D01*
G01X904300Y478000D02*
X909500D01*
G01X904300Y477800D02*
X909500D01*
G01X904300Y477600D02*
X909500D01*
G01X904300Y477400D02*
X909500D01*
G01X904300Y477200D02*
X909500D01*
G01X904300Y477000D02*
X909500D01*
G01X904300Y476800D02*
X909500D01*
G01X904300Y476600D02*
X909500D01*
G01X904300Y476400D02*
X909500D01*
G01X904300Y476200D02*
X909500D01*
G01X904300Y476000D02*
X909500D01*
G01X904300Y475800D02*
X909500D01*
G01X904300Y475600D02*
X909500D01*
G01X904300Y475400D02*
X909700D01*
G01X904300Y475200D02*
X909700D01*
G01X904300Y475000D02*
X909700D01*
G01X904300Y474800D02*
X909900D01*
G01X904300Y474600D02*
X909900D01*
G01X904500Y474400D02*
X910100D01*
G01X904500Y474200D02*
X910300D01*
G01X904500Y474000D02*
X910500D01*
G01X904500Y473800D02*
X911100D01*
G01X904700Y473600D02*
X920100D01*
G01X904700Y473400D02*
X919900D01*
G01X904700Y473200D02*
X919900D01*
G01X907700Y470200D02*
X916900D01*
G01X908100Y470000D02*
X916500D01*
G01X908700Y469800D02*
X915900D01*
G01X909500Y469600D02*
X915100D01*
G01X872300Y486800D02*
X878900D01*
G01X871900Y486600D02*
X879500D01*
G01X871300Y486400D02*
X879900D01*
G01X871100Y486200D02*
X880300D01*
G01X871100Y470400D02*
X880300D01*
G01X870700Y486000D02*
X880700D01*
G01X870300Y485800D02*
X880900D01*
G01X870100Y485600D02*
X881300D01*
G01X869900Y485400D02*
X881500D01*
G01X869700Y485200D02*
X881700D01*
G01X869500Y485000D02*
X881900D01*
G01X869300Y484800D02*
X882100D01*
G01X869100Y484600D02*
X882300D01*
G01X868900Y484400D02*
X882300D01*
G01X868700Y484200D02*
X882500D01*
G01X868500Y484000D02*
X882700D01*
G01X868500Y483800D02*
X882700D01*
G01X868300Y483600D02*
X882900D01*
G01X868100Y483400D02*
X882900D01*
G01X868100Y483200D02*
X883100D01*
G01X868100Y473400D02*
X883100D01*
G01X868100Y473200D02*
X883100D01*
G01X868300Y473000D02*
X882900D01*
G01X868500Y472800D02*
X882900D01*
G01X868500Y472600D02*
X882700D01*
G01X868700Y472400D02*
X882500D01*
G01X868900Y472200D02*
X882500D01*
G01X869100Y472000D02*
X882300D01*
G01X869300Y471800D02*
X882100D01*
G01X869500Y471600D02*
X881900D01*
G01X869700Y471400D02*
X881700D01*
G01X869900Y471200D02*
X881500D01*
G01X870100Y471000D02*
X881300D01*
G01X870300Y470800D02*
X880900D01*
G01X870700Y470600D02*
X880700D01*
G01X874100Y487200D02*
X877100D01*
G01X873100Y487000D02*
X878300D01*
G01X876700Y482800D02*
X883300D01*
G01X877300Y482600D02*
X883300D01*
G01X877700Y482400D02*
X883300D01*
G01X877900Y482200D02*
X883500D01*
G01X878100Y482000D02*
X883500D01*
G01X878300Y481800D02*
X883500D01*
G01X878300Y481600D02*
X883500D01*
G01X878500Y481400D02*
X883700D01*
G01X878500Y481200D02*
X883700D01*
G01X878700Y481000D02*
X883700D01*
G01X878700Y480800D02*
X883700D01*
G01X878700Y480600D02*
X883700D01*
G01X878700Y480400D02*
X883700D01*
G01X878900Y476400D02*
X883900D01*
G01X878900Y476200D02*
X883900D01*
G01X878900Y476000D02*
X883900D01*
G01X878700Y475800D02*
X883700D01*
G01X878700Y475600D02*
X883700D01*
G01X878700Y475400D02*
X883700D01*
G01X878500Y475200D02*
X883700D01*
G01X878500Y475000D02*
X883700D01*
G01X878300Y474800D02*
X883500D01*
G01X878100Y474600D02*
X883500D01*
G01X877900Y474400D02*
X883500D01*
G01X877700Y474200D02*
X883500D01*
G01X877300Y474000D02*
X883300D01*
G01X876900Y473800D02*
X883300D01*
G01X886500Y486800D02*
X895700D01*
G01X886500Y486600D02*
X897100D01*
G01X886500Y486400D02*
X897900D01*
G01X886500Y486200D02*
X898500D01*
G01X886500Y486000D02*
X898900D01*
G01X886500Y485800D02*
X899300D01*
G01X886500Y485600D02*
X899500D01*
G01X886500Y485400D02*
X899700D01*
G01X886500Y485200D02*
X899900D01*
G01X886500Y485000D02*
X900100D01*
G01X886500Y484800D02*
X900300D01*
G01X886500Y484600D02*
X900500D01*
G01X886500Y484400D02*
X900700D01*
G01X886500Y484200D02*
X900900D01*
G01X886500Y484000D02*
X900900D01*
G01X886500Y483800D02*
X901100D01*
G01X886500Y483600D02*
X901100D01*
G01X886500Y483400D02*
X901300D01*
G01X886500Y483200D02*
X901300D01*
G01X886500Y483000D02*
X901300D01*
G01X886500Y482800D02*
X901500D01*
G01X886500Y482600D02*
X891700D01*
G01X895300D02*
X901500D01*
G01X886500Y482400D02*
X891700D01*
G01X895900D02*
X901500D01*
G01X886500Y482200D02*
X891700D01*
G01X896300D02*
X901500D01*
G01X886500Y482000D02*
X891700D01*
G01X896500D02*
X901700D01*
G01X886500Y481800D02*
X891700D01*
G01X896500D02*
X901700D01*
G01X886500Y481600D02*
X891700D01*
G01X896700D02*
X901700D01*
G01X886500Y481400D02*
X891700D01*
G01X896700D02*
X901700D01*
G01X886500Y481200D02*
X891700D01*
G01X896700D02*
X901700D01*
G01X886500Y481000D02*
X891700D01*
G01X896700D02*
X901700D01*
G01X886500Y480800D02*
X891700D01*
G01X896700D02*
X901700D01*
G01X886500Y480600D02*
X891700D01*
G01X896700D02*
X901700D01*
G01X886500Y480400D02*
X891700D01*
G01X896700D02*
X901700D01*
G01X886500Y480200D02*
X891700D01*
G01X896700D02*
X901700D01*
G01X886500Y480000D02*
X891700D01*
G01X896500D02*
X901700D01*
G01X886500Y479800D02*
X891700D01*
G01X896500D02*
X901700D01*
G01X886500Y479600D02*
X891700D01*
G01X896300D02*
X901500D01*
G01X886500Y479400D02*
X891700D01*
G01X895900D02*
X901500D01*
G01X886500Y479200D02*
X891700D01*
G01X895300D02*
X901500D01*
G01X886500Y479000D02*
X901500D01*
G01X886500Y478800D02*
X901500D01*
G01X886500Y478600D02*
X901300D01*
G01X886500Y478400D02*
X901300D01*
G01X886500Y478200D02*
X901100D01*
G01X886500Y478000D02*
X901100D01*
G01X886500Y477800D02*
X901100D01*
G01X886500Y477600D02*
X900900D01*
G01X886500Y477400D02*
X900700D01*
G01X886500Y477200D02*
X900700D01*
G01X886500Y477000D02*
X900500D01*
G01X886500Y476800D02*
X900300D01*
G01X886500Y476600D02*
X900100D01*
G01X886500Y476400D02*
X899900D01*
G01X886500Y476200D02*
X899700D01*
G01X886500Y476000D02*
X899300D01*
G01X886500Y475800D02*
X899100D01*
G01X886500Y475600D02*
X898700D01*
G01X886500Y475400D02*
X898300D01*
G01X886500Y475200D02*
X897500D01*
G01X886500Y475000D02*
X896500D01*
G01X886500Y474800D02*
X891700D01*
G01X886500Y474600D02*
X891700D01*
G01X886500Y474400D02*
X891700D01*
G01X886500Y474200D02*
X891700D01*
G01X886500Y474000D02*
X891700D01*
G01X886500Y473800D02*
X891700D01*
G01X886500Y473600D02*
X891700D01*
G01X886500Y473400D02*
X891700D01*
G01X886500Y473200D02*
X891700D01*
G01X886500Y473000D02*
X891700D01*
G01X886500Y472800D02*
X891700D01*
G01X886500Y472600D02*
X891700D01*
G01X886500Y472400D02*
X891700D01*
G01X886500Y472200D02*
X891700D01*
G01X886500Y472000D02*
X891700D01*
G01X886500Y471800D02*
X891700D01*
G01X886500Y471600D02*
X891700D01*
G01X886500Y471400D02*
X891700D01*
G01X886500Y471200D02*
X891700D01*
G01X886500Y471000D02*
X891700D01*
G01X886500Y470800D02*
X891700D01*
G01X886500Y470600D02*
X891700D01*
G01X886500Y470400D02*
X891700D01*
G01X871500Y470200D02*
X879900D01*
G01X871900Y470000D02*
X879500D01*
G01X872500Y469800D02*
X878900D01*
G01X873100Y469600D02*
X878300D01*
G01X874300Y469400D02*
X877300D01*
G01X886500Y470200D02*
X891700D01*
G01X886500Y470000D02*
X891700D01*
G01X886500Y469800D02*
X891700D01*
G01X867900Y483000D02*
X883100D01*
G01X867900Y482800D02*
X874500D01*
G01X867700Y482600D02*
X874100D01*
G01X867700Y482400D02*
X873700D01*
G01X867500Y482200D02*
X873500D01*
G01X867500Y482000D02*
X873300D01*
G01X867500Y481800D02*
X873100D01*
G01X867300Y481600D02*
X872900D01*
G01X867300Y481400D02*
X872700D01*
G01X867300Y481200D02*
X872700D01*
G01X867300Y481000D02*
X872700D01*
G01X867100Y480800D02*
X872500D01*
G01X867100Y480600D02*
X872500D01*
G01X867100Y480400D02*
X872500D01*
G01X867100Y480200D02*
X872300D01*
G01X867100Y480000D02*
X872300D01*
G01X867100Y479800D02*
X872300D01*
G01X866900Y479600D02*
X872300D01*
G01X866900Y479400D02*
X872300D01*
G01X866900Y479200D02*
X872300D01*
G01X866900Y479000D02*
X872300D01*
G01X866900Y478800D02*
X872100D01*
G01X866900Y478600D02*
X872100D01*
G01X866900Y478400D02*
X872100D01*
G01X866900Y478200D02*
X872100D01*
G01X866900Y478000D02*
X872100D01*
G01X866900Y477800D02*
X872100D01*
G01X866900Y477600D02*
X872300D01*
G01X866900Y477400D02*
X872300D01*
G01X866900Y477200D02*
X872300D01*
G01X866900Y477000D02*
X872300D01*
G01X867100Y476800D02*
X872300D01*
G01X867100Y476600D02*
X872300D01*
G01X867100Y476400D02*
X872300D01*
G01X867100Y476200D02*
X872500D01*
G01X867100Y476000D02*
X872500D01*
G01X867100Y475800D02*
X872500D01*
G01X867300Y475600D02*
X872700D01*
G01X867300Y475400D02*
X872700D01*
G01X867300Y475200D02*
X872900D01*
G01X867300Y475000D02*
X872900D01*
G01X867500Y474800D02*
X873100D01*
G01X867500Y474600D02*
X873300D01*
G01X867500Y474400D02*
X873500D01*
G01X867700Y474200D02*
X873700D01*
G01X867700Y474000D02*
X874100D01*
G01X867900Y473800D02*
X874700D01*
G01X867900Y473600D02*
X883300D01*
G01X915100Y486800D02*
X920300D01*
G01X915100Y486600D02*
X920300D01*
G01X915100Y486400D02*
X920300D01*
G01X915100Y486200D02*
X920300D01*
G01X915100Y486000D02*
X920300D01*
G01X915100Y485800D02*
X920300D01*
G01X915100Y485600D02*
X920300D01*
G01X915100Y485400D02*
X920300D01*
G01X925300D02*
X934700D01*
G01X915100Y485200D02*
X920300D01*
G01X925100D02*
X934900D01*
G01X915100Y485000D02*
X920300D01*
G01X924900D02*
X935100D01*
G01X915100Y484800D02*
X920300D01*
G01X924700D02*
X935300D01*
G01X915100Y484600D02*
X920300D01*
G01X924500D02*
X935500D01*
G01X915100Y484400D02*
X920300D01*
G01X924500D02*
X935500D01*
G01X915100Y484200D02*
X920300D01*
G01X924300D02*
X935700D01*
G01X915100Y484000D02*
X920300D01*
G01X924100D02*
X935900D01*
G01X915100Y483800D02*
X920300D01*
G01X924100D02*
X935900D01*
G01X915100Y483600D02*
X920300D01*
G01X923900D02*
X936100D01*
G01X915100Y483400D02*
X920300D01*
G01X923700D02*
X936100D01*
G01X915100Y483200D02*
X920300D01*
G01X923700D02*
X936300D01*
G01X915100Y483000D02*
X920300D01*
G01X923700D02*
X929100D01*
G01X915100Y482800D02*
X920300D01*
G01X923500D02*
X928700D01*
G01X915100Y482600D02*
X920300D01*
G01X923500D02*
X928500D01*
G01X915100Y482400D02*
X920300D01*
G01X923300D02*
X928300D01*
G01X915100Y482200D02*
X920300D01*
G01X923300D02*
X928100D01*
G01X915100Y482000D02*
X920300D01*
G01X923300D02*
X928100D01*
G01X915100Y481800D02*
X920300D01*
G01X923100D02*
X927900D01*
G01X915100Y481600D02*
X920300D01*
G01X923100D02*
X927900D01*
G01X915100Y481400D02*
X920300D01*
G01X923100D02*
X927900D01*
G01X915100Y481200D02*
X920300D01*
G01X923100D02*
X927700D01*
G01X915100Y481000D02*
X920300D01*
G01X923100D02*
X927700D01*
G01X915100Y480800D02*
X920300D01*
G01X922900D02*
X927700D01*
G01X915100Y480600D02*
X920300D01*
G01X922900D02*
X927700D01*
G01X915100Y480400D02*
X920300D01*
G01X922900D02*
X927700D01*
G01X915100Y480200D02*
X920300D01*
G01X922900D02*
X927700D01*
G01X915100Y480000D02*
X920300D01*
G01X922900D02*
X927500D01*
G01X915100Y479800D02*
X920300D01*
G01X922900D02*
X927500D01*
G01X915100Y479600D02*
X920300D01*
G01X922900D02*
X927500D01*
G01X915100Y479400D02*
X920300D01*
G01X922700D02*
X927500D01*
G01X915100Y479200D02*
X920300D01*
G01X922700D02*
X927500D01*
G01X915100Y479000D02*
X920300D01*
G01X922700D02*
X927500D01*
G01X915100Y478800D02*
X920300D01*
G01X922700D02*
X927500D01*
G01X915100Y478600D02*
X920300D01*
G01X922700D02*
X927500D01*
G01X915100Y478400D02*
X920300D01*
G01X922700D02*
X927500D01*
G01X915100Y478200D02*
X920300D01*
G01X922700D02*
X927500D01*
G01X915100Y478000D02*
X920300D01*
G01X922700D02*
X927500D01*
G01X915100Y477800D02*
X920300D01*
G01X922700D02*
X927500D01*
G01X915100Y477600D02*
X920300D01*
G01X922700D02*
X927500D01*
G01X915100Y477400D02*
X920300D01*
G01X922700D02*
X927500D01*
G01X915100Y477200D02*
X920300D01*
G01X922700D02*
X927500D01*
G01X915100Y477000D02*
X920300D01*
G01X922700D02*
X927500D01*
G01X915100Y476800D02*
X920300D01*
G01X922700D02*
X927500D01*
G01X915100Y476600D02*
X920300D01*
G01X922900D02*
X927500D01*
G01X915100Y476400D02*
X920300D01*
G01X922900D02*
X927500D01*
G01X915100Y476200D02*
X920300D01*
G01X922900D02*
X927700D01*
G01X915100Y476000D02*
X920300D01*
G01X922900D02*
X927700D01*
G01X915100Y475800D02*
X920300D01*
G01X922900D02*
X927700D01*
G01X915100Y475600D02*
X920300D01*
G01X922900D02*
X927700D01*
G01X915100Y475400D02*
X920300D01*
G01X922900D02*
X927700D01*
G01X914900Y475200D02*
X920300D01*
G01X923100D02*
X927700D01*
G01X914900Y475000D02*
X920300D01*
G01X923100D02*
X927900D01*
G01X914900Y474800D02*
X920300D01*
G01X923100D02*
X927900D01*
G01X914700Y474600D02*
X920300D01*
G01X923100D02*
X927900D01*
G01X914500Y474400D02*
X920300D01*
G01X923100D02*
X928100D01*
G01X914300Y474200D02*
X920100D01*
G01X923300D02*
X928100D01*
G01X914100Y474000D02*
X920100D01*
G01X923300D02*
X928300D01*
G01X913500Y473800D02*
X920100D01*
G01X923300D02*
X928500D01*
G01X923500Y473600D02*
X928700D01*
G01X923500Y473400D02*
X929100D01*
G01X923700Y473200D02*
X936300D01*
G01X923700Y473000D02*
X936300D01*
G01X923700Y472800D02*
X936100D01*
G01X923900Y472600D02*
X936100D01*
G01X924100Y472400D02*
X935900D01*
G01X924100Y472200D02*
X935900D01*
G01X924300Y472000D02*
X935700D01*
G01X924500Y471800D02*
X935500D01*
G01X924500Y471600D02*
X935500D01*
G01X924700Y471400D02*
X935300D01*
G01X924900Y471200D02*
X935100D01*
G01X925100Y471000D02*
X934900D01*
G01X925300Y470800D02*
X934700D01*
G01X910700Y469400D02*
X914100D01*
G01X931700Y482400D02*
X936700D01*
G01X931900Y482200D02*
X936700D01*
G01X931900Y482000D02*
X936700D01*
G01X932100Y481800D02*
X936700D01*
G01X932100Y481600D02*
X936900D01*
G01X932100Y481400D02*
X936900D01*
G01X932300Y481200D02*
X936900D01*
G01X932300Y481000D02*
X936900D01*
G01X932300Y480800D02*
X937100D01*
G01X932300Y480600D02*
X937100D01*
G01X932300Y480400D02*
X937100D01*
G01X932300Y480200D02*
X937100D01*
G01X932300Y480000D02*
X937100D01*
G01X932500Y479800D02*
X937100D01*
G01X932500Y479600D02*
X937100D01*
G01X932500Y479400D02*
X937100D01*
G01X932500Y479200D02*
X937300D01*
G01X932500Y479000D02*
X937300D01*
G01X932500Y478800D02*
X937300D01*
G01X932500Y478600D02*
X937300D01*
G01X932500Y478400D02*
X937300D01*
G01X932500Y478200D02*
X937300D01*
G01X932500Y478000D02*
X937300D01*
G01X932500Y477800D02*
X937300D01*
G01X932500Y477600D02*
X937300D01*
G01X932500Y477400D02*
X937300D01*
G01X932500Y477200D02*
X937300D01*
G01X932500Y477000D02*
X937300D01*
G01X932500Y476800D02*
X937100D01*
G01X932500Y476600D02*
X937100D01*
G01X932500Y476400D02*
X937100D01*
G01X932300Y476200D02*
X937100D01*
G01X932300Y476000D02*
X937100D01*
G01X932300Y475800D02*
X937100D01*
G01X932300Y475600D02*
X937100D01*
G01X932300Y475400D02*
X937100D01*
G01X932300Y475200D02*
X936900D01*
G01X932100Y475000D02*
X936900D01*
G01X932100Y474800D02*
X936900D01*
G01X932100Y474600D02*
X936900D01*
G01X931900Y474400D02*
X936700D01*
G01X931900Y474200D02*
X936700D01*
G01X931700Y474000D02*
X936700D01*
G01X930900Y483000D02*
X936300D01*
G01X931300Y482800D02*
X936500D01*
G01X931500Y482600D02*
X936500D01*
G01X931500Y473800D02*
X936700D01*
G01X931300Y473600D02*
X936500D01*
G01X930900Y473400D02*
X936500D01*
G01X928700Y486800D02*
X931300D01*
G01X927700Y486600D02*
X932300D01*
G01X927100Y486400D02*
X932900D01*
G01X926700Y486200D02*
X933300D01*
G01X926300Y486000D02*
X933700D01*
G01X925900Y485800D02*
X934100D01*
G01X925700Y485600D02*
X934300D01*
G01X925700Y470600D02*
X934300D01*
G01X925900Y470400D02*
X934100D01*
G01X926300Y470200D02*
X933700D01*
G01X926700Y470000D02*
X933300D01*
G01X927100Y469800D02*
X932900D01*
G01X927700Y469600D02*
X932300D01*
G01X928700Y469400D02*
X931300D01*
G01X1214125Y124174D02*
G03I-500J0D01*
G01X1277241Y131396D02*
G03I-500J0D01*
G01X1225869Y121272D02*
G03I-500J0D01*
G01X1232473Y139915D02*
G03I-500J0D01*
G01X1252670Y189900D02*
G03I-499J0D01*
G01X1252671D02*
G03I-500J0D01*
G01X1342793Y507626D02*
G03I-500J0D01*
G01X1374696Y5180D02*
G03I-500J0D01*
G01X1366384Y73247D02*
G03I-500J0D01*
G01X1375007Y37204D02*
G03I-500J0D01*
G01X1351180Y96793D02*
G03I-500J0D01*
G01X1377314Y396072D02*
G03I-500J0D01*
G01X1381340Y586735D02*
G03I-500J0D01*
G01X1379007Y615260D02*
G03I-500J0D01*
G01X1435621Y187080D02*
G03I-500J0D01*
G01X1468040Y361160D02*
X1460540D01*
Y368660D01*
X1468040Y361160D01*
G01X1456150Y359600D02*
G03I-500J0D01*
G01X1435367Y429363D02*
G03I-500J0D01*
G01X1406176Y531208D02*
G03I-500J0D01*
G01X1494894Y66602D02*
G03I-500J0D01*
G01X1497935Y265998D02*
G03I-500J0D01*
G01X1520163Y330952D02*
G03I-500J0D01*
G01X1503069Y316819D02*
G03I-500J0D01*
G01X1515125Y311313D02*
G03I-500J0D01*
G01X1470225Y614278D02*
G03I-500J0D01*
G01X1505763Y615546D02*
G03I-500J0D01*
G01X1585360Y9109D02*
G03I-500J0D01*
G01X1574115Y175292D02*
G03I-500J0D01*
G01X1539432Y276605D02*
G03I-500J0D01*
G01X1562697Y299124D02*
G03I-500J0D01*
G01X1575672Y336018D02*
G03I-500J0D01*
G01X1580560Y579108D02*
G03I-499J0D01*
G01X1549816Y592753D02*
G03I-500J0D01*
G01X1627866Y68437D02*
G03I-500J0D01*
G01X1626710Y199868D02*
G03I-500J0D01*
G01X1636537Y210183D02*
G03I-500J0D01*
G01X1642620Y226830D02*
G03I-500J0D01*
G01X1648244Y228318D02*
G03I-500J0D01*
G01X1648150Y332359D02*
G03I-500J0D01*
G01X1590859Y334850D02*
G03I-500J0D01*
G01X1608402Y398144D02*
G03I-500J0D01*
G01X1642712Y347786D02*
G03I-500J0D01*
G01X1708859Y86518D02*
G03I-500J0D01*
G01X1688526Y192100D02*
G03I-500J0D01*
G01X1663886Y210364D02*
G03I-500J0D01*
G01X1658850Y310141D02*
G03I-500J0D01*
G01X1755200Y49150D02*
G03I-500J0D01*
G01X1717374Y519714D02*
G03I-500J0D01*
G01X1723740Y488546D02*
G03I-500J0D01*
G01X1729464Y579982D02*
G03I-500J0D01*
G01X1739885Y589689D02*
G03I-500J0D01*
G01X1779759Y94580D02*
G03I-499J0D01*
G01X1791797Y133463D02*
G03I-500J0D01*
G01X1794097Y104896D02*
G03I-500J0D01*
G01X1804075Y123242D02*
G03I-500J0D01*
G01X1810059Y165080D02*
G03I-499J0D01*
G01X1833200Y537650D02*
G03I-500J0D01*
G01X1780318Y553639D02*
G03I-500J0D01*
G01X1777622Y579462D02*
G03I-500J0D01*
G01X1785659Y623050D02*
G03I-500J0D01*
G01X1838289Y-13221D02*
G03I-500J0D01*
G01X1849347Y86953D02*
G03I-499J0D01*
G01X1873183Y155721D02*
G03I-500J0D01*
G01X1851978Y99592D02*
G03I-500J0D01*
G01X1845526Y148102D02*
G03I-499J0D01*
G01X1868350Y543500D02*
G03I-500J0D01*
G01X1879050Y578100D02*
G03I-500J0D01*
G01X1932795Y77162D02*
G03I-500J0D01*
G01X1916383Y122997D02*
G03I-500J0D01*
G01X1953162Y106892D02*
G03I-500J0D01*
G01X1929731Y142600D02*
G03I-500J0D01*
G01X1927924Y156974D02*
G03I-500J0D01*
G01X1921900Y490710D02*
G03I-500J0D01*
G01X1934721Y587350D02*
G03I-500J0D01*
G01X1922567Y584574D02*
G03I-500J0D01*
G01X1901159Y551450D02*
G03I-500J0D01*
G01X1922850Y536250D02*
G03I-500J0D01*
G01X1922567Y620768D02*
G03I-500J0D01*
G54D21*
G01X1416296Y130918D02*
G02X1416528Y130822I0J-328D01*
G02X1416606Y130634I-188J-188D01*
G01Y130256D01*
G02X1416534Y130082I-246J0D01*
G02X1416331Y129998I-203J203D01*
G01X1412499D01*
Y129115D01*
X1412523Y129091D01*
G01X1412609Y130992D02*
X1412698Y130903D01*
X1416325Y130912D01*
G54D12*
G01X-19522Y465950D02*
Y458250D01*
G01X-20488Y447094D02*
X21512D01*
G01X-2130Y31810D02*
Y23210D01*
G01X20100Y90200D02*
Y85200D01*
G01X-2030Y46850D02*
Y38250D01*
G01X83980Y158531D02*
X125980D01*
G01X116214Y115903D02*
X122414D01*
G01X430749Y-124922D02*
G02I-12000J0D01*
G01X425599D02*
G02I-6850J0D01*
G01X434749D02*
X402749D01*
G01X434749Y-140922D02*
Y-220922D01*
G01D02*
X1729349D01*
G01X434749Y-176422D02*
X1729349D01*
G01X418749Y-140922D02*
Y-108922D01*
G01X434749Y-140922D02*
X1729349D01*
G01X716195Y89488D02*
X722395D01*
G01X712595Y240280D02*
X717595D01*
G01X721104Y233224D02*
X726104D01*
G01X695561Y232214D02*
X690561D01*
G01X724992Y530743D02*
Y525743D01*
G01X726068Y38402D02*
Y33402D01*
G01X729844Y233243D02*
X734844D01*
G01X738555Y238036D02*
X743555D01*
G01X733037Y493195D02*
X739237D01*
G01X898700Y421600D02*
X836600D01*
G01X819800D02*
X810101D01*
X810100Y421601D01*
Y467399D01*
X810101Y467400D01*
X960900D01*
Y421601D01*
X960899Y421600D01*
G01X941849Y-140922D02*
Y-220922D01*
G01X960899Y421600D02*
X931900D01*
G01X1079349Y-140922D02*
Y-220922D01*
G01X1194349Y-140922D02*
Y-220922D01*
G01X1397560Y275165D02*
X1287324D01*
G01D02*
Y255480D01*
G01D02*
X1397560D01*
G01X1287324D02*
X1397560D01*
G01X1287324Y275165D02*
Y255480D01*
G01X1397560Y275165D02*
X1287324D01*
G01X1397560D02*
X1287324D01*
G01D02*
Y255480D01*
G01D02*
X1397560D01*
G01X1287324D02*
X1397560D01*
G01X1287324Y275165D02*
Y255480D01*
G01X1397560Y275165D02*
X1287324D01*
G01X1397560D02*
X1287324D01*
G01D02*
Y255480D01*
G01D02*
X1397560D01*
G01X1287324D02*
X1397560D01*
G01X1287324Y275165D02*
Y255480D01*
G01X1397560Y275165D02*
X1287324D01*
G01X1397560D02*
X1287324D01*
G01D02*
Y255480D01*
G01D02*
X1397560D01*
G01X1287324D02*
X1397560D01*
G01X1287324Y275165D02*
Y255480D01*
G01X1397560Y275165D02*
X1287324D01*
G01X1397560D02*
X1287324D01*
G01D02*
Y255480D01*
G01D02*
X1397560D01*
G01X1287324D02*
X1397560D01*
G01X1287324Y275165D02*
Y255480D01*
G01X1397560Y275165D02*
X1287324D01*
G01X1397560D02*
X1287324D01*
G01D02*
Y255480D01*
G01D02*
X1397560D01*
G01X1287324D02*
X1397560D01*
G01X1287324Y275165D02*
Y255480D01*
G01X1397560Y275165D02*
X1287324D01*
G01X1397560D02*
X1287324D01*
G01D02*
Y255480D01*
G01D02*
X1397560D01*
G01X1287324D02*
X1397560D01*
G01X1287324Y275165D02*
Y255480D01*
G01X1397560Y275165D02*
X1287324D01*
G01X1397560D02*
X1287324D01*
G01D02*
Y255480D01*
G01D02*
X1397560D01*
G01X1287324D02*
X1397560D01*
G01X1287324Y275165D02*
Y255480D01*
G01X1397560Y275165D02*
X1287324D01*
G01X1397560D02*
X1287324D01*
G01D02*
Y255480D01*
G01D02*
X1397560D01*
G01X1287324D02*
X1397560D01*
G01X1287324Y275165D02*
Y255480D01*
G01X1397560Y275165D02*
X1287324D01*
G01X1397560D02*
X1287324D01*
G01D02*
Y255480D01*
G01D02*
X1397560D01*
G01X1287324D02*
X1397560D01*
G01X1287324Y275165D02*
Y255480D01*
G01X1397560Y275165D02*
X1287324D01*
G01X1287552Y306777D02*
Y287092D01*
G01D02*
X1397788D01*
G01Y306777D02*
X1287552D01*
G01X1397958Y338777D02*
Y319092D01*
X1287722D01*
Y338777D01*
X1397958D01*
G01D02*
Y319092D01*
X1287722D01*
Y338777D01*
X1397958D01*
G01X1397788Y306777D02*
X1287552D01*
G01Y287092D02*
X1397788D01*
G01X1287552Y306777D02*
Y287092D01*
G01Y306777D02*
Y287092D01*
G01D02*
X1397788D01*
G01Y306777D02*
X1287552D01*
G01X1397958Y338777D02*
Y319092D01*
X1287722D01*
Y338777D01*
X1397958D01*
G01D02*
Y319092D01*
X1287722D01*
Y338777D01*
X1397958D01*
G01X1397788Y306777D02*
X1287552D01*
G01Y287092D02*
X1397788D01*
G01X1287552Y306777D02*
Y287092D01*
G01Y306777D02*
Y287092D01*
G01D02*
X1397788D01*
G01Y306777D02*
X1287552D01*
G01X1397958Y338777D02*
Y319092D01*
X1287722D01*
Y338777D01*
X1397958D01*
G01D02*
Y319092D01*
X1287722D01*
Y338777D01*
X1397958D01*
G01X1397788Y306777D02*
X1287552D01*
G01Y287092D02*
X1397788D01*
G01X1287552Y306777D02*
Y287092D01*
G01Y306777D02*
Y287092D01*
G01D02*
X1397788D01*
G01Y306777D02*
X1287552D01*
G01X1397958Y338777D02*
Y319092D01*
X1287722D01*
Y338777D01*
X1397958D01*
G01D02*
Y319092D01*
X1287722D01*
Y338777D01*
X1397958D01*
G01X1397788Y306777D02*
X1287552D01*
G01Y287092D02*
X1397788D01*
G01X1287552Y306777D02*
Y287092D01*
G01Y306777D02*
Y287092D01*
G01D02*
X1397788D01*
G01Y306777D02*
X1287552D01*
G01X1397958Y338777D02*
Y319092D01*
X1287722D01*
Y338777D01*
X1397958D01*
G01D02*
Y319092D01*
X1287722D01*
Y338777D01*
X1397958D01*
G01X1397788Y306777D02*
X1287552D01*
G01Y287092D02*
X1397788D01*
G01X1287552Y306777D02*
Y287092D01*
G01Y306777D02*
Y287092D01*
G01D02*
X1397788D01*
G01Y306777D02*
X1287552D01*
G01X1397958Y338777D02*
Y319092D01*
X1287722D01*
Y338777D01*
X1397958D01*
G01D02*
Y319092D01*
X1287722D01*
Y338777D01*
X1397958D01*
G01X1397788Y306777D02*
X1287552D01*
G01Y287092D02*
X1397788D01*
G01X1287552Y306777D02*
Y287092D01*
G01Y306777D02*
Y287092D01*
G01D02*
X1397788D01*
G01Y306777D02*
X1287552D01*
G01X1397958Y338777D02*
Y319092D01*
X1287722D01*
Y338777D01*
X1397958D01*
G01D02*
Y319092D01*
X1287722D01*
Y338777D01*
X1397958D01*
G01X1397788Y306777D02*
X1287552D01*
G01Y287092D02*
X1397788D01*
G01X1287552Y306777D02*
Y287092D01*
G01Y306777D02*
Y287092D01*
G01D02*
X1397788D01*
G01Y306777D02*
X1287552D01*
G01X1397958Y338777D02*
Y319092D01*
X1287722D01*
Y338777D01*
X1397958D01*
G01D02*
Y319092D01*
X1287722D01*
Y338777D01*
X1397958D01*
G01X1397788Y306777D02*
X1287552D01*
G01Y287092D02*
X1397788D01*
G01X1287552Y306777D02*
Y287092D01*
G01Y306777D02*
Y287092D01*
G01D02*
X1397788D01*
G01Y306777D02*
X1287552D01*
G01X1397958Y338777D02*
Y319092D01*
X1287722D01*
Y338777D01*
X1397958D01*
G01D02*
Y319092D01*
X1287722D01*
Y338777D01*
X1397958D01*
G01X1397788Y306777D02*
X1287552D01*
G01Y287092D02*
X1397788D01*
G01X1287552Y306777D02*
Y287092D01*
G01Y306777D02*
Y287092D01*
G01D02*
X1397788D01*
G01Y306777D02*
X1287552D01*
G01X1397958Y338777D02*
Y319092D01*
X1287722D01*
Y338777D01*
X1397958D01*
G01D02*
Y319092D01*
X1287722D01*
Y338777D01*
X1397958D01*
G01X1397788Y306777D02*
X1287552D01*
G01Y287092D02*
X1397788D01*
G01X1287552Y306777D02*
Y287092D01*
G01X1361849Y-140922D02*
Y-220922D01*
G01X1386795Y103589D02*
Y98589D01*
G01X1377304Y212318D02*
X1487540D01*
Y192633D01*
X1377304D01*
Y212318D01*
G01X1397560Y255480D02*
Y275165D01*
G01Y255480D02*
Y275165D01*
G01Y255480D02*
Y275165D01*
G01Y255480D02*
Y275165D01*
G01Y255480D02*
Y275165D01*
G01Y255480D02*
Y275165D01*
G01Y255480D02*
Y275165D01*
G01Y255480D02*
Y275165D01*
G01Y255480D02*
Y275165D01*
G01Y255480D02*
Y275165D01*
G01Y255480D02*
Y275165D01*
G01Y255480D02*
Y275165D01*
G01Y255480D02*
Y275165D01*
G01Y255480D02*
Y275165D01*
G01Y255480D02*
Y275165D01*
G01Y255480D02*
Y275165D01*
G01Y255480D02*
Y275165D01*
G01Y255480D02*
Y275165D01*
G01Y255480D02*
Y275165D01*
G01Y255480D02*
Y275165D01*
G01X1397788Y287092D02*
Y306777D01*
G01Y287092D02*
Y306777D01*
G01Y287092D02*
Y306777D01*
G01Y287092D02*
Y306777D01*
G01Y287092D02*
Y306777D01*
G01Y287092D02*
Y306777D01*
G01Y287092D02*
Y306777D01*
G01Y287092D02*
Y306777D01*
G01Y287092D02*
Y306777D01*
G01Y287092D02*
Y306777D01*
G01Y287092D02*
Y306777D01*
G01Y287092D02*
Y306777D01*
G01Y287092D02*
Y306777D01*
G01Y287092D02*
Y306777D01*
G01Y287092D02*
Y306777D01*
G01Y287092D02*
Y306777D01*
G01Y287092D02*
Y306777D01*
G01Y287092D02*
Y306777D01*
G01Y287092D02*
Y306777D01*
G01Y287092D02*
Y306777D01*
G01X1369500Y410500D02*
X1374500D01*
G01X1361500D02*
X1366500D01*
G01X1382000Y514500D02*
Y509500D01*
G01X1408222Y118160D02*
X1414004Y118876D01*
X1413813Y119784D01*
X1410850Y118876D01*
X1415605Y119378D01*
X1416107Y119474D01*
X1414817Y120382D01*
X1416131Y120621D01*
X1415963Y126068D01*
X1415032Y125901D01*
X1414888Y121576D01*
X1414004Y125567D01*
X1407099Y122962D01*
X1406955Y121505D01*
X1412714Y123798D01*
G01X1407123Y109869D02*
X1407051Y117420D01*
X1412881Y118519D01*
X1408078Y116942D01*
X1407242Y115915D01*
X1407768Y109917D01*
X1411830Y111423D01*
X1409106Y111494D01*
X1412021Y112641D01*
X1411543Y113525D01*
X1411495Y116703D01*
X1411997Y116990D01*
X1412642Y114242D01*
X1416298Y113477D01*
X1416274Y114815D01*
X1413455Y115485D01*
G01X1444054Y582339D02*
X1439054D01*
G01X1454014Y615161D02*
X1459014D01*
G01X1446014D02*
X1451014D01*
G01X1438014D02*
X1443014D01*
G01X1460500Y601000D02*
Y596000D01*
G01X1521700Y257100D02*
X1516700D01*
G01X1529400D02*
X1524400D01*
G01X1518150Y271200D02*
X1523150D01*
G01X1525950D02*
X1530950D01*
G01X1531849Y-140922D02*
Y-220922D01*
G01X1603386Y98836D02*
X1597086D01*
Y105136D01*
G01X1606440Y227535D02*
X1601440D01*
G01X1598840D02*
X1593840D01*
G01X1591265Y235647D02*
Y252247D01*
G01X1649000Y425110D02*
Y417410D01*
G01X1702620Y72500D02*
Y64500D01*
G01X1729349Y-140922D02*
Y-220922D01*
G01X1757349Y-124922D02*
G02I-12000J0D01*
G01X1752199D02*
G02I-6850J0D01*
G01X1745349Y-140922D02*
Y-108922D01*
G01X1761349Y-124922D02*
X1729349D01*
G01X1750750Y100947D02*
Y94647D01*
X1744450D01*
G01X1747253Y103159D02*
Y96859D01*
X1740953D01*
G01X1816900Y79100D02*
X1800300D01*
G01X1795100D02*
X1778500D01*
G01X1876641Y88212D02*
X1871641D01*
G01X1884400Y88200D02*
X1879400D01*
G01X1899400Y83300D02*
X1894400D01*
G01X1859170Y106600D02*
X1864170D01*
G01X1932218Y219975D02*
X1927218D01*
G01X1940991Y219942D02*
X1935991D01*
G01X1936400Y236000D02*
X1941400D01*
G01X1928100D02*
X1933100D01*
G54D22*
G01X1408512Y113189D02*
X1408495Y115823D01*
X1410591Y116649D01*
Y113262D01*
X1408524Y112480D01*
X1408509Y113320D01*
G01X1413752Y120943D02*
X1406521Y118344D01*
G03X1406198Y118156I349J-971D01*
G01X1413202Y123105D02*
X1413919Y123129D01*
X1413901Y120662D01*
G01X1406196Y118077D02*
X1406197Y110017D01*
G03X1407582Y108919I1128J0D01*
G01X1412190Y110530D01*
G03X1412919Y111533I-359J1028D01*
G01Y113276D01*
X1417108Y112368D01*
Y115721D01*
X1412893Y116533D01*
Y117392D01*
X1417095Y118920D01*
X1417092Y126177D01*
G03X1416091Y127091I-918J0D01*
G01X1415410D01*
X1406203Y123745D01*
Y120406D01*
X1414152Y123440D01*
G01X1413465Y134822D02*
G03X1412952Y134536I0J-603D01*
G03X1412856Y133724I824J-509D01*
G02X1412868Y133378I-588J-194D01*
G03X1413537Y132995I388J-98D01*
G02X1414014Y132984I233J-233D01*
G01X1414635Y133557D01*
X1415268Y134667D01*
X1416390D01*
X1416844Y134512D01*
X1416880Y133688D01*
X1416784Y133163D01*
X1416486Y132876D01*
X1416271Y132852D01*
G01X1413714Y135042D02*
Y134391D01*
X1413571D01*
G03X1413087Y134081I0J-533D01*
G03X1413666Y133287I511J-235D01*
G03X1414347Y133752I-108J890D01*
G03X1414922Y134845I-55458J29873D01*
G01X1415789Y134393D02*
X1416380D01*
G02X1416583Y134309I0J-287D01*
G01X1416666Y134226D01*
G02X1416702Y134139I-87J-87D01*
G01Y133695D01*
G02X1416575Y133387I-435J-1D01*
G01X1416446Y133259D01*
G02X1416301Y133199I-145J145D01*
G01X1415902D01*
Y132507D01*
X1416362D01*
G03X1417197Y133342I0J835D01*
G01Y134319D01*
G03X1416421Y135095I-776J0D01*
G01X1415376D01*
G03X1414839Y134558I0J-537D01*
G01Y133328D01*
G01X1413712Y135114D02*
X1413495D01*
G03X1412805Y134828I0J-975D01*
G01X1412788Y134811D01*
G03X1412602Y134362I449J-449D01*
G01Y133264D01*
G03X1412671Y133099I234J1D01*
G01X1412703Y133066D01*
G03X1413826Y132601I1123J1124D01*
G01X1413885D01*
G03X1414578Y132888I0J980D01*
G01X1414956Y133266D01*
G03X1415586Y135109I-1564J1564D01*
G01X1412734Y129647D02*
X1416520D01*
X1416734Y129861D01*
Y131031D01*
X1416519Y131246D01*
X1413081D01*
G01X1412595Y129193D02*
X1416342D01*
G03X1417003Y129467I0J934D01*
G03X1417218Y129986I-519J519D01*
G01Y131020D01*
G03X1417137Y131214I-275J-1D01*
G01X1416728Y131624D01*
G03X1416322Y131792I-406J-407D01*
G01X1412609D01*
Y130992D01*
G01X1413793Y108026D02*
X1413184D01*
X1412909Y107751D01*
Y106426D01*
X1413160Y106175D01*
X1416551D01*
X1416980Y106604D01*
Y107656D01*
X1416551Y108085D01*
X1415882D01*
G01X1413971Y107704D02*
X1413744D01*
G03X1413210Y107483I0J-756D01*
G03X1413094Y107203I280J-280D01*
G01Y106987D01*
G03X1413589Y106492I495J0D01*
G01X1416306D01*
G03X1416706Y106892I0J400D01*
G01Y107148D01*
G03X1416156Y107698I-550J0D01*
G01X1415601D01*
Y108486D01*
X1415613Y108498D01*
X1416151D01*
G02X1417176Y107936I0J-1216D01*
G01X1417214Y107805D01*
X1417219Y107800D01*
Y106623D01*
G02X1416297Y105701I-922J0D01*
G01X1413423D01*
G02X1412599Y106525I0J824D01*
G01Y107743D01*
G02X1413256Y108400I657J0D01*
G01X1414020D01*
Y107733D01*
X1413992Y107705D01*
G54D13*
G01X1435621Y187080D02*
G03I-500J0D01*
G01X1494894Y66602D02*
G03I-500J0D01*
G01X1574115Y175292D02*
G03I-500J0D01*
G54D23*
G01X548049Y-193422D02*
Y-210922D01*
G01X543027Y-193422D02*
X553071D01*
G01X565549Y-199256D02*
Y-210922D01*
G01Y-194589D02*
X565112Y-194297D01*
Y-193714D01*
X565549Y-193422D01*
X565986Y-193714D01*
Y-194297D01*
X565549Y-194589D01*
G01X583049Y-210922D02*
X581739Y-210630D01*
X580429Y-209464D01*
X579555Y-207422D01*
X579119Y-205089D01*
X579555Y-202755D01*
X580429Y-200714D01*
X581739Y-199547D01*
X583049Y-199256D01*
X584359Y-199547D01*
X585669Y-200714D01*
X586542Y-202755D01*
X586761Y-205089D01*
X586542Y-207422D01*
X585669Y-209464D01*
X584359Y-210630D01*
X583049Y-210922D01*
G01X597492Y-215297D02*
X599021Y-216464D01*
X600767Y-216755D01*
X602295Y-216464D01*
X603606Y-215006D01*
X604479Y-212964D01*
Y-199256D01*
G01Y-201589D02*
X603606Y-200422D01*
X602295Y-199547D01*
X600767Y-199256D01*
X599021Y-199839D01*
X597929Y-201005D01*
X597055Y-203047D01*
X596619Y-205089D01*
X596837Y-206839D01*
X597711Y-208881D01*
X599021Y-210339D01*
X600767Y-210922D01*
X602077Y-210630D01*
X603606Y-209464D01*
X604479Y-208298D01*
G01X621979Y-210922D02*
Y-199256D01*
G01Y-201297D02*
X621106Y-200131D01*
X619795Y-199547D01*
X618267Y-199256D01*
X616739Y-199839D01*
X615429Y-201005D01*
X614555Y-202755D01*
X614119Y-205089D01*
X614555Y-207422D01*
X615429Y-209172D01*
X616739Y-210339D01*
X618267Y-210922D01*
X619795Y-210630D01*
X621106Y-209756D01*
X621979Y-208589D01*
G01X648682Y-210922D02*
Y-193422D01*
X653922D01*
X655669Y-194297D01*
X656979Y-196339D01*
X657416Y-198672D01*
X656979Y-201005D01*
X655887Y-202755D01*
X653922Y-203631D01*
X648682D01*
G01X674479Y-210922D02*
Y-199256D01*
G01Y-201297D02*
X673606Y-200131D01*
X672295Y-199547D01*
X670767Y-199256D01*
X669239Y-199839D01*
X667929Y-201005D01*
X667055Y-202755D01*
X666619Y-205089D01*
X667055Y-207422D01*
X667929Y-209172D01*
X669239Y-210339D01*
X670767Y-210922D01*
X672295Y-210630D01*
X673606Y-209756D01*
X674479Y-208589D01*
G01X684774Y-208881D02*
X685866Y-210047D01*
X687394Y-210922D01*
X688704D01*
X690014Y-210339D01*
X690887Y-209464D01*
X691324Y-208298D01*
X691106Y-206547D01*
X690232Y-205672D01*
X686302Y-203922D01*
X685429Y-201880D01*
X685866Y-200422D01*
X686739Y-199547D01*
X688049Y-199256D01*
X689359Y-199547D01*
X690669Y-200422D01*
G01X702274Y-208881D02*
X703366Y-210047D01*
X704894Y-210922D01*
X706204D01*
X707514Y-210339D01*
X708387Y-209464D01*
X708824Y-208298D01*
X708606Y-206547D01*
X707732Y-205672D01*
X703802Y-203922D01*
X702929Y-201880D01*
X703366Y-200422D01*
X704239Y-199547D01*
X705549Y-199256D01*
X706859Y-199547D01*
X708169Y-200422D01*
G01X735746Y-210922D02*
Y-193422D01*
X740112D01*
X741859Y-194297D01*
X743169Y-195464D01*
X744261Y-197213D01*
X745134Y-199256D01*
X745352Y-202172D01*
X745134Y-205089D01*
X744261Y-207131D01*
X743169Y-208881D01*
X741859Y-210047D01*
X740112Y-210922D01*
X735746D01*
G01X752590Y-193422D02*
X758049Y-210922D01*
X763508Y-193422D01*
G01X775549D02*
Y-210922D01*
G01X770527Y-193422D02*
X780571D01*
G01X804872Y-210922D02*
Y-193422D01*
X810549Y-208005D01*
X816226Y-193422D01*
Y-210922D01*
G01X829795Y-201589D02*
X830669Y-200714D01*
X831324Y-199256D01*
X831761Y-197213D01*
X831324Y-195464D01*
X830451Y-194297D01*
X828922Y-193422D01*
X823027D01*
Y-210922D01*
X830232D01*
X831761Y-209756D01*
X832634Y-208005D01*
X833071Y-205964D01*
X832634Y-203922D01*
X831324Y-202172D01*
X829795Y-201589D01*
X823027D01*
G01X577998Y202469D02*
X555397D01*
G01X577408Y264882D02*
X563304D01*
Y264868D01*
G01X577294Y249295D02*
X563190D01*
X560483D01*
G01X578842Y233649D02*
X564738D01*
X560637Y233648D01*
G01X578615Y218069D02*
X560837D01*
G01X575241Y327289D02*
X560279D01*
G01X576120Y311667D02*
X552007D01*
G01X576010Y296082D02*
X552007D01*
G01X577875Y280469D02*
X558827D01*
G01X577889Y395519D02*
X556992D01*
G01X577846Y389669D02*
X559825D01*
Y389674D01*
G01X577533Y374069D02*
X563494D01*
G01X575534Y358495D02*
X558162D01*
Y358478D01*
G01X574691Y342874D02*
X560300D01*
G01X576413Y405782D02*
X547824D01*
Y405787D01*
G01X647372Y-165922D02*
Y-148422D01*
X653049Y-163005D01*
X658726Y-148422D01*
Y-165922D01*
G01X670549D02*
X669239Y-165630D01*
X667929Y-164464D01*
X667055Y-162422D01*
X666619Y-160089D01*
X667055Y-157755D01*
X667929Y-155714D01*
X669239Y-154547D01*
X670549Y-154256D01*
X671859Y-154547D01*
X673169Y-155714D01*
X674042Y-157755D01*
X674261Y-160089D01*
X674042Y-162422D01*
X673169Y-164464D01*
X671859Y-165630D01*
X670549Y-165922D01*
G01X691979Y-148422D02*
Y-165922D01*
G01Y-163298D02*
X691106Y-164756D01*
X689795Y-165630D01*
X688267Y-165922D01*
X686521Y-165339D01*
X685211Y-163881D01*
X684337Y-162131D01*
X684119Y-160089D01*
X684337Y-158047D01*
X685211Y-156297D01*
X686521Y-154839D01*
X688267Y-154256D01*
X689795Y-154547D01*
X690887Y-155131D01*
X691979Y-156297D01*
G01X702274Y-158047D02*
X709261D01*
X708606Y-156005D01*
X707514Y-154839D01*
X705986Y-154256D01*
X704457Y-154547D01*
X703147Y-155422D01*
X702274Y-157464D01*
X701837Y-159214D01*
Y-160964D01*
X702274Y-162714D01*
X703366Y-164464D01*
X704676Y-165630D01*
X706204Y-165922D01*
X707732Y-165339D01*
X709261Y-163589D01*
G01X723049Y-165922D02*
Y-148422D01*
G01X975549Y-210922D02*
Y-193422D01*
X972929Y-196922D01*
G01Y-210922D02*
X978169D01*
G01X988246Y-208298D02*
X989555Y-209756D01*
X991084Y-210630D01*
X993049Y-210922D01*
X995014Y-210339D01*
X996542Y-209172D01*
X997634Y-207131D01*
X997852Y-204797D01*
X997416Y-202464D01*
X996324Y-201005D01*
X994795Y-199839D01*
X993267Y-199547D01*
X991739Y-199839D01*
X989774Y-201005D01*
X990429Y-193422D01*
X996324D01*
G01X1010549Y-210922D02*
Y-193422D01*
X1007929Y-196922D01*
G01Y-210922D02*
X1013169D01*
G01X1023901Y-196339D02*
X1025211Y-194589D01*
X1026739Y-193714D01*
X1028486Y-193422D01*
X1030669Y-194005D01*
X1032197Y-195464D01*
X1032634Y-197213D01*
X1032416Y-198964D01*
X1031542Y-200422D01*
X1027176Y-203339D01*
X1025211Y-205380D01*
X1023901Y-208298D01*
X1023464Y-210922D01*
X1032634D01*
G01X1041401Y-203631D02*
X1042929Y-201589D01*
X1044239Y-200422D01*
X1045986Y-199839D01*
X1047514Y-200422D01*
X1048606Y-201589D01*
X1049479Y-203339D01*
X1049697Y-205380D01*
X1049479Y-207131D01*
X1048606Y-208881D01*
X1047295Y-210339D01*
X1045767Y-210922D01*
X1044021Y-210339D01*
X1042492Y-208589D01*
X1041619Y-205964D01*
X1041401Y-203047D01*
X1041837Y-199256D01*
X1042492Y-197213D01*
X1043584Y-195172D01*
X1045112Y-193714D01*
X1046641Y-193422D01*
X1048169Y-194005D01*
X1049261Y-195464D01*
G01X962432Y-165922D02*
Y-148422D01*
X967672D01*
X969419Y-149297D01*
X970729Y-151339D01*
X971166Y-153672D01*
X970729Y-156005D01*
X969637Y-157755D01*
X967672Y-158631D01*
X962432D01*
G01X989102Y-149881D02*
X987792Y-149005D01*
X986264Y-148422D01*
X984517D01*
X982552Y-149297D01*
X981024Y-150755D01*
X979932Y-152506D01*
X979059Y-155422D01*
X978840Y-158047D01*
X979277Y-160672D01*
X979932Y-162422D01*
X981242Y-164172D01*
X982771Y-165339D01*
X984299Y-165922D01*
X985827D01*
X987356Y-165339D01*
X988666Y-164464D01*
X989758Y-163298D01*
G01X1003545Y-156589D02*
X1004419Y-155714D01*
X1005074Y-154256D01*
X1005511Y-152213D01*
X1005074Y-150464D01*
X1004201Y-149297D01*
X1002672Y-148422D01*
X996777D01*
Y-165922D01*
X1003982D01*
X1005511Y-164756D01*
X1006384Y-163005D01*
X1006821Y-160964D01*
X1006384Y-158922D01*
X1005074Y-157172D01*
X1003545Y-156589D01*
X996777D01*
G01X1012749Y-171755D02*
X1025849D01*
G01X1031777Y-165922D02*
Y-148422D01*
X1041821Y-165922D01*
Y-148422D01*
G01X1054299Y-165922D02*
X1052552Y-165630D01*
X1051024Y-164464D01*
X1049714Y-162714D01*
X1048840Y-160672D01*
X1048404Y-158339D01*
Y-156005D01*
X1048840Y-153672D01*
X1049714Y-151630D01*
X1051024Y-149881D01*
X1052552Y-148714D01*
X1054299Y-148422D01*
X1056045Y-148714D01*
X1057574Y-149881D01*
X1058884Y-151630D01*
X1059758Y-153672D01*
X1060194Y-156005D01*
Y-158339D01*
X1059758Y-160672D01*
X1058884Y-162714D01*
X1057574Y-164464D01*
X1056045Y-165630D01*
X1054299Y-165922D01*
G01X1128099Y-210922D02*
Y-193422D01*
X1125479Y-196922D01*
G01Y-210922D02*
X1130719D01*
G01X1147345Y-201589D02*
X1148219Y-200714D01*
X1148874Y-199256D01*
X1149311Y-197213D01*
X1148874Y-195464D01*
X1148001Y-194297D01*
X1146472Y-193422D01*
X1140577D01*
Y-210922D01*
X1147782D01*
X1149311Y-209756D01*
X1150184Y-208005D01*
X1150621Y-205964D01*
X1150184Y-203922D01*
X1148874Y-202172D01*
X1147345Y-201589D01*
X1140577D01*
G01X1105140Y-148422D02*
X1110599Y-165922D01*
X1116058Y-148422D01*
G01X1132466Y-165922D02*
X1123732D01*
Y-148422D01*
X1132466D01*
G01X1128972Y-156880D02*
X1123732D01*
G01X1141232Y-165922D02*
Y-148422D01*
X1146691D01*
X1148437Y-149297D01*
X1149529Y-150464D01*
X1149966Y-152797D01*
X1149529Y-155131D01*
X1148219Y-156589D01*
X1146691Y-157464D01*
X1141232D01*
G01X1146691D02*
X1149966Y-165922D01*
G01X1163099Y-166505D02*
X1162662Y-166214D01*
Y-165630D01*
X1163099Y-165339D01*
X1163536Y-165630D01*
Y-166214D01*
X1163099Y-166505D01*
G01X1227606Y202469D02*
X1205005D01*
G01X1227016Y264882D02*
X1212912D01*
Y264868D01*
G01X1226902Y249295D02*
X1212798D01*
X1210091D01*
G01X1228450Y233649D02*
X1214346D01*
X1210245Y233648D01*
G01X1228223Y218069D02*
X1210445D01*
G01X1224849Y327289D02*
X1209887D01*
G01X1225728Y311667D02*
X1201615D01*
G01X1225618Y296082D02*
X1201615D01*
G01X1227483Y280469D02*
X1208435D01*
G01X1227497Y395519D02*
X1206600D01*
G01X1227454Y389669D02*
X1209433D01*
Y389674D01*
G01X1227141Y374069D02*
X1213102D01*
G01X1225142Y358495D02*
X1207770D01*
Y358478D01*
G01X1224299Y342874D02*
X1209908D01*
G01X1226021Y405782D02*
X1197432D01*
Y405787D01*
G01X1243049Y-193422D02*
Y-210922D01*
G01X1238027Y-193422D02*
X1248071D01*
G01X1255964Y-208589D02*
X1257711Y-210047D01*
X1259676Y-210922D01*
X1261422D01*
X1263169Y-210047D01*
X1264479Y-208589D01*
X1265134Y-206547D01*
X1264697Y-204506D01*
X1263606Y-202755D01*
X1261641Y-201589D01*
X1259021Y-201005D01*
X1257492Y-199839D01*
X1256837Y-197797D01*
X1257274Y-195755D01*
X1258366Y-194297D01*
X1259894Y-193422D01*
X1261422D01*
X1262951Y-194005D01*
X1264261Y-195464D01*
G01X1275429Y-193422D02*
X1280669D01*
G01X1278049D02*
Y-210922D01*
G01X1275429D02*
X1280669D01*
G01X1291182Y-193422D02*
Y-210922D01*
X1299916D01*
G01X1308246D02*
Y-193422D01*
G01X1316542D02*
X1308246Y-204214D01*
G01X1317852Y-210922D02*
X1311957Y-199256D01*
G01X1238682Y-148422D02*
Y-165922D01*
X1247416D01*
G01X1264479D02*
Y-154256D01*
G01Y-156297D02*
X1263606Y-155131D01*
X1262295Y-154547D01*
X1260767Y-154256D01*
X1259239Y-154839D01*
X1257929Y-156005D01*
X1257055Y-157755D01*
X1256619Y-160089D01*
X1257055Y-162422D01*
X1257929Y-164172D01*
X1259239Y-165339D01*
X1260767Y-165922D01*
X1262295Y-165630D01*
X1263606Y-164756D01*
X1264479Y-163589D01*
G01X1273464Y-171172D02*
X1274774Y-171755D01*
X1276521Y-171172D01*
X1277612Y-170006D01*
X1278486Y-168547D01*
X1279795Y-163881D01*
X1282634Y-154256D01*
G01X1275647D02*
X1279795Y-163881D01*
G01X1292274Y-158047D02*
X1299261D01*
X1298606Y-156005D01*
X1297514Y-154839D01*
X1295986Y-154256D01*
X1294457Y-154547D01*
X1293147Y-155422D01*
X1292274Y-157464D01*
X1291837Y-159214D01*
Y-160964D01*
X1292274Y-162714D01*
X1293366Y-164464D01*
X1294676Y-165630D01*
X1296204Y-165922D01*
X1297732Y-165339D01*
X1299261Y-163589D01*
G01X1309992Y-165922D02*
Y-154256D01*
G01Y-156589D02*
X1311084Y-155422D01*
X1312176Y-154547D01*
X1313704Y-154256D01*
X1314795Y-154547D01*
X1316106Y-155422D01*
G01X1312100Y258900D02*
Y270900D01*
X1315900D01*
G01X1314500Y265100D02*
X1312100D01*
G01X1320800Y265300D02*
X1321200Y265900D01*
X1321500Y266900D01*
X1321700Y268300D01*
X1321500Y269500D01*
X1321100Y270300D01*
X1320400Y270900D01*
X1317700D01*
Y258900D01*
X1321000D01*
X1321700Y259700D01*
X1322100Y260900D01*
X1322300Y262300D01*
X1322100Y263700D01*
X1321500Y264900D01*
X1320800Y265300D01*
X1317700D01*
G01X1330000Y258900D02*
Y270900D01*
X1332400D01*
X1333200Y270300D01*
X1333800Y268900D01*
X1334000Y267300D01*
X1333800Y265700D01*
X1333300Y264500D01*
X1332400Y263900D01*
X1330000D01*
G01X1335700Y258900D02*
Y270900D01*
X1340300Y258900D01*
Y270900D01*
G01X1348000D02*
Y258900D01*
X1352000D01*
G01X1353500D02*
X1356000Y270900D01*
X1358500Y258900D01*
G01X1357600Y263100D02*
X1354400D01*
G01X1362800Y265300D02*
X1363200Y265900D01*
X1363500Y266900D01*
X1363700Y268300D01*
X1363500Y269500D01*
X1363100Y270300D01*
X1362400Y270900D01*
X1359700D01*
Y258900D01*
X1363000D01*
X1363700Y259700D01*
X1364100Y260900D01*
X1364300Y262300D01*
X1364100Y263700D01*
X1363500Y264900D01*
X1362800Y265300D01*
X1359700D01*
G01X1370000Y258900D02*
X1366000D01*
Y270900D01*
X1370000D01*
G01X1368400Y265100D02*
X1366000D01*
G01X1372000Y270900D02*
Y258900D01*
X1376000D01*
G01X1318563Y293640D02*
X1319363Y292640D01*
X1320263Y292040D01*
X1321063D01*
X1321863Y292640D01*
X1322463Y293640D01*
X1322763Y295040D01*
X1322563Y296440D01*
X1322063Y297640D01*
X1321163Y298440D01*
X1319963Y298840D01*
X1319263Y299640D01*
X1318963Y301040D01*
X1319163Y302440D01*
X1319663Y303440D01*
X1320363Y304040D01*
X1321063D01*
X1321763Y303640D01*
X1322363Y302640D01*
G01X1324363Y292040D02*
Y304040D01*
X1328963Y292040D01*
Y304040D01*
G01X1336663D02*
Y292040D01*
X1340663D01*
G01X1342163D02*
X1344663Y304040D01*
X1347163Y292040D01*
G01X1346263Y296240D02*
X1343063D01*
G01X1351463Y298440D02*
X1351863Y299040D01*
X1352163Y300040D01*
X1352363Y301440D01*
X1352163Y302640D01*
X1351763Y303440D01*
X1351063Y304040D01*
X1348363D01*
Y292040D01*
X1351663D01*
X1352363Y292840D01*
X1352763Y294040D01*
X1352963Y295440D01*
X1352763Y296840D01*
X1352163Y298040D01*
X1351463Y298440D01*
X1348363D01*
G01X1358663Y292040D02*
X1354663D01*
Y304040D01*
X1358663D01*
G01X1357063Y298240D02*
X1354663D01*
G01X1360663Y304040D02*
Y292040D01*
X1364663D01*
G01X1317600Y322800D02*
Y334800D01*
X1320200Y324800D01*
X1322800Y334800D01*
Y322800D01*
G01X1323700D02*
X1326200Y334800D01*
X1328700Y322800D01*
G01X1327800Y327000D02*
X1324600D01*
G01X1334400Y333800D02*
X1333800Y334400D01*
X1333100Y334800D01*
X1332300D01*
X1331400Y334200D01*
X1330700Y333200D01*
X1330200Y332000D01*
X1329800Y330000D01*
X1329700Y328200D01*
X1329900Y326400D01*
X1330200Y325200D01*
X1330800Y324000D01*
X1331500Y323200D01*
X1332200Y322800D01*
X1332900D01*
X1333600Y323200D01*
X1334200Y323800D01*
X1334700Y324600D01*
G01X1342200Y334800D02*
Y322800D01*
X1346200D01*
G01X1347700D02*
X1350200Y334800D01*
X1352700Y322800D01*
G01X1351800Y327000D02*
X1348600D01*
G01X1357000Y329200D02*
X1357400Y329800D01*
X1357700Y330800D01*
X1357900Y332200D01*
X1357700Y333400D01*
X1357300Y334200D01*
X1356600Y334800D01*
X1353900D01*
Y322800D01*
X1357200D01*
X1357900Y323600D01*
X1358300Y324800D01*
X1358500Y326200D01*
X1358300Y327600D01*
X1357700Y328800D01*
X1357000Y329200D01*
X1353900D01*
G01X1364200Y322800D02*
X1360200D01*
Y334800D01*
X1364200D01*
G01X1362600Y329000D02*
X1360200D01*
G01X1366200Y334800D02*
Y322800D01*
X1370200D01*
G01X1380796Y-165922D02*
Y-148422D01*
X1385162D01*
X1386909Y-149297D01*
X1388219Y-150464D01*
X1389311Y-152213D01*
X1390184Y-154256D01*
X1390402Y-157172D01*
X1390184Y-160089D01*
X1389311Y-162131D01*
X1388219Y-163881D01*
X1386909Y-165047D01*
X1385162Y-165922D01*
X1380796D01*
G01X1399824Y-158047D02*
X1406811D01*
X1406156Y-156005D01*
X1405064Y-154839D01*
X1403536Y-154256D01*
X1402007Y-154547D01*
X1400697Y-155422D01*
X1399824Y-157464D01*
X1399387Y-159214D01*
Y-160964D01*
X1399824Y-162714D01*
X1400916Y-164464D01*
X1402226Y-165630D01*
X1403754Y-165922D01*
X1405282Y-165339D01*
X1406811Y-163589D01*
G01X1417324Y-163881D02*
X1418416Y-165047D01*
X1419944Y-165922D01*
X1421254D01*
X1422564Y-165339D01*
X1423437Y-164464D01*
X1423874Y-163298D01*
X1423656Y-161547D01*
X1422782Y-160672D01*
X1418852Y-158922D01*
X1417979Y-156880D01*
X1418416Y-155422D01*
X1419289Y-154547D01*
X1420599Y-154256D01*
X1421909Y-154547D01*
X1423219Y-155422D01*
G01X1438099Y-154256D02*
Y-165922D01*
G01Y-149589D02*
X1437662Y-149297D01*
Y-148714D01*
X1438099Y-148422D01*
X1438536Y-148714D01*
Y-149297D01*
X1438099Y-149589D01*
G01X1452542Y-170297D02*
X1454071Y-171464D01*
X1455817Y-171755D01*
X1457345Y-171464D01*
X1458656Y-170006D01*
X1459529Y-167964D01*
Y-154256D01*
G01Y-156589D02*
X1458656Y-155422D01*
X1457345Y-154547D01*
X1455817Y-154256D01*
X1454071Y-154839D01*
X1452979Y-156005D01*
X1452105Y-158047D01*
X1451669Y-160089D01*
X1451887Y-161839D01*
X1452761Y-163881D01*
X1454071Y-165339D01*
X1455817Y-165922D01*
X1457127Y-165630D01*
X1458656Y-164464D01*
X1459529Y-163298D01*
G01X1469387Y-165922D02*
Y-154256D01*
G01Y-157172D02*
X1470261Y-155714D01*
X1471571Y-154547D01*
X1473317Y-154256D01*
X1474845Y-154547D01*
X1476156Y-155714D01*
X1476811Y-157755D01*
Y-165922D01*
G01X1487324Y-158047D02*
X1494311D01*
X1493656Y-156005D01*
X1492564Y-154839D01*
X1491036Y-154256D01*
X1489507Y-154547D01*
X1488197Y-155422D01*
X1487324Y-157464D01*
X1486887Y-159214D01*
Y-160964D01*
X1487324Y-162714D01*
X1488416Y-164464D01*
X1489726Y-165630D01*
X1491254Y-165922D01*
X1492782Y-165339D01*
X1494311Y-163589D01*
G01X1505042Y-165922D02*
Y-154256D01*
G01Y-156589D02*
X1506134Y-155422D01*
X1507226Y-154547D01*
X1508754Y-154256D01*
X1509845Y-154547D01*
X1511156Y-155422D01*
G01X1426729Y-193422D02*
X1431969D01*
G01X1429349D02*
Y-210922D01*
G01X1426729D02*
X1431969D01*
G01X1441390Y-193422D02*
X1446849Y-210922D01*
X1452308Y-193422D01*
G01X1464349Y-210922D02*
Y-203047D01*
X1459982Y-193422D01*
G01X1468716D02*
X1464349Y-203047D01*
G01X1437500Y-19800D02*
Y-19799D01*
G01Y-200D02*
Y-204D01*
G01X1412162Y196706D02*
Y208706D01*
X1414562D01*
X1415362Y208106D01*
X1415962Y206706D01*
X1416162Y205106D01*
X1415962Y203506D01*
X1415462Y202306D01*
X1414562Y201706D01*
X1412162D01*
G01X1417862Y196706D02*
Y208706D01*
X1422462Y196706D01*
Y208706D01*
G01X1430162D02*
Y196706D01*
X1434162D01*
G01X1435662D02*
X1438162Y208706D01*
X1440662Y196706D01*
G01X1439762Y200906D02*
X1436562D01*
G01X1444962Y203106D02*
X1445362Y203706D01*
X1445662Y204706D01*
X1445862Y206106D01*
X1445662Y207306D01*
X1445262Y208106D01*
X1444562Y208706D01*
X1441862D01*
Y196706D01*
X1445162D01*
X1445862Y197506D01*
X1446262Y198706D01*
X1446462Y200106D01*
X1446262Y201506D01*
X1445662Y202706D01*
X1444962Y203106D01*
X1441862D01*
G01X1452162Y196706D02*
X1448162D01*
Y208706D01*
X1452162D01*
G01X1450562Y202906D02*
X1448162D01*
G01X1454162Y208706D02*
Y196706D01*
X1458162D01*
G01X1551799Y-193422D02*
X1550052Y-194005D01*
X1548742Y-195464D01*
X1547869Y-197213D01*
X1547214Y-199547D01*
X1546996Y-202172D01*
X1547214Y-204797D01*
X1547869Y-207131D01*
X1548742Y-208881D01*
X1550052Y-210339D01*
X1551799Y-210922D01*
X1553545Y-210339D01*
X1554856Y-208881D01*
X1555729Y-207131D01*
X1556384Y-204797D01*
X1556602Y-202172D01*
X1556384Y-199547D01*
X1555729Y-197213D01*
X1554856Y-195464D01*
X1553545Y-194005D01*
X1551799Y-193422D01*
G01X1565151Y-196339D02*
X1566461Y-194589D01*
X1567989Y-193714D01*
X1569736Y-193422D01*
X1571919Y-194005D01*
X1573447Y-195464D01*
X1573884Y-197213D01*
X1573666Y-198964D01*
X1572792Y-200422D01*
X1568426Y-203339D01*
X1566461Y-205380D01*
X1565151Y-208298D01*
X1564714Y-210922D01*
X1573884D01*
G01X1582869Y-211505D02*
X1590729Y-193422D01*
G01X1604299Y-210922D02*
Y-193422D01*
X1601679Y-196922D01*
G01Y-210922D02*
X1606919D01*
G01X1621799Y-193422D02*
X1620052Y-194005D01*
X1618742Y-195464D01*
X1617869Y-197213D01*
X1617214Y-199547D01*
X1616996Y-202172D01*
X1617214Y-204797D01*
X1617869Y-207131D01*
X1618742Y-208881D01*
X1620052Y-210339D01*
X1621799Y-210922D01*
X1623545Y-210339D01*
X1624856Y-208881D01*
X1625729Y-207131D01*
X1626384Y-204797D01*
X1626602Y-202172D01*
X1626384Y-199547D01*
X1625729Y-197213D01*
X1624856Y-195464D01*
X1623545Y-194005D01*
X1621799Y-193422D01*
G01X1635369Y-211505D02*
X1643229Y-193422D01*
G01X1652651Y-196339D02*
X1653961Y-194589D01*
X1655489Y-193714D01*
X1657236Y-193422D01*
X1659419Y-194005D01*
X1660947Y-195464D01*
X1661384Y-197213D01*
X1661166Y-198964D01*
X1660292Y-200422D01*
X1655926Y-203339D01*
X1653961Y-205380D01*
X1652651Y-208298D01*
X1652214Y-210922D01*
X1661384D01*
G01X1674299Y-193422D02*
X1672552Y-194005D01*
X1671242Y-195464D01*
X1670369Y-197213D01*
X1669714Y-199547D01*
X1669496Y-202172D01*
X1669714Y-204797D01*
X1670369Y-207131D01*
X1671242Y-208881D01*
X1672552Y-210339D01*
X1674299Y-210922D01*
X1676045Y-210339D01*
X1677356Y-208881D01*
X1678229Y-207131D01*
X1678884Y-204797D01*
X1679102Y-202172D01*
X1678884Y-199547D01*
X1678229Y-197213D01*
X1677356Y-195464D01*
X1676045Y-194005D01*
X1674299Y-193422D01*
G01X1691799Y-210922D02*
Y-193422D01*
X1689179Y-196922D01*
G01Y-210922D02*
X1694419D01*
G01X1708862D02*
X1709299Y-207131D01*
X1709954Y-203922D01*
X1710827Y-201005D01*
X1711919Y-197797D01*
X1713666Y-193422D01*
X1704932D01*
G01X1599496Y-165922D02*
Y-148422D01*
X1603862D01*
X1605609Y-149297D01*
X1606919Y-150464D01*
X1608011Y-152213D01*
X1608884Y-154256D01*
X1609102Y-157172D01*
X1608884Y-160089D01*
X1608011Y-162131D01*
X1606919Y-163881D01*
X1605609Y-165047D01*
X1603862Y-165922D01*
X1599496D01*
G01X1625729D02*
Y-154256D01*
G01Y-156297D02*
X1624856Y-155131D01*
X1623545Y-154547D01*
X1622017Y-154256D01*
X1620489Y-154839D01*
X1619179Y-156005D01*
X1618305Y-157755D01*
X1617869Y-160089D01*
X1618305Y-162422D01*
X1619179Y-164172D01*
X1620489Y-165339D01*
X1622017Y-165922D01*
X1623545Y-165630D01*
X1624856Y-164756D01*
X1625729Y-163589D01*
G01X1639299Y-148422D02*
Y-165922D01*
G01X1636242Y-154256D02*
X1642356D01*
G01X1653524Y-158047D02*
X1660511D01*
X1659856Y-156005D01*
X1658764Y-154839D01*
X1657236Y-154256D01*
X1655707Y-154547D01*
X1654397Y-155422D01*
X1653524Y-157464D01*
X1653087Y-159214D01*
Y-160964D01*
X1653524Y-162714D01*
X1654616Y-164464D01*
X1655926Y-165630D01*
X1657454Y-165922D01*
X1658982Y-165339D01*
X1660511Y-163589D01*
G01X1699003Y-200D02*
Y-204D01*
G01Y-19800D02*
Y-19799D01*
G01X1765004Y-200D02*
Y-204D01*
G01Y-19800D02*
Y-19799D01*
G01X-15900Y19300D02*
X-22462D01*
Y54479D01*
G01Y78946D02*
Y90860D01*
X18247D01*
G01X-22256Y55637D02*
Y77637D01*
X-4556D01*
Y55637D01*
X-22256D01*
G01X-23622Y92580D02*
Y164980D01*
X45555D01*
Y92580D01*
X-23622D01*
G01X-39978Y162980D02*
X-40395Y162447D01*
X-40645Y161847D01*
Y161313D01*
X-40395Y160780D01*
X-39978Y160380D01*
X-39395Y160180D01*
X-38812Y160313D01*
X-38312Y160647D01*
X-37978Y161247D01*
X-37812Y162047D01*
X-37478Y162513D01*
X-36895Y162713D01*
X-36312Y162580D01*
X-35895Y162247D01*
X-35645Y161780D01*
Y161313D01*
X-35812Y160847D01*
X-36228Y160447D01*
G01X-40645Y156480D02*
X-35645D01*
G01X-37312Y151380D02*
X-40645D01*
G01X-35978D02*
X-35895Y151513D01*
X-35728D01*
X-35645Y151380D01*
X-35728Y151247D01*
X-35895D01*
X-35978Y151380D01*
G01X-35645Y146280D02*
X-40645D01*
G01X-37312Y147213D02*
Y145347D01*
G01X-23520Y192362D02*
X59763D01*
G01D02*
Y164410D01*
X-23437D01*
G01X-36162Y224696D02*
X-36579Y224163D01*
X-36829Y223563D01*
Y223029D01*
X-36579Y222496D01*
X-36162Y222096D01*
X-35579Y221896D01*
X-34996Y222029D01*
X-34496Y222363D01*
X-34162Y222963D01*
X-33996Y223763D01*
X-33662Y224229D01*
X-33079Y224429D01*
X-32496Y224296D01*
X-32079Y223963D01*
X-31829Y223496D01*
Y223029D01*
X-31996Y222563D01*
X-32412Y222163D01*
G01X-36829Y218196D02*
X-31829D01*
G01X-33496Y213096D02*
X-36829D01*
G01X-32162D02*
X-32079Y213229D01*
X-31912D01*
X-31829Y213096D01*
X-31912Y212963D01*
X-32079D01*
X-32162Y213096D01*
G01X-31829Y207996D02*
X-36829D01*
G01X-33496Y208929D02*
Y207063D01*
G01X-23622Y240531D02*
Y191831D01*
X50776D01*
Y240531D01*
X-23622D01*
G01X-20667Y262758D02*
X-18167Y263800D01*
X-20667Y264842D01*
G01X-18167Y266067D02*
X-20667D01*
Y267108D01*
X-20542Y267442D01*
X-20375Y267650D01*
X-20042Y267733D01*
X-19709Y267650D01*
X-19500Y267400D01*
X-19375Y267108D01*
Y266067D01*
G01Y267108D02*
X-18167Y267733D01*
G01Y270000D02*
X-20667D01*
X-20167Y269500D01*
G01X-18167D02*
Y270500D01*
G01Y272183D02*
X-20667D01*
Y273017D01*
X-20542Y273350D01*
X-20375Y273600D01*
X-20125Y273808D01*
X-19834Y273975D01*
X-19417Y274017D01*
X-19000Y273975D01*
X-18709Y273808D01*
X-18459Y273600D01*
X-18292Y273350D01*
X-18167Y273017D01*
Y272183D01*
G01Y276200D02*
X-20667D01*
X-20167Y275700D01*
G01X-18167D02*
Y276700D01*
G01X14600Y242750D02*
X-16200D01*
G01Y267250D02*
X14600D01*
G01X-16200Y247350D02*
Y242750D01*
G01Y267250D02*
Y262650D01*
G01X-36162Y333830D02*
X-36579Y333297D01*
X-36829Y332697D01*
Y332163D01*
X-36579Y331630D01*
X-36162Y331230D01*
X-35579Y331030D01*
X-34996Y331163D01*
X-34496Y331497D01*
X-34162Y332097D01*
X-33996Y332897D01*
X-33662Y333363D01*
X-33079Y333563D01*
X-32496Y333430D01*
X-32079Y333097D01*
X-31829Y332630D01*
Y332163D01*
X-31996Y331697D01*
X-32412Y331297D01*
G01X-36829Y327330D02*
X-31829D01*
G01X-33496Y322230D02*
X-36829D01*
G01X-32162D02*
X-32079Y322363D01*
X-31912D01*
X-31829Y322230D01*
X-31912Y322097D01*
X-32079D01*
X-32162Y322230D01*
G01X-31829Y317130D02*
X-36829D01*
G01X-33496Y318063D02*
Y316197D01*
G01X-20483Y297167D02*
X-20275Y296917D01*
X-20025Y296750D01*
X-19733Y296667D01*
X-19400Y296750D01*
X-19150Y296917D01*
X-18900Y297167D01*
X-18817Y297500D01*
Y299167D01*
G01X-16550Y296667D02*
Y299167D01*
X-17050Y298667D01*
G01Y296667D02*
X-16050D01*
G01X-14367D02*
Y299167D01*
X-13533D01*
X-13200Y299042D01*
X-12950Y298875D01*
X-12742Y298625D01*
X-12575Y298334D01*
X-12533Y297917D01*
X-12575Y297500D01*
X-12742Y297209D01*
X-12950Y296959D01*
X-13200Y296792D01*
X-13533Y296667D01*
X-14367D01*
G01X-10350D02*
Y299167D01*
X-10850Y298667D01*
G01Y296667D02*
X-9850D01*
G01X-23622Y349665D02*
Y300965D01*
X50776D01*
Y349665D01*
X-23622D01*
G01X-36203Y390530D02*
X-36620Y389997D01*
X-36870Y389397D01*
Y388863D01*
X-36620Y388330D01*
X-36203Y387930D01*
X-35620Y387730D01*
X-35037Y387863D01*
X-34537Y388197D01*
X-34203Y388797D01*
X-34037Y389597D01*
X-33703Y390063D01*
X-33120Y390263D01*
X-32537Y390130D01*
X-32120Y389797D01*
X-31870Y389330D01*
Y388863D01*
X-32037Y388397D01*
X-32453Y387997D01*
G01X-36870Y384030D02*
X-31870D01*
G01X-33537Y378930D02*
X-36870D01*
G01X-32203D02*
X-32120Y379063D01*
X-31953D01*
X-31870Y378930D01*
X-31953Y378797D01*
X-32120D01*
X-32203Y378930D01*
G01X-31870Y373830D02*
X-36870D01*
G01X-33537Y374763D02*
Y372897D01*
G01X-23622Y348721D02*
Y421121D01*
X45555D01*
Y348721D01*
X-23622D01*
G01X-17042Y450915D02*
X-17292Y451040D01*
X-17584Y451123D01*
X-17917D01*
X-18292Y450998D01*
X-18584Y450790D01*
X-18792Y450540D01*
X-18959Y450123D01*
X-19001Y449748D01*
X-18917Y449373D01*
X-18792Y449123D01*
X-18542Y448873D01*
X-18251Y448706D01*
X-17959Y448623D01*
X-17667D01*
X-17376Y448706D01*
X-17126Y448831D01*
X-16917Y448998D01*
G01X-15692Y448623D02*
Y451123D01*
X-14651D01*
X-14317Y450998D01*
X-14109Y450831D01*
X-14026Y450498D01*
X-14109Y450165D01*
X-14359Y449956D01*
X-14651Y449831D01*
X-15692D01*
G01X-14651D02*
X-14026Y448623D01*
G01X-11759D02*
Y451123D01*
X-12259Y450623D01*
G01Y448623D02*
X-11259D01*
G01X-8659Y451123D02*
X-8992Y451040D01*
X-9242Y450831D01*
X-9409Y450581D01*
X-9534Y450248D01*
X-9576Y449873D01*
X-9534Y449498D01*
X-9409Y449165D01*
X-9242Y448915D01*
X-8992Y448706D01*
X-8659Y448623D01*
X-8326Y448706D01*
X-8076Y448915D01*
X-7909Y449165D01*
X-7784Y449498D01*
X-7742Y449873D01*
X-7784Y450248D01*
X-7909Y450581D01*
X-8076Y450831D01*
X-8326Y451040D01*
X-8659Y451123D01*
G01X-6809D02*
X-6226Y448623D01*
X-5559Y451123D01*
X-4892Y448623D01*
X-4309Y451123D01*
G01X-3376Y449123D02*
X-3126Y448831D01*
X-2792Y448665D01*
X-2417Y448623D01*
X-2084Y448665D01*
X-1751Y448873D01*
X-1542Y449123D01*
X-1501Y449373D01*
X-1584Y449665D01*
X-1876Y449873D01*
X-2167Y449956D01*
X-2542D01*
G01X-2167D02*
X-1917Y450081D01*
X-1709Y450290D01*
X-1626Y450540D01*
X-1709Y450790D01*
X-1917Y450998D01*
X-2292Y451123D01*
X-2667Y451081D01*
X-3042Y450915D01*
G01X-20488Y422194D02*
Y446394D01*
X21512D01*
Y422194D01*
X-20488D01*
G01X-18420Y556858D02*
X-20334D01*
Y487800D01*
X-15400D01*
Y483164D01*
X4300D01*
G01X-20838Y475613D02*
X-19046D01*
X-18671Y475780D01*
X-18421Y476113D01*
X-18338Y476530D01*
X-18421Y476947D01*
X-18671Y477280D01*
X-19046Y477447D01*
X-20838D01*
G01X-18338Y479630D02*
X-20838D01*
X-20338Y479130D01*
G01X-18338D02*
Y480130D01*
G01X-19671Y483063D02*
X-19796Y483230D01*
X-20005Y483355D01*
X-20296Y483438D01*
X-20546Y483355D01*
X-20713Y483188D01*
X-20838Y482897D01*
Y481772D01*
X-18338D01*
Y483147D01*
X-18505Y483438D01*
X-18755Y483605D01*
X-19046Y483688D01*
X-19338Y483605D01*
X-19588Y483355D01*
X-19671Y483063D01*
Y481772D01*
G01X-20421Y485038D02*
X-20671Y485288D01*
X-20796Y485580D01*
X-20838Y485913D01*
X-20755Y486330D01*
X-20546Y486622D01*
X-20296Y486705D01*
X-20046Y486663D01*
X-19838Y486497D01*
X-19421Y485663D01*
X-19130Y485288D01*
X-18713Y485038D01*
X-18338Y484955D01*
Y486705D01*
G01X-8272Y466250D02*
Y474250D01*
X-20222D01*
Y466250D01*
X-8272D01*
G01X-20222Y472400D02*
X-18222Y470400D01*
X-20222Y468400D01*
G01X-16646Y581400D02*
X-18200D01*
Y589300D01*
X-13901D01*
X-13900Y589301D01*
Y592700D01*
X-6300D01*
G01X-19959Y575090D02*
Y577590D01*
X-18918D01*
X-18584Y577465D01*
X-18376Y577298D01*
X-18293Y576965D01*
X-18376Y576632D01*
X-18626Y576423D01*
X-18918Y576298D01*
X-19959D01*
G01X-18918D02*
X-18293Y575090D01*
G01X-16026D02*
Y577590D01*
X-16526Y577090D01*
G01Y575090D02*
X-15526D01*
G01X-13968D02*
X-12926Y577590D01*
X-11884Y575090D01*
G01X-12259Y575965D02*
X-13593D01*
G01X-10618Y577173D02*
X-10368Y577423D01*
X-10076Y577548D01*
X-9743Y577590D01*
X-9326Y577507D01*
X-9034Y577298D01*
X-8951Y577048D01*
X-8993Y576798D01*
X-9159Y576590D01*
X-9993Y576173D01*
X-10368Y575882D01*
X-10618Y575465D01*
X-10701Y575090D01*
X-8951D01*
G01X-17116Y558070D02*
X-17241Y557820D01*
X-17324Y557528D01*
Y557195D01*
X-17199Y556820D01*
X-16991Y556528D01*
X-16741Y556320D01*
X-16324Y556153D01*
X-15949Y556111D01*
X-15574Y556195D01*
X-15324Y556320D01*
X-15074Y556570D01*
X-14907Y556861D01*
X-14824Y557153D01*
Y557445D01*
X-14907Y557736D01*
X-15032Y557986D01*
X-15199Y558195D01*
G01X-17324Y560253D02*
X-14824D01*
G01X-17324Y559295D02*
Y561211D01*
G01X-14824Y563353D02*
X-17324D01*
X-16824Y562853D01*
G01X-14824D02*
Y563853D01*
G01X-16907Y565661D02*
X-17157Y565911D01*
X-17282Y566203D01*
X-17324Y566536D01*
X-17241Y566953D01*
X-17032Y567245D01*
X-16782Y567328D01*
X-16532Y567286D01*
X-16324Y567120D01*
X-15907Y566286D01*
X-15616Y565911D01*
X-15199Y565661D01*
X-14824Y565578D01*
Y567328D01*
G01X44500Y-38250D02*
Y-46250D01*
X26500D01*
Y-38250D01*
X44500D01*
G01Y-48250D02*
Y-56250D01*
X26500D01*
Y-48250D01*
X44500D01*
G01X27727Y19500D02*
X32187D01*
G01X19000Y13777D02*
X26500D01*
Y18895D01*
G01X17966Y-13917D02*
X24246D01*
Y-16020D01*
G01X43500Y21300D02*
X42129D01*
Y19300D01*
X41018D01*
G01X91071Y7786D02*
X85859D01*
Y-22500D01*
X27500D01*
G01X11800Y19200D02*
X15047D01*
G01X34400Y29500D02*
X34000D01*
Y46500D01*
X36500D01*
Y56500D01*
X34000D01*
Y90859D01*
X33999Y90860D01*
X31621D01*
G01X48986Y-21703D02*
Y-17703D01*
X41586D01*
G01X10726Y-22300D02*
Y-19800D01*
X11767D01*
X12101Y-19925D01*
X12309Y-20092D01*
X12392Y-20425D01*
X12309Y-20758D01*
X12059Y-20967D01*
X11767Y-21092D01*
X10726D01*
G01X11767D02*
X12392Y-22300D01*
G01X13576D02*
Y-19800D01*
X14659Y-21883D01*
X15742Y-19800D01*
Y-22300D01*
G01X17759D02*
Y-19800D01*
X17259Y-20300D01*
G01Y-22300D02*
X18259D01*
G01X21109Y-21050D02*
X21942D01*
Y-21800D01*
X21692Y-22050D01*
X21401Y-22217D01*
X20984Y-22300D01*
X20567Y-22217D01*
X20276Y-22050D01*
X20026Y-21800D01*
X19859Y-21508D01*
X19776Y-21175D01*
Y-20883D01*
X19859Y-20633D01*
X20026Y-20342D01*
X20276Y-20092D01*
X20526Y-19925D01*
X20859Y-19800D01*
X21151D01*
X21484Y-19883D01*
X21734Y-20050D01*
G01X23959Y-22300D02*
Y-19800D01*
X23459Y-20300D01*
G01Y-22300D02*
X24459D01*
G01X51550Y-13025D02*
X27450D01*
Y11075D01*
X51550D01*
Y-13025D01*
G01X29461Y7818D02*
Y9064D01*
X30643D01*
G01X30659Y-11014D02*
X29461D01*
Y-9866D01*
G01X33039Y25527D02*
X5739D01*
Y49077D01*
X33039D01*
Y25527D01*
G01X75550Y28694D02*
Y22646D01*
X38150D01*
Y28694D01*
G01X-9500Y21410D02*
X-13300D01*
G01X1848Y82827D02*
X-3486D01*
Y89827D01*
X1848D01*
G01X-286Y86444D02*
X-3486D01*
G01X21935Y90860D02*
X26645D01*
G01X33364Y56894D02*
X6064D01*
Y80444D01*
X33364D01*
Y56894D01*
G01X38150Y41794D02*
Y47842D01*
G01D02*
X75550D01*
Y41794D01*
G01X75450Y55950D02*
Y49902D01*
X38050D01*
Y55950D01*
G01Y69050D02*
Y75098D01*
G01D02*
X75450D01*
Y69050D01*
G01X-13300Y33610D02*
X-9500D01*
G01X-13200Y48650D02*
X-9400D01*
G01Y36450D02*
X-13200D01*
G01X38555Y148613D02*
X43555D01*
Y147013D01*
X43305Y146480D01*
X42722Y146080D01*
X42055Y145947D01*
X41388Y146080D01*
X40888Y146413D01*
X40638Y147013D01*
Y148613D01*
G01X38555Y143113D02*
X41888D01*
G01X41222D02*
X41555Y142780D01*
X41805Y142447D01*
X41888Y141980D01*
X41805Y141647D01*
X41555Y141247D01*
G01X40805Y138080D02*
Y135947D01*
X41388Y136147D01*
X41722Y136480D01*
X41888Y136947D01*
X41805Y137413D01*
X41555Y137813D01*
X40972Y138080D01*
X40472Y138213D01*
X39972D01*
X39472Y138080D01*
X38972Y137747D01*
X38638Y137347D01*
X38555Y136880D01*
X38722Y136413D01*
X39222Y135947D01*
G01X39138Y132980D02*
X38805Y132647D01*
X38555Y132180D01*
Y131780D01*
X38722Y131380D01*
X38972Y131113D01*
X39305Y130980D01*
X39805Y131047D01*
X40055Y131313D01*
X40555Y132513D01*
X41138Y132780D01*
X41555Y132647D01*
X41805Y132380D01*
X41888Y131980D01*
X41805Y131580D01*
X41555Y131180D01*
G01X39138Y127880D02*
X38805Y127547D01*
X38555Y127080D01*
Y126680D01*
X38722Y126280D01*
X38972Y126013D01*
X39305Y125880D01*
X39805Y125947D01*
X40055Y126213D01*
X40555Y127413D01*
X41138Y127680D01*
X41555Y127547D01*
X41805Y127280D01*
X41888Y126880D01*
X41805Y126480D01*
X41555Y126080D01*
G01X38555Y117947D02*
X43555D01*
Y115413D01*
G01X41138Y116347D02*
Y117947D01*
G01X41888Y111580D02*
X38555D01*
G01X43222D02*
X43305Y111713D01*
X43472D01*
X43555Y111580D01*
X43472Y111447D01*
X43305D01*
X43222Y111580D01*
G01X43555Y106480D02*
X38555D01*
G01X41888Y107413D02*
Y105547D01*
G01X39526Y235614D02*
X44526D01*
Y234014D01*
X44276Y233481D01*
X43693Y233081D01*
X43026Y232948D01*
X42359Y233081D01*
X41859Y233414D01*
X41609Y234014D01*
Y235614D01*
G01X39526Y230114D02*
X42859D01*
G01X42193D02*
X42526Y229781D01*
X42776Y229448D01*
X42859Y228981D01*
X42776Y228648D01*
X42526Y228248D01*
G01X41776Y225081D02*
Y222948D01*
X42359Y223148D01*
X42693Y223481D01*
X42859Y223948D01*
X42776Y224414D01*
X42526Y224814D01*
X41943Y225081D01*
X41443Y225214D01*
X40943D01*
X40443Y225081D01*
X39943Y224748D01*
X39609Y224348D01*
X39526Y223881D01*
X39693Y223414D01*
X40193Y222948D01*
G01X40109Y219981D02*
X39776Y219648D01*
X39526Y219181D01*
Y218781D01*
X39693Y218381D01*
X39943Y218114D01*
X40276Y217981D01*
X40776Y218048D01*
X41026Y218314D01*
X41526Y219514D01*
X42109Y219781D01*
X42526Y219648D01*
X42776Y219381D01*
X42859Y218981D01*
X42776Y218581D01*
X42526Y218181D01*
G01X40109Y214881D02*
X39776Y214548D01*
X39526Y214081D01*
Y213681D01*
X39693Y213281D01*
X39943Y213014D01*
X40276Y212881D01*
X40776Y212948D01*
X41026Y213214D01*
X41526Y214414D01*
X42109Y214681D01*
X42526Y214548D01*
X42776Y214281D01*
X42859Y213881D01*
X42776Y213481D01*
X42526Y213081D01*
G01X39526Y204948D02*
X44526D01*
Y202414D01*
G01X42109Y203348D02*
Y204948D01*
G01X42859Y198581D02*
X39526D01*
G01X44193D02*
X44276Y198714D01*
X44443D01*
X44526Y198581D01*
X44443Y198448D01*
X44276D01*
X44193Y198581D01*
G01X44526Y193481D02*
X39526D01*
G01X42859Y194414D02*
Y192548D01*
G01X15808Y268543D02*
X13308D01*
Y269584D01*
X13433Y269918D01*
X13600Y270126D01*
X13933Y270209D01*
X14266Y270126D01*
X14475Y269876D01*
X14600Y269584D01*
Y268543D01*
G01Y269584D02*
X15808Y270209D01*
G01Y272476D02*
X13308D01*
X13808Y271976D01*
G01X15808D02*
Y272976D01*
G01Y276409D02*
Y274743D01*
X13308D01*
Y276409D01*
G01X14516Y275743D02*
Y274743D01*
G01X15808Y278676D02*
X13308D01*
X13808Y278176D01*
G01X15808D02*
Y279176D01*
G01X13308Y281776D02*
X13391Y281443D01*
X13600Y281193D01*
X13850Y281026D01*
X14183Y280901D01*
X14558Y280859D01*
X14933Y280901D01*
X15266Y281026D01*
X15516Y281193D01*
X15725Y281443D01*
X15808Y281776D01*
X15725Y282109D01*
X15516Y282359D01*
X15266Y282526D01*
X14933Y282651D01*
X14558Y282693D01*
X14183Y282651D01*
X13850Y282526D01*
X13600Y282359D01*
X13391Y282109D01*
X13308Y281776D01*
G01X19590Y270672D02*
X17090D01*
Y271713D01*
X17215Y272047D01*
X17382Y272255D01*
X17715Y272338D01*
X18048Y272255D01*
X18257Y272005D01*
X18382Y271713D01*
Y270672D01*
G01Y271713D02*
X19590Y272338D01*
G01Y274605D02*
X17090D01*
X17590Y274105D01*
G01X19590D02*
Y275105D01*
G01Y278538D02*
Y276872D01*
X17090D01*
Y278538D01*
G01X18298Y277872D02*
Y276872D01*
G01X19298Y280097D02*
X19507Y280388D01*
X19590Y280722D01*
X19507Y281055D01*
X19257Y281347D01*
X18882Y281555D01*
X18507Y281638D01*
X18048D01*
X17673Y281555D01*
X17340Y281347D01*
X17173Y281097D01*
X17090Y280805D01*
X17173Y280472D01*
X17340Y280222D01*
X17590Y280055D01*
X17923Y279972D01*
X18215Y280055D01*
X18507Y280263D01*
X18673Y280513D01*
X18715Y280805D01*
X18632Y281138D01*
X18423Y281388D01*
X18048Y281638D01*
G01X38067Y273866D02*
Y276366D01*
X39108D01*
X39442Y276241D01*
X39650Y276074D01*
X39733Y275741D01*
X39650Y275408D01*
X39400Y275199D01*
X39108Y275074D01*
X38067D01*
G01X39108D02*
X39733Y273866D01*
G01X42000D02*
Y276366D01*
X41500Y275866D01*
G01Y273866D02*
X42500D01*
G01X44183D02*
Y276366D01*
X45017D01*
X45350Y276241D01*
X45600Y276074D01*
X45808Y275824D01*
X45975Y275533D01*
X46017Y275116D01*
X45975Y274699D01*
X45808Y274408D01*
X45600Y274158D01*
X45350Y273991D01*
X45017Y273866D01*
X44183D01*
G01X48700D02*
Y276366D01*
X47158Y274574D01*
X49242D01*
G01X50383Y274241D02*
X50633Y274033D01*
X50925Y273908D01*
X51300Y273866D01*
X51675Y273949D01*
X51967Y274116D01*
X52175Y274408D01*
X52217Y274741D01*
X52133Y275074D01*
X51925Y275283D01*
X51633Y275449D01*
X51342Y275491D01*
X51050Y275449D01*
X50675Y275283D01*
X50800Y276366D01*
X51925D01*
G01X21867Y274066D02*
Y276566D01*
X22908D01*
X23242Y276441D01*
X23450Y276274D01*
X23533Y275941D01*
X23450Y275608D01*
X23200Y275399D01*
X22908Y275274D01*
X21867D01*
G01X22908D02*
X23533Y274066D01*
G01X25800D02*
Y276566D01*
X25300Y276066D01*
G01Y274066D02*
X26300D01*
G01X27983D02*
Y276566D01*
X28817D01*
X29150Y276441D01*
X29400Y276274D01*
X29608Y276024D01*
X29775Y275733D01*
X29817Y275316D01*
X29775Y274899D01*
X29608Y274608D01*
X29400Y274358D01*
X29150Y274191D01*
X28817Y274066D01*
X27983D01*
G01X32500D02*
Y276566D01*
X30958Y274774D01*
X33042D01*
G01X35600Y274066D02*
Y276566D01*
X34058Y274774D01*
X36142D01*
G01X43747Y269817D02*
Y272317D01*
X44788D01*
X45122Y272192D01*
X45330Y272025D01*
X45413Y271692D01*
X45330Y271359D01*
X45080Y271150D01*
X44788Y271025D01*
X43747D01*
G01X44788D02*
X45413Y269817D01*
G01X47680D02*
Y272317D01*
X47180Y271817D01*
G01Y269817D02*
X48180D01*
G01X49863D02*
Y272317D01*
X50697D01*
X51030Y272192D01*
X51280Y272025D01*
X51488Y271775D01*
X51655Y271484D01*
X51697Y271067D01*
X51655Y270650D01*
X51488Y270359D01*
X51280Y270109D01*
X51030Y269942D01*
X50697Y269817D01*
X49863D01*
G01X54380D02*
Y272317D01*
X52838Y270525D01*
X54922D01*
G01X56897Y269817D02*
X56980Y270359D01*
X57105Y270817D01*
X57272Y271234D01*
X57480Y271692D01*
X57813Y272317D01*
X56147D01*
G01X21428Y269920D02*
Y272420D01*
X22469D01*
X22803Y272295D01*
X23011Y272128D01*
X23094Y271795D01*
X23011Y271462D01*
X22761Y271253D01*
X22469Y271128D01*
X21428D01*
G01X22469D02*
X23094Y269920D01*
G01X25361D02*
Y272420D01*
X24861Y271920D01*
G01Y269920D02*
X25861D01*
G01X27544D02*
Y272420D01*
X28378D01*
X28711Y272295D01*
X28961Y272128D01*
X29169Y271878D01*
X29336Y271587D01*
X29378Y271170D01*
X29336Y270753D01*
X29169Y270462D01*
X28961Y270212D01*
X28711Y270045D01*
X28378Y269920D01*
X27544D01*
G01X32061D02*
Y272420D01*
X30519Y270628D01*
X32603D01*
G01X33869Y270962D02*
X34161Y271253D01*
X34411Y271420D01*
X34744Y271503D01*
X35036Y271420D01*
X35244Y271253D01*
X35411Y271003D01*
X35453Y270712D01*
X35411Y270462D01*
X35244Y270212D01*
X34994Y270003D01*
X34703Y269920D01*
X34369Y270003D01*
X34078Y270253D01*
X33911Y270628D01*
X33869Y271045D01*
X33953Y271587D01*
X34078Y271878D01*
X34286Y272170D01*
X34578Y272378D01*
X34869Y272420D01*
X35161Y272337D01*
X35369Y272128D01*
G01X43617Y280759D02*
X43367Y280884D01*
X43075Y280967D01*
X42742D01*
X42367Y280842D01*
X42075Y280634D01*
X41867Y280384D01*
X41700Y279967D01*
X41658Y279592D01*
X41742Y279217D01*
X41867Y278967D01*
X42117Y278717D01*
X42408Y278550D01*
X42700Y278467D01*
X42992D01*
X43283Y278550D01*
X43533Y278675D01*
X43742Y278842D01*
G01X45800Y278467D02*
Y280967D01*
X45300Y280467D01*
G01Y278467D02*
X46300D01*
G01X47983D02*
Y280967D01*
X48817D01*
X49150Y280842D01*
X49400Y280675D01*
X49608Y280425D01*
X49775Y280134D01*
X49817Y279717D01*
X49775Y279300D01*
X49608Y279009D01*
X49400Y278759D01*
X49150Y278592D01*
X48817Y278467D01*
X47983D01*
G01X51208Y280550D02*
X51458Y280800D01*
X51750Y280925D01*
X52083Y280967D01*
X52500Y280884D01*
X52792Y280675D01*
X52875Y280425D01*
X52833Y280175D01*
X52667Y279967D01*
X51833Y279550D01*
X51458Y279259D01*
X51208Y278842D01*
X51125Y278467D01*
X52875D01*
G01X54308Y280550D02*
X54558Y280800D01*
X54850Y280925D01*
X55183Y280967D01*
X55600Y280884D01*
X55892Y280675D01*
X55975Y280425D01*
X55933Y280175D01*
X55767Y279967D01*
X54933Y279550D01*
X54558Y279259D01*
X54308Y278842D01*
X54225Y278467D01*
X55975D01*
G01X-13134Y270998D02*
X-13384Y271123D01*
X-13676Y271206D01*
X-14009D01*
X-14384Y271081D01*
X-14676Y270873D01*
X-14884Y270623D01*
X-15051Y270206D01*
X-15093Y269831D01*
X-15009Y269456D01*
X-14884Y269206D01*
X-14634Y268956D01*
X-14343Y268789D01*
X-14051Y268706D01*
X-13759D01*
X-13468Y268789D01*
X-13218Y268914D01*
X-13009Y269081D01*
G01X-10951Y268706D02*
Y271206D01*
X-11451Y270706D01*
G01Y268706D02*
X-10451D01*
G01X-7018D02*
X-8684D01*
Y271206D01*
X-7018D01*
G01X-7684Y269998D02*
X-8684D01*
G01X-4751Y268706D02*
Y271206D01*
X-5251Y270706D01*
G01Y268706D02*
X-4251D01*
G01X-2359Y268998D02*
X-2068Y268789D01*
X-1734Y268706D01*
X-1401Y268789D01*
X-1109Y269039D01*
X-901Y269414D01*
X-818Y269789D01*
Y270248D01*
X-901Y270623D01*
X-1109Y270956D01*
X-1359Y271123D01*
X-1651Y271206D01*
X-1984Y271123D01*
X-2234Y270956D01*
X-2401Y270706D01*
X-2484Y270373D01*
X-2401Y270081D01*
X-2193Y269789D01*
X-1943Y269623D01*
X-1651Y269581D01*
X-1318Y269664D01*
X-1068Y269873D01*
X-818Y270248D01*
G01X46932Y264650D02*
X45266D01*
Y267150D01*
X46932D01*
G01X46266Y265942D02*
X45266D01*
G01X48282Y267150D02*
Y265358D01*
X48449Y264983D01*
X48782Y264733D01*
X49199Y264650D01*
X49616Y264733D01*
X49949Y264983D01*
X50116Y265358D01*
Y267150D01*
G01X52299Y264650D02*
Y267150D01*
X51799Y266650D01*
G01Y264650D02*
X52799D01*
G01X56232D02*
X54566D01*
Y267150D01*
X56232D01*
G01X55566Y265942D02*
X54566D01*
G01X58499Y264650D02*
Y267150D01*
X57999Y266650D01*
G01Y264650D02*
X58999D01*
G01X34759Y243316D02*
Y245816D01*
X35800D01*
X36134Y245691D01*
X36342Y245524D01*
X36425Y245191D01*
X36342Y244858D01*
X36092Y244649D01*
X35800Y244524D01*
X34759D01*
G01X35800D02*
X36425Y243316D01*
G01X38692D02*
Y245816D01*
X38192Y245316D01*
G01Y243316D02*
X39192D01*
G01X40875D02*
Y245816D01*
X41709D01*
X42042Y245691D01*
X42292Y245524D01*
X42500Y245274D01*
X42667Y244983D01*
X42709Y244566D01*
X42667Y244149D01*
X42500Y243858D01*
X42292Y243608D01*
X42042Y243441D01*
X41709Y243316D01*
X40875D01*
G01X45392D02*
Y245816D01*
X43850Y244024D01*
X45934D01*
G01X47284Y243608D02*
X47575Y243399D01*
X47909Y243316D01*
X48242Y243399D01*
X48534Y243649D01*
X48742Y244024D01*
X48825Y244399D01*
Y244858D01*
X48742Y245233D01*
X48534Y245566D01*
X48284Y245733D01*
X47992Y245816D01*
X47659Y245733D01*
X47409Y245566D01*
X47242Y245316D01*
X47159Y244983D01*
X47242Y244691D01*
X47450Y244399D01*
X47700Y244233D01*
X47992Y244191D01*
X48325Y244274D01*
X48575Y244483D01*
X48825Y244858D01*
G01X14600Y267250D02*
Y262650D01*
G01Y247350D02*
Y242750D01*
G01X38933Y279967D02*
X36433D01*
Y281008D01*
X36558Y281342D01*
X36725Y281550D01*
X37058Y281633D01*
X37391Y281550D01*
X37600Y281300D01*
X37725Y281008D01*
Y279967D01*
G01Y281008D02*
X38933Y281633D01*
G01Y283900D02*
X36433D01*
X36933Y283400D01*
G01X38933D02*
Y284400D01*
G01Y286083D02*
X36433D01*
Y286917D01*
X36558Y287250D01*
X36725Y287500D01*
X36975Y287708D01*
X37266Y287875D01*
X37683Y287917D01*
X38100Y287875D01*
X38391Y287708D01*
X38641Y287500D01*
X38808Y287250D01*
X38933Y286917D01*
Y286083D01*
G01Y290600D02*
X36433D01*
X38225Y289058D01*
Y291142D01*
G01X38933Y293200D02*
X36433D01*
X36933Y292700D01*
G01X38933D02*
Y293700D01*
G01X46574Y285798D02*
X44074D01*
Y286839D01*
X44199Y287173D01*
X44366Y287381D01*
X44699Y287464D01*
X45032Y287381D01*
X45241Y287131D01*
X45366Y286839D01*
Y285798D01*
G01Y286839D02*
X46574Y287464D01*
G01Y289731D02*
X44074D01*
X44574Y289231D01*
G01X46574D02*
Y290231D01*
G01Y291914D02*
X44074D01*
Y292748D01*
X44199Y293081D01*
X44366Y293331D01*
X44616Y293539D01*
X44907Y293706D01*
X45324Y293748D01*
X45741Y293706D01*
X46032Y293539D01*
X46282Y293331D01*
X46449Y293081D01*
X46574Y292748D01*
Y291914D01*
G01X46074Y295014D02*
X46366Y295264D01*
X46532Y295598D01*
X46574Y295973D01*
X46532Y296306D01*
X46324Y296639D01*
X46074Y296848D01*
X45824Y296889D01*
X45532Y296806D01*
X45324Y296514D01*
X45241Y296223D01*
Y295848D01*
G01Y296223D02*
X45116Y296473D01*
X44907Y296681D01*
X44657Y296764D01*
X44407Y296681D01*
X44199Y296473D01*
X44074Y296098D01*
X44116Y295723D01*
X44282Y295348D01*
G01X46574Y299031D02*
X44074D01*
X44574Y298531D01*
G01X46574D02*
Y299531D01*
G01X-1204Y288016D02*
X-3704D01*
Y289057D01*
X-3579Y289391D01*
X-3412Y289599D01*
X-3079Y289682D01*
X-2746Y289599D01*
X-2537Y289349D01*
X-2412Y289057D01*
Y288016D01*
G01Y289057D02*
X-1204Y289682D01*
G01X-1496Y291241D02*
X-1287Y291532D01*
X-1204Y291866D01*
X-1287Y292199D01*
X-1537Y292491D01*
X-1912Y292699D01*
X-2287Y292782D01*
X-2746D01*
X-3121Y292699D01*
X-3454Y292491D01*
X-3621Y292241D01*
X-3704Y291949D01*
X-3621Y291616D01*
X-3454Y291366D01*
X-3204Y291199D01*
X-2871Y291116D01*
X-2579Y291199D01*
X-2287Y291407D01*
X-2121Y291657D01*
X-2079Y291949D01*
X-2162Y292282D01*
X-2371Y292532D01*
X-2746Y292782D01*
G01X-1204Y294216D02*
X-3704D01*
Y295257D01*
X-3579Y295591D01*
X-3412Y295799D01*
X-3079Y295882D01*
X-2746Y295799D01*
X-2537Y295549D01*
X-2412Y295257D01*
Y294216D01*
G01Y295257D02*
X-1204Y295882D01*
G01Y298149D02*
X-1246Y298441D01*
X-1371Y298774D01*
X-1579Y298982D01*
X-1871Y299066D01*
X-2162Y298982D01*
X-2412Y298732D01*
X-2537Y298357D01*
Y297941D01*
X-2621Y297691D01*
X-2829Y297482D01*
X-3121Y297399D01*
X-3412Y297524D01*
X-3621Y297816D01*
X-3704Y298149D01*
X-3621Y298482D01*
X-3412Y298774D01*
X-3121Y298899D01*
X-2829Y298816D01*
X-2621Y298607D01*
X-2537Y298357D01*
Y297941D01*
X-2412Y297566D01*
X-2162Y297316D01*
X-1871Y297232D01*
X-1579Y297316D01*
X-1371Y297524D01*
X-1246Y297857D01*
X-1204Y298149D01*
G01X-5295Y288028D02*
X-7795D01*
Y289069D01*
X-7670Y289403D01*
X-7503Y289611D01*
X-7170Y289694D01*
X-6837Y289611D01*
X-6628Y289361D01*
X-6503Y289069D01*
Y288028D01*
G01Y289069D02*
X-5295Y289694D01*
G01X-5587Y291253D02*
X-5378Y291544D01*
X-5295Y291878D01*
X-5378Y292211D01*
X-5628Y292503D01*
X-6003Y292711D01*
X-6378Y292794D01*
X-6837D01*
X-7212Y292711D01*
X-7545Y292503D01*
X-7712Y292253D01*
X-7795Y291961D01*
X-7712Y291628D01*
X-7545Y291378D01*
X-7295Y291211D01*
X-6962Y291128D01*
X-6670Y291211D01*
X-6378Y291419D01*
X-6212Y291669D01*
X-6170Y291961D01*
X-6253Y292294D01*
X-6462Y292544D01*
X-6837Y292794D01*
G01X-5295Y294228D02*
X-7795D01*
Y295269D01*
X-7670Y295603D01*
X-7503Y295811D01*
X-7170Y295894D01*
X-6837Y295811D01*
X-6628Y295561D01*
X-6503Y295269D01*
Y294228D01*
G01Y295269D02*
X-5295Y295894D01*
G01Y298078D02*
X-5837Y298161D01*
X-6295Y298286D01*
X-6712Y298453D01*
X-7170Y298661D01*
X-7795Y298994D01*
Y297328D01*
G01X35033Y282867D02*
X32533D01*
Y283908D01*
X32658Y284242D01*
X32825Y284450D01*
X33158Y284533D01*
X33491Y284450D01*
X33700Y284200D01*
X33825Y283908D01*
Y282867D01*
G01Y283908D02*
X35033Y284533D01*
G01Y286800D02*
X32533D01*
X33033Y286300D01*
G01X35033D02*
Y287300D01*
G01Y288983D02*
X32533D01*
Y289817D01*
X32658Y290150D01*
X32825Y290400D01*
X33075Y290608D01*
X33366Y290775D01*
X33783Y290817D01*
X34200Y290775D01*
X34491Y290608D01*
X34741Y290400D01*
X34908Y290150D01*
X35033Y289817D01*
Y288983D01*
G01X34533Y292083D02*
X34825Y292333D01*
X34991Y292667D01*
X35033Y293042D01*
X34991Y293375D01*
X34783Y293708D01*
X34533Y293917D01*
X34283Y293958D01*
X33991Y293875D01*
X33783Y293583D01*
X33700Y293292D01*
Y292917D01*
G01Y293292D02*
X33575Y293542D01*
X33366Y293750D01*
X33116Y293833D01*
X32866Y293750D01*
X32658Y293542D01*
X32533Y293167D01*
X32575Y292792D01*
X32741Y292417D01*
G01X34533Y295183D02*
X34825Y295433D01*
X34991Y295767D01*
X35033Y296142D01*
X34991Y296475D01*
X34783Y296808D01*
X34533Y297017D01*
X34283Y297058D01*
X33991Y296975D01*
X33783Y296683D01*
X33700Y296392D01*
Y296017D01*
G01Y296392D02*
X33575Y296642D01*
X33366Y296850D01*
X33116Y296933D01*
X32866Y296850D01*
X32658Y296642D01*
X32533Y296267D01*
X32575Y295892D01*
X32741Y295517D01*
G01X42474Y282998D02*
X39974D01*
Y284039D01*
X40099Y284373D01*
X40266Y284581D01*
X40599Y284664D01*
X40932Y284581D01*
X41141Y284331D01*
X41266Y284039D01*
Y282998D01*
G01Y284039D02*
X42474Y284664D01*
G01Y286931D02*
X39974D01*
X40474Y286431D01*
G01X42474D02*
Y287431D01*
G01Y289114D02*
X39974D01*
Y289948D01*
X40099Y290281D01*
X40266Y290531D01*
X40516Y290739D01*
X40807Y290906D01*
X41224Y290948D01*
X41641Y290906D01*
X41932Y290739D01*
X42182Y290531D01*
X42349Y290281D01*
X42474Y289948D01*
Y289114D01*
G01X41974Y292214D02*
X42266Y292464D01*
X42432Y292798D01*
X42474Y293173D01*
X42432Y293506D01*
X42224Y293839D01*
X41974Y294048D01*
X41724Y294089D01*
X41432Y294006D01*
X41224Y293714D01*
X41141Y293423D01*
Y293048D01*
G01Y293423D02*
X41016Y293673D01*
X40807Y293881D01*
X40557Y293964D01*
X40307Y293881D01*
X40099Y293673D01*
X39974Y293298D01*
X40016Y292923D01*
X40182Y292548D01*
G01X41432Y295439D02*
X41141Y295731D01*
X40974Y295981D01*
X40891Y296314D01*
X40974Y296606D01*
X41141Y296814D01*
X41391Y296981D01*
X41682Y297023D01*
X41932Y296981D01*
X42182Y296814D01*
X42391Y296564D01*
X42474Y296273D01*
X42391Y295939D01*
X42141Y295648D01*
X41766Y295481D01*
X41349Y295439D01*
X40807Y295523D01*
X40516Y295648D01*
X40224Y295856D01*
X40016Y296148D01*
X39974Y296439D01*
X40057Y296731D01*
X40266Y296939D01*
G01X-12667Y284100D02*
Y282308D01*
X-12500Y281933D01*
X-12167Y281683D01*
X-11750Y281600D01*
X-11333Y281683D01*
X-11000Y281933D01*
X-10833Y282308D01*
Y284100D01*
G01X-8650Y281600D02*
Y284100D01*
X-9150Y283600D01*
G01Y281600D02*
X-8150D01*
G01X-4717D02*
X-6383D01*
Y284100D01*
X-4717D01*
G01X-5383Y282892D02*
X-6383D01*
G01X-2450Y281600D02*
Y284100D01*
X-2950Y283600D01*
G01Y281600D02*
X-1950D01*
G01X12740Y286734D02*
Y284301D01*
G01X940Y286668D02*
Y284381D01*
G01X39526Y344748D02*
X44526D01*
Y343148D01*
X44276Y342615D01*
X43693Y342215D01*
X43026Y342082D01*
X42359Y342215D01*
X41859Y342548D01*
X41609Y343148D01*
Y344748D01*
G01X39526Y339248D02*
X42859D01*
G01X42193D02*
X42526Y338915D01*
X42776Y338582D01*
X42859Y338115D01*
X42776Y337782D01*
X42526Y337382D01*
G01X41776Y334215D02*
Y332082D01*
X42359Y332282D01*
X42693Y332615D01*
X42859Y333082D01*
X42776Y333548D01*
X42526Y333948D01*
X41943Y334215D01*
X41443Y334348D01*
X40943D01*
X40443Y334215D01*
X39943Y333882D01*
X39609Y333482D01*
X39526Y333015D01*
X39693Y332548D01*
X40193Y332082D01*
G01X40109Y329115D02*
X39776Y328782D01*
X39526Y328315D01*
Y327915D01*
X39693Y327515D01*
X39943Y327248D01*
X40276Y327115D01*
X40776Y327182D01*
X41026Y327448D01*
X41526Y328648D01*
X42109Y328915D01*
X42526Y328782D01*
X42776Y328515D01*
X42859Y328115D01*
X42776Y327715D01*
X42526Y327315D01*
G01X40109Y324015D02*
X39776Y323682D01*
X39526Y323215D01*
Y322815D01*
X39693Y322415D01*
X39943Y322148D01*
X40276Y322015D01*
X40776Y322082D01*
X41026Y322348D01*
X41526Y323548D01*
X42109Y323815D01*
X42526Y323682D01*
X42776Y323415D01*
X42859Y323015D01*
X42776Y322615D01*
X42526Y322215D01*
G01X39526Y314082D02*
X44526D01*
Y311548D01*
G01X42109Y312482D02*
Y314082D01*
G01X42859Y307715D02*
X39526D01*
G01X44193D02*
X44276Y307848D01*
X44443D01*
X44526Y307715D01*
X44443Y307582D01*
X44276D01*
X44193Y307715D01*
G01X44526Y302615D02*
X39526D01*
G01X42859Y303548D02*
Y301682D01*
G01X48387Y390032D02*
X48137Y390157D01*
X47845Y390240D01*
X47512D01*
X47137Y390115D01*
X46845Y389907D01*
X46637Y389657D01*
X46470Y389240D01*
X46428Y388865D01*
X46512Y388490D01*
X46637Y388240D01*
X46887Y387990D01*
X47178Y387823D01*
X47470Y387740D01*
X47762D01*
X48053Y387823D01*
X48303Y387948D01*
X48512Y388115D01*
G01X50570Y387740D02*
Y390240D01*
X50070Y389740D01*
G01Y387740D02*
X51070D01*
G01X54587Y390032D02*
X54337Y390157D01*
X54045Y390240D01*
X53712D01*
X53337Y390115D01*
X53045Y389907D01*
X52837Y389657D01*
X52670Y389240D01*
X52628Y388865D01*
X52712Y388490D01*
X52837Y388240D01*
X53087Y387990D01*
X53378Y387823D01*
X53670Y387740D01*
X53962D01*
X54253Y387823D01*
X54503Y387948D01*
X54712Y388115D01*
G01X56687Y387740D02*
X56770Y388282D01*
X56895Y388740D01*
X57062Y389157D01*
X57270Y389615D01*
X57603Y390240D01*
X55937D01*
G01X38555Y404754D02*
X43555D01*
Y403154D01*
X43305Y402621D01*
X42722Y402221D01*
X42055Y402088D01*
X41388Y402221D01*
X40888Y402554D01*
X40638Y403154D01*
Y404754D01*
G01X38555Y399254D02*
X41888D01*
G01X41222D02*
X41555Y398921D01*
X41805Y398588D01*
X41888Y398121D01*
X41805Y397788D01*
X41555Y397388D01*
G01X40805Y394221D02*
Y392088D01*
X41388Y392288D01*
X41722Y392621D01*
X41888Y393088D01*
X41805Y393554D01*
X41555Y393954D01*
X40972Y394221D01*
X40472Y394354D01*
X39972D01*
X39472Y394221D01*
X38972Y393888D01*
X38638Y393488D01*
X38555Y393021D01*
X38722Y392554D01*
X39222Y392088D01*
G01X39138Y389121D02*
X38805Y388788D01*
X38555Y388321D01*
Y387921D01*
X38722Y387521D01*
X38972Y387254D01*
X39305Y387121D01*
X39805Y387188D01*
X40055Y387454D01*
X40555Y388654D01*
X41138Y388921D01*
X41555Y388788D01*
X41805Y388521D01*
X41888Y388121D01*
X41805Y387721D01*
X41555Y387321D01*
G01X39138Y384021D02*
X38805Y383688D01*
X38555Y383221D01*
Y382821D01*
X38722Y382421D01*
X38972Y382154D01*
X39305Y382021D01*
X39805Y382088D01*
X40055Y382354D01*
X40555Y383554D01*
X41138Y383821D01*
X41555Y383688D01*
X41805Y383421D01*
X41888Y383021D01*
X41805Y382621D01*
X41555Y382221D01*
G01X38555Y374088D02*
X43555D01*
Y371554D01*
G01X41138Y372488D02*
Y374088D01*
G01X41888Y367721D02*
X38555D01*
G01X43222D02*
X43305Y367854D01*
X43472D01*
X43555Y367721D01*
X43472Y367588D01*
X43305D01*
X43222Y367721D01*
G01X43555Y362621D02*
X38555D01*
G01X41888Y363554D02*
Y361688D01*
G01X37163Y428165D02*
X36913Y428290D01*
X36621Y428373D01*
X36288D01*
X35913Y428248D01*
X35621Y428040D01*
X35413Y427790D01*
X35246Y427373D01*
X35204Y426998D01*
X35288Y426623D01*
X35413Y426373D01*
X35663Y426123D01*
X35954Y425956D01*
X36246Y425873D01*
X36538D01*
X36829Y425956D01*
X37079Y426081D01*
X37288Y426248D01*
G01X38638Y426165D02*
X38929Y425956D01*
X39263Y425873D01*
X39596Y425956D01*
X39888Y426206D01*
X40096Y426581D01*
X40179Y426956D01*
Y427415D01*
X40096Y427790D01*
X39888Y428123D01*
X39638Y428290D01*
X39346Y428373D01*
X39013Y428290D01*
X38763Y428123D01*
X38596Y427873D01*
X38513Y427540D01*
X38596Y427248D01*
X38804Y426956D01*
X39054Y426790D01*
X39346Y426748D01*
X39679Y426831D01*
X39929Y427040D01*
X40179Y427415D01*
G01X41363Y425873D02*
Y428373D01*
X42446Y426290D01*
X43529Y428373D01*
Y425873D01*
G01X46046D02*
Y428373D01*
X44504Y426581D01*
X46588D01*
G01X40763Y439267D02*
X40513Y439392D01*
X40221Y439475D01*
X39888D01*
X39513Y439350D01*
X39221Y439142D01*
X39013Y438892D01*
X38846Y438475D01*
X38804Y438100D01*
X38888Y437725D01*
X39013Y437475D01*
X39263Y437225D01*
X39554Y437058D01*
X39846Y436975D01*
X40138D01*
X40429Y437058D01*
X40679Y437183D01*
X40888Y437350D01*
G01X42946Y436975D02*
Y439475D01*
X42446Y438975D01*
G01Y436975D02*
X43446D01*
G01X46379Y438308D02*
X46546Y438433D01*
X46671Y438642D01*
X46754Y438933D01*
X46671Y439183D01*
X46504Y439350D01*
X46213Y439475D01*
X45088D01*
Y436975D01*
X46463D01*
X46754Y437142D01*
X46921Y437392D01*
X47004Y437683D01*
X46921Y437975D01*
X46671Y438225D01*
X46379Y438308D01*
X45088D01*
G01X49146Y436975D02*
Y439475D01*
X48646Y438975D01*
G01Y436975D02*
X49646D01*
G01X52246D02*
X52538Y437017D01*
X52871Y437142D01*
X53079Y437350D01*
X53163Y437642D01*
X53079Y437933D01*
X52829Y438183D01*
X52454Y438308D01*
X52038D01*
X51788Y438392D01*
X51579Y438600D01*
X51496Y438892D01*
X51621Y439183D01*
X51913Y439392D01*
X52246Y439475D01*
X52579Y439392D01*
X52871Y439183D01*
X52996Y438892D01*
X52913Y438600D01*
X52704Y438392D01*
X52454Y438308D01*
X52038D01*
X51663Y438183D01*
X51413Y437933D01*
X51329Y437642D01*
X51413Y437350D01*
X51621Y437142D01*
X51954Y437017D01*
X52246Y436975D01*
G01X11265Y449382D02*
Y451882D01*
X12306D01*
X12640Y451757D01*
X12848Y451590D01*
X12931Y451257D01*
X12848Y450924D01*
X12598Y450715D01*
X12306Y450590D01*
X11265D01*
G01X12306D02*
X12931Y449382D01*
G01X15198D02*
Y451882D01*
X14698Y451382D01*
G01Y449382D02*
X15698D01*
G01X18298Y451882D02*
X17965Y451799D01*
X17715Y451590D01*
X17548Y451340D01*
X17423Y451007D01*
X17381Y450632D01*
X17423Y450257D01*
X17548Y449924D01*
X17715Y449674D01*
X17965Y449465D01*
X18298Y449382D01*
X18631Y449465D01*
X18881Y449674D01*
X19048Y449924D01*
X19173Y450257D01*
X19215Y450632D01*
X19173Y451007D01*
X19048Y451340D01*
X18881Y451590D01*
X18631Y451799D01*
X18298Y451882D01*
G01X20148D02*
X20731Y449382D01*
X21398Y451882D01*
X22065Y449382D01*
X22648Y451882D01*
G01X24415Y449382D02*
X24498Y449924D01*
X24623Y450382D01*
X24790Y450799D01*
X24998Y451257D01*
X25331Y451882D01*
X23665D01*
G01X3880Y452970D02*
Y455470D01*
X4921D01*
X5255Y455345D01*
X5463Y455178D01*
X5546Y454845D01*
X5463Y454512D01*
X5213Y454303D01*
X4921Y454178D01*
X3880D01*
G01X4921D02*
X5546Y452970D01*
G01X7813D02*
Y455470D01*
X7313Y454970D01*
G01Y452970D02*
X8313D01*
G01X10913Y455470D02*
X10580Y455387D01*
X10330Y455178D01*
X10163Y454928D01*
X10038Y454595D01*
X9996Y454220D01*
X10038Y453845D01*
X10163Y453512D01*
X10330Y453262D01*
X10580Y453053D01*
X10913Y452970D01*
X11246Y453053D01*
X11496Y453262D01*
X11663Y453512D01*
X11788Y453845D01*
X11830Y454220D01*
X11788Y454595D01*
X11663Y454928D01*
X11496Y455178D01*
X11246Y455387D01*
X10913Y455470D01*
G01X12763D02*
X13346Y452970D01*
X14013Y455470D01*
X14680Y452970D01*
X15263Y455470D01*
G01X16321Y454012D02*
X16613Y454303D01*
X16863Y454470D01*
X17196Y454553D01*
X17488Y454470D01*
X17696Y454303D01*
X17863Y454053D01*
X17905Y453762D01*
X17863Y453512D01*
X17696Y453262D01*
X17446Y453053D01*
X17155Y452970D01*
X16821Y453053D01*
X16530Y453303D01*
X16363Y453678D01*
X16321Y454095D01*
X16405Y454637D01*
X16530Y454928D01*
X16738Y455220D01*
X17030Y455428D01*
X17321Y455470D01*
X17613Y455387D01*
X17821Y455178D01*
G01X36242Y424279D02*
X35992Y424404D01*
X35700Y424487D01*
X35367D01*
X34992Y424362D01*
X34700Y424154D01*
X34492Y423904D01*
X34325Y423487D01*
X34283Y423112D01*
X34367Y422737D01*
X34492Y422487D01*
X34742Y422237D01*
X35033Y422070D01*
X35325Y421987D01*
X35617D01*
X35908Y422070D01*
X36158Y422195D01*
X36367Y422362D01*
G01X37717Y422279D02*
X38008Y422070D01*
X38342Y421987D01*
X38675Y422070D01*
X38967Y422320D01*
X39175Y422695D01*
X39258Y423070D01*
Y423529D01*
X39175Y423904D01*
X38967Y424237D01*
X38717Y424404D01*
X38425Y424487D01*
X38092Y424404D01*
X37842Y424237D01*
X37675Y423987D01*
X37592Y423654D01*
X37675Y423362D01*
X37883Y423070D01*
X38133Y422904D01*
X38425Y422862D01*
X38758Y422945D01*
X39008Y423154D01*
X39258Y423529D01*
G01X40442Y421987D02*
Y424487D01*
X41525Y422404D01*
X42608Y424487D01*
Y421987D01*
G01X43708Y422362D02*
X43958Y422154D01*
X44250Y422029D01*
X44625Y421987D01*
X45000Y422070D01*
X45292Y422237D01*
X45500Y422529D01*
X45542Y422862D01*
X45458Y423195D01*
X45250Y423404D01*
X44958Y423570D01*
X44667Y423612D01*
X44375Y423570D01*
X44000Y423404D01*
X44125Y424487D01*
X45250D01*
G01X40663Y435031D02*
X40413Y435156D01*
X40121Y435239D01*
X39788D01*
X39413Y435114D01*
X39121Y434906D01*
X38913Y434656D01*
X38746Y434239D01*
X38704Y433864D01*
X38788Y433489D01*
X38913Y433239D01*
X39163Y432989D01*
X39454Y432822D01*
X39746Y432739D01*
X40038D01*
X40329Y432822D01*
X40579Y432947D01*
X40788Y433114D01*
G01X42846Y432739D02*
Y435239D01*
X42346Y434739D01*
G01Y432739D02*
X43346D01*
G01X46279Y434072D02*
X46446Y434197D01*
X46571Y434406D01*
X46654Y434697D01*
X46571Y434947D01*
X46404Y435114D01*
X46113Y435239D01*
X44988D01*
Y432739D01*
X46363D01*
X46654Y432906D01*
X46821Y433156D01*
X46904Y433447D01*
X46821Y433739D01*
X46571Y433989D01*
X46279Y434072D01*
X44988D01*
G01X49046Y432739D02*
Y435239D01*
X48546Y434739D01*
G01Y432739D02*
X49546D01*
G01X51438Y433031D02*
X51729Y432822D01*
X52063Y432739D01*
X52396Y432822D01*
X52688Y433072D01*
X52896Y433447D01*
X52979Y433822D01*
Y434281D01*
X52896Y434656D01*
X52688Y434989D01*
X52438Y435156D01*
X52146Y435239D01*
X51813Y435156D01*
X51563Y434989D01*
X51396Y434739D01*
X51313Y434406D01*
X51396Y434114D01*
X51604Y433822D01*
X51854Y433656D01*
X52146Y433614D01*
X52479Y433697D01*
X52729Y433906D01*
X52979Y434281D01*
G01X-3710Y455804D02*
X-7299D01*
Y453911D01*
X-10578Y455804D01*
X-7299Y457697D01*
Y455804D01*
G01X-10578Y457697D02*
Y453911D01*
G01X-15001Y455804D02*
X-10578D01*
G01X39810Y451752D02*
Y454252D01*
X40851D01*
X41185Y454127D01*
X41393Y453960D01*
X41476Y453627D01*
X41393Y453294D01*
X41143Y453085D01*
X40851Y452960D01*
X39810D01*
G01X40851D02*
X41476Y451752D01*
G01X43743D02*
Y454252D01*
X43243Y453752D01*
G01Y451752D02*
X44243D01*
G01X46843Y454252D02*
X46510Y454169D01*
X46260Y453960D01*
X46093Y453710D01*
X45968Y453377D01*
X45926Y453002D01*
X45968Y452627D01*
X46093Y452294D01*
X46260Y452044D01*
X46510Y451835D01*
X46843Y451752D01*
X47176Y451835D01*
X47426Y452044D01*
X47593Y452294D01*
X47718Y452627D01*
X47760Y453002D01*
X47718Y453377D01*
X47593Y453710D01*
X47426Y453960D01*
X47176Y454169D01*
X46843Y454252D01*
G01X48693D02*
X49276Y451752D01*
X49943Y454252D01*
X50610Y451752D01*
X51193Y454252D01*
G01X52126Y452127D02*
X52376Y451919D01*
X52668Y451794D01*
X53043Y451752D01*
X53418Y451835D01*
X53710Y452002D01*
X53918Y452294D01*
X53960Y452627D01*
X53876Y452960D01*
X53668Y453169D01*
X53376Y453335D01*
X53085Y453377D01*
X52793Y453335D01*
X52418Y453169D01*
X52543Y454252D01*
X53668D01*
G01X44812Y456554D02*
X66202D01*
Y480924D01*
X4822D01*
Y456554D01*
X36212D01*
G01X25482Y423908D02*
X25732Y424116D01*
X25899Y424366D01*
X25982Y424658D01*
X25899Y424991D01*
X25732Y425241D01*
X25482Y425491D01*
X25149Y425574D01*
X23482D01*
G01X25982Y427841D02*
X23482D01*
X23982Y427341D01*
G01X25982D02*
Y428341D01*
G01X23482Y430941D02*
X23565Y430608D01*
X23774Y430358D01*
X24024Y430191D01*
X24357Y430066D01*
X24732Y430024D01*
X25107Y430066D01*
X25440Y430191D01*
X25690Y430358D01*
X25899Y430608D01*
X25982Y430941D01*
X25899Y431274D01*
X25690Y431524D01*
X25440Y431691D01*
X25107Y431816D01*
X24732Y431858D01*
X24357Y431816D01*
X24024Y431691D01*
X23774Y431524D01*
X23565Y431274D01*
X23482Y430941D01*
G01Y432791D02*
X25982Y433374D01*
X23482Y434041D01*
X25982Y434708D01*
X23482Y435291D01*
G01X25982Y437141D02*
X23482D01*
X23982Y436641D01*
G01X25982D02*
Y437641D01*
G01X2267Y518667D02*
X5600Y525667D01*
X8933Y518667D01*
G01X7733Y521117D02*
X3467D01*
G01X17583Y482600D02*
Y485700D01*
X18503D01*
X18810Y485545D01*
X19040Y485183D01*
X19117Y484770D01*
X19040Y484357D01*
X18848Y484047D01*
X18503Y483892D01*
X17583D01*
G01X20607Y485700D02*
Y483478D01*
X20760Y483013D01*
X21067Y482703D01*
X21450Y482600D01*
X21833Y482703D01*
X22140Y483013D01*
X22293Y483478D01*
Y485700D01*
G01X23553Y482600D02*
Y485700D01*
X24550Y483117D01*
X25547Y485700D01*
Y482600D01*
G01X26883D02*
Y485700D01*
X27803D01*
X28110Y485545D01*
X28340Y485183D01*
X28417Y484770D01*
X28340Y484357D01*
X28148Y484047D01*
X27803Y483892D01*
X26883D01*
G01X29600Y481567D02*
X31900D01*
G01X33045Y482600D02*
Y485700D01*
G01X34655D02*
Y482600D01*
G01Y484150D02*
X33045D01*
G01X37717Y482600D02*
X36183D01*
Y485700D01*
X37717D01*
G01X37103Y484202D02*
X36183D01*
G01X39092Y482600D02*
X40050Y485700D01*
X41008Y482600D01*
G01X40663Y483685D02*
X39437D01*
G01X42307Y482600D02*
Y485700D01*
X43073D01*
X43380Y485545D01*
X43610Y485338D01*
X43802Y485028D01*
X43955Y484667D01*
X43993Y484150D01*
X43955Y483633D01*
X43802Y483272D01*
X43610Y482962D01*
X43380Y482755D01*
X43073Y482600D01*
X42307D01*
G01X47017D02*
X45483D01*
Y485700D01*
X47017D01*
G01X46403Y484202D02*
X45483D01*
G01X48583Y482600D02*
Y485700D01*
X49542D01*
X49848Y485545D01*
X50040Y485338D01*
X50117Y484925D01*
X50040Y484512D01*
X49810Y484253D01*
X49542Y484098D01*
X48583D01*
G01X49542D02*
X50117Y482600D01*
G01X32428Y503000D02*
Y488762D01*
X27631D01*
G01X18100Y489250D02*
X21100D01*
G01X7200Y483164D02*
X11058D01*
Y489200D01*
X12650D01*
G01X-5104Y468789D02*
X-5229Y468539D01*
X-5312Y468247D01*
Y467914D01*
X-5187Y467539D01*
X-4979Y467247D01*
X-4729Y467039D01*
X-4312Y466872D01*
X-3937Y466830D01*
X-3562Y466914D01*
X-3312Y467039D01*
X-3062Y467289D01*
X-2895Y467580D01*
X-2812Y467872D01*
Y468164D01*
X-2895Y468455D01*
X-3020Y468705D01*
X-3187Y468914D01*
G01X-2812Y470972D02*
X-5312D01*
X-4812Y470472D01*
G01X-2812D02*
Y471472D01*
G01X-5312Y474072D02*
X-5229Y473739D01*
X-5020Y473489D01*
X-4770Y473322D01*
X-4437Y473197D01*
X-4062Y473155D01*
X-3687Y473197D01*
X-3354Y473322D01*
X-3104Y473489D01*
X-2895Y473739D01*
X-2812Y474072D01*
X-2895Y474405D01*
X-3104Y474655D01*
X-3354Y474822D01*
X-3687Y474947D01*
X-4062Y474989D01*
X-4437Y474947D01*
X-4770Y474822D01*
X-5020Y474655D01*
X-5229Y474405D01*
X-5312Y474072D01*
G01Y475922D02*
X-2812Y476505D01*
X-5312Y477172D01*
X-2812Y477839D01*
X-5312Y478422D01*
G01X-3187Y479355D02*
X-2979Y479605D01*
X-2854Y479897D01*
X-2812Y480272D01*
X-2895Y480647D01*
X-3062Y480939D01*
X-3354Y481147D01*
X-3687Y481189D01*
X-4020Y481105D01*
X-4229Y480897D01*
X-4395Y480605D01*
X-4437Y480314D01*
X-4395Y480022D01*
X-4229Y479647D01*
X-5312Y479772D01*
Y480897D01*
G01X52Y480662D02*
X320Y481023D01*
X550Y481230D01*
X857Y481333D01*
X1125Y481230D01*
X1317Y481023D01*
X1470Y480713D01*
X1508Y480352D01*
X1470Y480042D01*
X1317Y479732D01*
X1087Y479473D01*
X818Y479370D01*
X512Y479473D01*
X243Y479783D01*
X90Y480248D01*
X52Y480765D01*
X128Y481437D01*
X243Y481798D01*
X435Y482160D01*
X703Y482418D01*
X972Y482470D01*
X1240Y482367D01*
X1432Y482108D01*
G01X30870Y509085D02*
X26870D01*
Y501685D01*
G01X52000Y510150D02*
X30000D01*
Y527850D01*
X52000D01*
Y510150D01*
G01X46724Y488052D02*
X41524D01*
G01X46724Y495052D02*
X38924D01*
G01X33324Y488052D02*
X42024D01*
G01X33324Y495052D02*
Y488052D01*
G01X39724Y495052D02*
X33324D01*
G01X35061Y505358D02*
Y507858D01*
X36102D01*
X36436Y507733D01*
X36644Y507566D01*
X36727Y507233D01*
X36644Y506900D01*
X36394Y506691D01*
X36102Y506566D01*
X35061D01*
G01X36102D02*
X36727Y505358D01*
G01X38994D02*
Y507858D01*
X38494Y507358D01*
G01Y505358D02*
X39494D01*
G01X41302Y507441D02*
X41552Y507691D01*
X41844Y507816D01*
X42177Y507858D01*
X42594Y507775D01*
X42886Y507566D01*
X42969Y507316D01*
X42927Y507066D01*
X42761Y506858D01*
X41927Y506441D01*
X41552Y506150D01*
X41302Y505733D01*
X41219Y505358D01*
X42969D01*
G01X43944Y507858D02*
X44527Y505358D01*
X45194Y507858D01*
X45861Y505358D01*
X46444Y507858D01*
G01X48294Y505358D02*
Y507858D01*
X47794Y507358D01*
G01Y505358D02*
X48794D01*
G01X50602Y506400D02*
X50894Y506691D01*
X51144Y506858D01*
X51477Y506941D01*
X51769Y506858D01*
X51977Y506691D01*
X52144Y506441D01*
X52186Y506150D01*
X52144Y505900D01*
X51977Y505650D01*
X51727Y505441D01*
X51436Y505358D01*
X51102Y505441D01*
X50811Y505691D01*
X50644Y506066D01*
X50602Y506483D01*
X50686Y507025D01*
X50811Y507316D01*
X51019Y507608D01*
X51311Y507816D01*
X51602Y507858D01*
X51894Y507775D01*
X52102Y507566D01*
G01X46782Y495819D02*
X41582D01*
G01X46782Y502819D02*
X38982D01*
G01X33382Y495819D02*
X42082D01*
G01X33382Y502819D02*
Y495819D01*
G01X39782Y502819D02*
X33382D01*
G01X20150Y515850D02*
Y491750D01*
X-3950D01*
Y515850D01*
X20150D01*
G01X17130Y513839D02*
X18139D01*
Y512657D01*
G01X-1939Y512767D02*
Y513839D01*
G01X-693Y493761D02*
X-1939D01*
Y494943D01*
G01X18139Y494959D02*
Y493761D01*
X16991D01*
G01X-1939Y513839D02*
X-826D01*
G01X-5900Y569800D02*
Y572400D01*
G01X18200Y566000D02*
X-5900D01*
Y567200D01*
G01Y576300D02*
Y581399D01*
X-5901Y581400D01*
X-14003D01*
G01X6977Y561005D02*
X13731D01*
Y556917D01*
X15200D01*
G01X-9402Y556858D02*
X-2740D01*
Y558576D01*
X5051D01*
G01X25000Y567800D02*
Y590899D01*
X25001Y590900D01*
X26300D01*
G01X23980Y555700D02*
Y532983D01*
X23979D01*
Y532697D01*
X25274D01*
Y530705D01*
X30000D01*
Y528748D01*
G01X-13498Y558107D02*
X-13623Y557857D01*
X-13706Y557565D01*
Y557232D01*
X-13581Y556857D01*
X-13373Y556565D01*
X-13123Y556357D01*
X-12706Y556190D01*
X-12331Y556148D01*
X-11956Y556232D01*
X-11706Y556357D01*
X-11456Y556607D01*
X-11289Y556898D01*
X-11206Y557190D01*
Y557482D01*
X-11289Y557773D01*
X-11414Y558023D01*
X-11581Y558232D01*
G01X-11206Y560290D02*
X-13706D01*
X-13206Y559790D01*
G01X-11206D02*
Y560790D01*
G01Y562348D02*
X-13706Y563390D01*
X-11206Y564432D01*
G01X-12081Y564057D02*
Y562723D01*
G01X-12248Y565698D02*
X-12539Y565990D01*
X-12706Y566240D01*
X-12789Y566573D01*
X-12706Y566865D01*
X-12539Y567073D01*
X-12289Y567240D01*
X-11998Y567282D01*
X-11748Y567240D01*
X-11498Y567073D01*
X-11289Y566823D01*
X-11206Y566532D01*
X-11289Y566198D01*
X-11539Y565907D01*
X-11914Y565740D01*
X-12331Y565698D01*
X-12873Y565782D01*
X-13164Y565907D01*
X-13456Y566115D01*
X-13664Y566407D01*
X-13706Y566698D01*
X-13623Y566990D01*
X-13414Y567198D01*
G01X-6818Y562214D02*
X-7068Y562339D01*
X-7360Y562422D01*
X-7693D01*
X-8068Y562297D01*
X-8360Y562089D01*
X-8568Y561839D01*
X-8735Y561422D01*
X-8777Y561047D01*
X-8693Y560672D01*
X-8568Y560422D01*
X-8318Y560172D01*
X-8027Y560005D01*
X-7735Y559922D01*
X-7443D01*
X-7152Y560005D01*
X-6902Y560130D01*
X-6693Y560297D01*
G01X-4635Y559922D02*
Y562422D01*
X-5135Y561922D01*
G01Y559922D02*
X-4135D01*
G01X-2577D02*
X-1535Y562422D01*
X-493Y559922D01*
G01X-868Y560797D02*
X-2202D01*
G01X1565Y559922D02*
Y562422D01*
X1065Y561922D01*
G01Y559922D02*
X2065D01*
G01X3748Y560422D02*
X3998Y560130D01*
X4332Y559964D01*
X4707Y559922D01*
X5040Y559964D01*
X5373Y560172D01*
X5582Y560422D01*
X5623Y560672D01*
X5540Y560964D01*
X5248Y561172D01*
X4957Y561255D01*
X4582D01*
G01X4957D02*
X5207Y561380D01*
X5415Y561589D01*
X5498Y561839D01*
X5415Y562089D01*
X5207Y562297D01*
X4832Y562422D01*
X4457Y562380D01*
X4082Y562214D01*
G01X35479Y560284D02*
X35229Y560409D01*
X34937Y560492D01*
X34604D01*
X34229Y560367D01*
X33937Y560159D01*
X33729Y559909D01*
X33562Y559492D01*
X33520Y559117D01*
X33604Y558742D01*
X33729Y558492D01*
X33979Y558242D01*
X34270Y558075D01*
X34562Y557992D01*
X34854D01*
X35145Y558075D01*
X35395Y558200D01*
X35604Y558367D01*
G01X37662Y560492D02*
Y557992D01*
G01X36704Y560492D02*
X38620D01*
G01X40762Y557992D02*
Y560492D01*
X40262Y559992D01*
G01Y557992D02*
X41262D01*
G01X43862D02*
Y560492D01*
X43362Y559992D01*
G01Y557992D02*
X44362D01*
G01X17614Y556770D02*
Y559270D01*
X18655D01*
X18989Y559145D01*
X19197Y558978D01*
X19280Y558645D01*
X19197Y558312D01*
X18947Y558103D01*
X18655Y557978D01*
X17614D01*
G01X18655D02*
X19280Y556770D01*
G01X21547Y559270D02*
Y556770D01*
G01X20589Y559270D02*
X22505D01*
G01X24564Y556770D02*
X24647Y557312D01*
X24772Y557770D01*
X24939Y558187D01*
X25147Y558645D01*
X25480Y559270D01*
X23814D01*
G01X22939Y532183D02*
X-4361D01*
Y555733D01*
X22939D01*
Y532183D01*
G01Y568183D02*
X-4361D01*
Y591733D01*
X22939D01*
Y568183D01*
G01X66450Y573450D02*
Y567402D01*
X29050D01*
Y573450D01*
G01Y586550D02*
Y592598D01*
G01X66050Y537550D02*
Y531502D01*
X28650D01*
Y537550D01*
G01Y550650D02*
Y556698D01*
G01D02*
X66050D01*
Y550650D01*
G01X-2400Y594200D02*
Y595300D01*
X7100D01*
G01X41400Y602900D02*
Y597300D01*
X43800D01*
G01X42400Y607800D02*
X44000D01*
G01X33800D02*
X30000D01*
G01X26800Y600700D02*
X28300D01*
Y603000D01*
G01X22800Y596700D02*
X25300D01*
Y599000D01*
G01X11000Y594400D02*
X19000D01*
G01X20556Y593265D02*
Y595765D01*
X21597D01*
X21931Y595640D01*
X22139Y595473D01*
X22222Y595140D01*
X22139Y594807D01*
X21889Y594598D01*
X21597Y594473D01*
X20556D01*
G01X21597D02*
X22222Y593265D01*
G01X24489Y595765D02*
Y593265D01*
G01X23531Y595765D02*
X25447D01*
G01X27589Y593265D02*
X27881Y593307D01*
X28214Y593432D01*
X28422Y593640D01*
X28506Y593932D01*
X28422Y594223D01*
X28172Y594473D01*
X27797Y594598D01*
X27381D01*
X27131Y594682D01*
X26922Y594890D01*
X26839Y595182D01*
X26964Y595473D01*
X27256Y595682D01*
X27589Y595765D01*
X27922Y595682D01*
X28214Y595473D01*
X28339Y595182D01*
X28256Y594890D01*
X28047Y594682D01*
X27797Y594598D01*
X27381D01*
X27006Y594473D01*
X26756Y594223D01*
X26672Y593932D01*
X26756Y593640D01*
X26964Y593432D01*
X27297Y593307D01*
X27589Y593265D01*
G01X31629Y606378D02*
X31379Y606503D01*
X31087Y606586D01*
X30754D01*
X30379Y606461D01*
X30087Y606253D01*
X29879Y606003D01*
X29712Y605586D01*
X29670Y605211D01*
X29754Y604836D01*
X29879Y604586D01*
X30129Y604336D01*
X30420Y604169D01*
X30712Y604086D01*
X31004D01*
X31295Y604169D01*
X31545Y604294D01*
X31754Y604461D01*
G01X33812Y604086D02*
Y606586D01*
X33312Y606086D01*
G01Y604086D02*
X34312D01*
G01X35870D02*
X36912Y606586D01*
X37954Y604086D01*
G01X37579Y604961D02*
X36245D01*
G01X39220Y606169D02*
X39470Y606419D01*
X39762Y606544D01*
X40095Y606586D01*
X40512Y606503D01*
X40804Y606294D01*
X40887Y606044D01*
X40845Y605794D01*
X40679Y605586D01*
X39845Y605169D01*
X39470Y604878D01*
X39220Y604461D01*
X39137Y604086D01*
X40887D01*
G01X43112Y606586D02*
X42779Y606503D01*
X42529Y606294D01*
X42362Y606044D01*
X42237Y605711D01*
X42195Y605336D01*
X42237Y604961D01*
X42362Y604628D01*
X42529Y604378D01*
X42779Y604169D01*
X43112Y604086D01*
X43445Y604169D01*
X43695Y604378D01*
X43862Y604628D01*
X43987Y604961D01*
X44029Y605336D01*
X43987Y605711D01*
X43862Y606044D01*
X43695Y606294D01*
X43445Y606503D01*
X43112Y606586D01*
G01X31067Y602792D02*
X30817Y602917D01*
X30525Y603000D01*
X30192D01*
X29817Y602875D01*
X29525Y602667D01*
X29317Y602417D01*
X29150Y602000D01*
X29108Y601625D01*
X29192Y601250D01*
X29317Y601000D01*
X29567Y600750D01*
X29858Y600583D01*
X30150Y600500D01*
X30442D01*
X30733Y600583D01*
X30983Y600708D01*
X31192Y600875D01*
G01X33250Y600500D02*
Y603000D01*
X32750Y602500D01*
G01Y600500D02*
X33750D01*
G01X35308D02*
X36350Y603000D01*
X37392Y600500D01*
G01X37017Y601375D02*
X35683D01*
G01X38742Y600792D02*
X39033Y600583D01*
X39367Y600500D01*
X39700Y600583D01*
X39992Y600833D01*
X40200Y601208D01*
X40283Y601583D01*
Y602042D01*
X40200Y602417D01*
X39992Y602750D01*
X39742Y602917D01*
X39450Y603000D01*
X39117Y602917D01*
X38867Y602750D01*
X38700Y602500D01*
X38617Y602167D01*
X38700Y601875D01*
X38908Y601583D01*
X39158Y601417D01*
X39450Y601375D01*
X39783Y601458D01*
X40033Y601667D01*
X40283Y602042D01*
G01X28168Y599264D02*
X27918Y599389D01*
X27626Y599472D01*
X27293D01*
X26918Y599347D01*
X26626Y599139D01*
X26418Y598889D01*
X26251Y598472D01*
X26209Y598097D01*
X26293Y597722D01*
X26418Y597472D01*
X26668Y597222D01*
X26959Y597055D01*
X27251Y596972D01*
X27543D01*
X27834Y597055D01*
X28084Y597180D01*
X28293Y597347D01*
G01X30351Y596972D02*
Y599472D01*
X29851Y598972D01*
G01Y596972D02*
X30851D01*
G01X32409D02*
X33451Y599472D01*
X34493Y596972D01*
G01X34118Y597847D02*
X32784D01*
G01X36551Y596972D02*
X36843Y597014D01*
X37176Y597139D01*
X37384Y597347D01*
X37468Y597639D01*
X37384Y597930D01*
X37134Y598180D01*
X36759Y598305D01*
X36343D01*
X36093Y598389D01*
X35884Y598597D01*
X35801Y598889D01*
X35926Y599180D01*
X36218Y599389D01*
X36551Y599472D01*
X36884Y599389D01*
X37176Y599180D01*
X37301Y598889D01*
X37218Y598597D01*
X37009Y598389D01*
X36759Y598305D01*
X36343D01*
X35968Y598180D01*
X35718Y597930D01*
X35634Y597639D01*
X35718Y597347D01*
X35926Y597139D01*
X36259Y597014D01*
X36551Y596972D01*
G01X30276Y622821D02*
Y620321D01*
G01X29318Y622821D02*
X31234D01*
G01X32501Y620321D02*
Y622821D01*
G01X34251D02*
Y620321D01*
G01Y621571D02*
X32501D01*
G01X36476Y620321D02*
Y622821D01*
X35976Y622321D01*
G01Y620321D02*
X36976D01*
G01X38534D02*
X39576Y622821D01*
X40618Y620321D01*
G01X40243Y621196D02*
X38909D01*
G01X42676Y620321D02*
Y622821D01*
X42176Y622321D01*
G01Y620321D02*
X43176D01*
G01X33144Y593517D02*
X31478D01*
Y596017D01*
X33144D01*
G01X32478Y594809D02*
X31478D01*
G01X34494Y596017D02*
Y594225D01*
X34661Y593850D01*
X34994Y593600D01*
X35411Y593517D01*
X35828Y593600D01*
X36161Y593850D01*
X36328Y594225D01*
Y596017D01*
G01X38511Y593517D02*
Y596017D01*
X38011Y595517D01*
G01Y593517D02*
X39011D01*
G01X40569D02*
X41611Y596017D01*
X42653Y593517D01*
G01X42278Y594392D02*
X40944D01*
G01X44711Y593517D02*
Y596017D01*
X44211Y595517D01*
G01Y593517D02*
X45211D01*
G01X29050Y592598D02*
X66450D01*
Y586550D01*
G01X38860Y659070D02*
X71560D01*
Y640370D01*
X38860D01*
Y659070D01*
G01X64500Y-38250D02*
Y-46250D01*
X46500D01*
Y-38250D01*
X64500D01*
G01X84500D02*
Y-46250D01*
X66500D01*
Y-38250D01*
X84500D01*
G01X104500D02*
Y-46250D01*
X86500D01*
Y-38250D01*
X104500D01*
G01X124500D02*
Y-46250D01*
X106500D01*
Y-38250D01*
X124500D01*
G01X64500Y-48250D02*
Y-56250D01*
X46500D01*
Y-48250D01*
X64500D01*
G01X84500D02*
Y-56250D01*
X66500D01*
Y-48250D01*
X84500D01*
G01X104500D02*
Y-56250D01*
X86500D01*
Y-48250D01*
X104500D01*
G01X124500D02*
Y-56250D01*
X106500D01*
Y-48250D01*
X124500D01*
G01X64060Y-14265D02*
X67393Y-7265D01*
X70726Y-14265D01*
G01X69526Y-11815D02*
X65260D01*
G01X72660Y-14265D02*
X75993Y-7265D01*
X79326Y-14265D01*
G01X78126Y-11815D02*
X73860D01*
G01X54601Y500D02*
X54600Y499D01*
G01X90399Y18389D02*
X80505D01*
Y21500D01*
X54500D01*
G01X117400Y9140D02*
Y7786D01*
X98891D01*
G01X126700Y10750D02*
X128280D01*
Y18389D01*
X97805D01*
G01X93903Y-21717D02*
X94111Y-21967D01*
X94361Y-22134D01*
X94653Y-22217D01*
X94986Y-22134D01*
X95236Y-21967D01*
X95486Y-21717D01*
X95569Y-21384D01*
Y-19717D01*
G01X97836Y-22217D02*
Y-19717D01*
X97336Y-20217D01*
G01Y-22217D02*
X98336D01*
G01X101186Y-20967D02*
X102019D01*
Y-21717D01*
X101769Y-21967D01*
X101478Y-22134D01*
X101061Y-22217D01*
X100644Y-22134D01*
X100353Y-21967D01*
X100103Y-21717D01*
X99936Y-21425D01*
X99853Y-21092D01*
Y-20800D01*
X99936Y-20550D01*
X100103Y-20259D01*
X100353Y-20009D01*
X100603Y-19842D01*
X100936Y-19717D01*
X101228D01*
X101561Y-19800D01*
X101811Y-19967D01*
G01X103119Y-21717D02*
X103369Y-22009D01*
X103703Y-22175D01*
X104078Y-22217D01*
X104411Y-22175D01*
X104744Y-21967D01*
X104953Y-21717D01*
X104994Y-21467D01*
X104911Y-21175D01*
X104619Y-20967D01*
X104328Y-20884D01*
X103953D01*
G01X104328D02*
X104578Y-20759D01*
X104786Y-20550D01*
X104869Y-20300D01*
X104786Y-20050D01*
X104578Y-19842D01*
X104203Y-19717D01*
X103828Y-19759D01*
X103453Y-19925D01*
G01X111100Y-18617D02*
X86710D01*
Y6973D01*
X111100D01*
G01X84887Y20395D02*
X85137Y20603D01*
X85304Y20853D01*
X85387Y21145D01*
X85304Y21478D01*
X85137Y21728D01*
X84887Y21978D01*
X84554Y22061D01*
X82887D01*
G01X85387Y24328D02*
X82887D01*
X83387Y23828D01*
G01X85387D02*
Y24828D01*
G01X84137Y27678D02*
Y28511D01*
X84887D01*
X85137Y28261D01*
X85304Y27970D01*
X85387Y27553D01*
X85304Y27136D01*
X85137Y26845D01*
X84887Y26595D01*
X84595Y26428D01*
X84262Y26345D01*
X83970D01*
X83720Y26428D01*
X83429Y26595D01*
X83179Y26845D01*
X83012Y27095D01*
X82887Y27428D01*
Y27720D01*
X82970Y28053D01*
X83137Y28303D01*
G01X83304Y29736D02*
X83054Y29986D01*
X82929Y30278D01*
X82887Y30611D01*
X82970Y31028D01*
X83179Y31320D01*
X83429Y31403D01*
X83679Y31361D01*
X83887Y31195D01*
X84304Y30361D01*
X84595Y29986D01*
X85012Y29736D01*
X85387Y29653D01*
Y31403D01*
G01X111100Y19183D02*
X86710D01*
Y44773D01*
X111100D01*
G01X49539Y-10005D02*
Y-11014D01*
X48357D01*
G01X48467Y9064D02*
X49539D01*
G01D02*
Y7951D01*
G01X60700Y91195D02*
Y95939D01*
G01X46610Y152467D02*
X50402D01*
Y139670D01*
X52949D01*
Y89847D01*
X59510D01*
G01X85033Y63214D02*
X85283Y63422D01*
X85450Y63672D01*
X85533Y63964D01*
X85450Y64297D01*
X85283Y64547D01*
X85033Y64797D01*
X84700Y64880D01*
X83033D01*
G01X85533Y67147D02*
X83033D01*
X83533Y66647D01*
G01X85533D02*
Y67647D01*
G01X84283Y70497D02*
Y71330D01*
X85033D01*
X85283Y71080D01*
X85450Y70789D01*
X85533Y70372D01*
X85450Y69955D01*
X85283Y69664D01*
X85033Y69414D01*
X84741Y69247D01*
X84408Y69164D01*
X84116D01*
X83866Y69247D01*
X83575Y69414D01*
X83325Y69664D01*
X83158Y69914D01*
X83033Y70247D01*
Y70539D01*
X83116Y70872D01*
X83283Y71122D01*
G01X85533Y73347D02*
X83033D01*
X83533Y72847D01*
G01X85533D02*
Y73847D01*
G01X111100Y56983D02*
X86710D01*
Y82573D01*
X111100D01*
G01X80833Y37017D02*
X83333D01*
Y38683D01*
G01Y40950D02*
X80833D01*
X81333Y40450D01*
G01X83333D02*
Y41450D01*
G01X82083Y44300D02*
Y45133D01*
X82833D01*
X83083Y44883D01*
X83250Y44592D01*
X83333Y44175D01*
X83250Y43758D01*
X83083Y43467D01*
X82833Y43217D01*
X82541Y43050D01*
X82208Y42967D01*
X81916D01*
X81666Y43050D01*
X81375Y43217D01*
X81125Y43467D01*
X80958Y43717D01*
X80833Y44050D01*
Y44342D01*
X80916Y44675D01*
X81083Y44925D01*
G01X83333Y47150D02*
X80833D01*
X81333Y46650D01*
G01X83333D02*
Y47650D01*
G01X66017Y79667D02*
Y77167D01*
X67683D01*
G01X69950D02*
Y79667D01*
X69450Y79167D01*
G01Y77167D02*
X70450D01*
G01X72258D02*
Y79667D01*
X73842D01*
G01X73258Y78459D02*
X72258D01*
G01X75358Y79250D02*
X75608Y79500D01*
X75900Y79625D01*
X76233Y79667D01*
X76650Y79584D01*
X76942Y79375D01*
X77025Y79125D01*
X76983Y78875D01*
X76817Y78667D01*
X75983Y78250D01*
X75608Y77959D01*
X75358Y77542D01*
X75275Y77167D01*
X77025D01*
G01X90034Y95861D02*
Y98961D01*
X90954D01*
X91261Y98806D01*
X91491Y98444D01*
X91568Y98031D01*
X91491Y97618D01*
X91299Y97308D01*
X90954Y97153D01*
X90034D01*
G01X92751Y98961D02*
X93288Y95861D01*
X93901Y98961D01*
X94514Y95861D01*
X95051Y98961D01*
G01X96234Y95861D02*
Y98961D01*
X97193D01*
X97499Y98806D01*
X97691Y98599D01*
X97768Y98186D01*
X97691Y97773D01*
X97461Y97514D01*
X97193Y97359D01*
X96234D01*
G01X97193D02*
X97768Y95861D01*
G01X102396Y96274D02*
X102703Y96016D01*
X103048Y95861D01*
X103354D01*
X103661Y96016D01*
X103891Y96274D01*
X104006Y96636D01*
X103929Y96998D01*
X103738Y97308D01*
X103393Y97514D01*
X102933Y97618D01*
X102664Y97824D01*
X102549Y98186D01*
X102626Y98548D01*
X102818Y98806D01*
X103086Y98961D01*
X103354D01*
X103623Y98858D01*
X103853Y98599D01*
G01X105841Y98961D02*
X106761D01*
G01X106301D02*
Y95861D01*
G01X105841D02*
X106761D01*
G01X108558D02*
Y98961D01*
X109324D01*
X109631Y98806D01*
X109861Y98599D01*
X110053Y98289D01*
X110206Y97928D01*
X110244Y97411D01*
X110206Y96894D01*
X110053Y96533D01*
X109861Y96223D01*
X109631Y96016D01*
X109324Y95861D01*
X108558D01*
G01X113268D02*
X111734D01*
Y98961D01*
X113268D01*
G01X112654Y97463D02*
X111734D01*
G01X115908Y97514D02*
X116061Y97669D01*
X116176Y97928D01*
X116253Y98289D01*
X116176Y98599D01*
X116023Y98806D01*
X115754Y98961D01*
X114719D01*
Y95861D01*
X115984D01*
X116253Y96068D01*
X116406Y96378D01*
X116483Y96739D01*
X116406Y97101D01*
X116176Y97411D01*
X115908Y97514D01*
X114719D01*
G01X117743Y95861D02*
X118701Y98961D01*
X119659Y95861D01*
G01X119314Y96946D02*
X118088D01*
G01X120919Y95861D02*
Y98961D01*
X122683Y95861D01*
Y98961D01*
G01X124058Y95861D02*
Y98961D01*
X124824D01*
X125131Y98806D01*
X125361Y98599D01*
X125553Y98289D01*
X125706Y97928D01*
X125744Y97411D01*
X125706Y96894D01*
X125553Y96533D01*
X125361Y96223D01*
X125131Y96016D01*
X124824Y95861D01*
X124058D01*
G01X59000Y153100D02*
X61667D01*
Y151000D01*
X60867Y150300D01*
X59933Y149833D01*
X58600Y149600D01*
X57267Y149833D01*
X56333Y150300D01*
X55533Y151000D01*
X55000Y151817D01*
X54733Y152750D01*
Y153567D01*
X55000Y154267D01*
X55533Y155083D01*
X56333Y155783D01*
X57133Y156250D01*
X58200Y156600D01*
X59133D01*
X60200Y156367D01*
X61000Y155900D01*
G01X51880Y97782D02*
X48780Y98740D01*
X51880Y99698D01*
G01X50795Y99353D02*
Y98127D01*
G01X48780Y101380D02*
Y102300D01*
G01Y101840D02*
X51880D01*
G01Y101380D02*
Y102300D01*
G01Y104173D02*
X48780D01*
Y105132D01*
X48935Y105438D01*
X49142Y105630D01*
X49555Y105707D01*
X49968Y105630D01*
X50227Y105400D01*
X50382Y105132D01*
Y104173D01*
G01Y105132D02*
X51880Y105707D01*
G01Y107043D02*
X48780D01*
X51363Y108040D01*
X48780Y109037D01*
X51880D01*
G01Y110182D02*
X48780Y111140D01*
X51880Y112098D01*
G01X50795Y111753D02*
Y110527D01*
G01X51880Y113435D02*
X48780Y115045D01*
G01Y113435D02*
X51880Y115045D01*
G01Y119482D02*
X48780Y120440D01*
X51880Y121398D01*
G01X50795Y121053D02*
Y119827D01*
G01X60700Y99100D02*
Y101400D01*
G01X53750Y158598D02*
X64309D01*
X64310Y158597D01*
Y130162D01*
X106400D01*
Y114701D01*
X106399Y114700D01*
X60701D01*
X60700Y114699D01*
Y113200D01*
G01Y104429D02*
Y110400D01*
G01X76243Y128149D02*
Y123726D01*
G01X78136D02*
X74350D01*
G01X76243Y116858D02*
Y120447D01*
X74350D01*
X76243Y123726D01*
X78136Y120447D01*
X76243D01*
G01X90243Y128649D02*
Y124226D01*
G01X92136D02*
X88350D01*
G01X90243Y117358D02*
Y120947D01*
X88350D01*
X90243Y124226D01*
X92136Y120947D01*
X90243D01*
G01X83243Y116858D02*
Y120447D01*
X81350D01*
X83243Y123726D01*
X85136Y120447D01*
X83243D01*
G01X85136Y123726D02*
X81350D01*
G01X83243Y128149D02*
Y123726D01*
G01X110500Y115650D02*
X110448Y115918D01*
X110293Y116225D01*
X110035Y116417D01*
X109673Y116493D01*
X109312Y116417D01*
X109002Y116187D01*
X108847Y115842D01*
Y115458D01*
X108743Y115228D01*
X108485Y115037D01*
X108123Y114960D01*
X107762Y115075D01*
X107503Y115343D01*
X107400Y115650D01*
X107503Y115957D01*
X107762Y116225D01*
X108123Y116340D01*
X108485Y116263D01*
X108743Y116072D01*
X108847Y115842D01*
Y115458D01*
X109002Y115113D01*
X109312Y114883D01*
X109673Y114807D01*
X110035Y114883D01*
X110293Y115075D01*
X110448Y115382D01*
X110500Y115650D01*
G01X75597Y96760D02*
X75805Y96510D01*
X76055Y96343D01*
X76347Y96260D01*
X76680Y96343D01*
X76930Y96510D01*
X77180Y96760D01*
X77263Y97093D01*
Y98760D01*
G01X79530Y96260D02*
Y98760D01*
X79030Y98260D01*
G01Y96260D02*
X80030D01*
G01X81838D02*
Y98760D01*
X83422D01*
G01X82838Y97552D02*
X81838D01*
G01X84813Y96760D02*
X85063Y96468D01*
X85397Y96302D01*
X85772Y96260D01*
X86105Y96302D01*
X86438Y96510D01*
X86647Y96760D01*
X86688Y97010D01*
X86605Y97302D01*
X86313Y97510D01*
X86022Y97593D01*
X85647D01*
G01X86022D02*
X86272Y97718D01*
X86480Y97927D01*
X86563Y98177D01*
X86480Y98427D01*
X86272Y98635D01*
X85897Y98760D01*
X85522Y98718D01*
X85147Y98552D01*
G01X66501Y100157D02*
Y113543D01*
X113548D01*
Y100157D01*
X66501D01*
G01X49119Y139927D02*
X49369Y140135D01*
X49536Y140385D01*
X49619Y140677D01*
X49536Y141010D01*
X49369Y141260D01*
X49119Y141510D01*
X48786Y141593D01*
X47119D01*
G01X49619Y143860D02*
X47119D01*
X47619Y143360D01*
G01X49619D02*
Y144360D01*
G01Y146168D02*
X47119D01*
Y147752D01*
G01X48327Y147168D02*
Y146168D01*
G01X49619Y150060D02*
X47119D01*
X47619Y149560D01*
G01X49619D02*
Y150560D01*
G01X81544Y139295D02*
X81794Y139503D01*
X81961Y139753D01*
X82044Y140045D01*
X81961Y140378D01*
X81794Y140628D01*
X81544Y140878D01*
X81211Y140961D01*
X79544D01*
G01X82044Y143228D02*
X79544D01*
X80044Y142728D01*
G01X82044D02*
Y143728D01*
G01Y145536D02*
X79544D01*
Y147120D01*
G01X80752Y146536D02*
Y145536D01*
G01X79961Y148636D02*
X79711Y148886D01*
X79586Y149178D01*
X79544Y149511D01*
X79627Y149928D01*
X79836Y150220D01*
X80086Y150303D01*
X80336Y150261D01*
X80544Y150095D01*
X80961Y149261D01*
X81252Y148886D01*
X81669Y148636D01*
X82044Y148553D01*
Y150303D01*
G01X83980Y133631D02*
Y157831D01*
X125980D01*
Y133631D01*
X83980D01*
G01X46314Y160405D02*
X52476D01*
Y159220D01*
G01X103896Y161836D02*
X103771Y161586D01*
X103688Y161294D01*
Y160961D01*
X103813Y160586D01*
X104021Y160294D01*
X104271Y160086D01*
X104688Y159919D01*
X105063Y159877D01*
X105438Y159961D01*
X105688Y160086D01*
X105938Y160336D01*
X106105Y160627D01*
X106188Y160919D01*
Y161211D01*
X106105Y161502D01*
X105980Y161752D01*
X105813Y161961D01*
G01X106188Y164019D02*
X103688D01*
X104188Y163519D01*
G01X106188D02*
Y164519D01*
G01Y167952D02*
Y166286D01*
X103688D01*
Y167952D01*
G01X104896Y167286D02*
Y166286D01*
G01X104105Y169427D02*
X103855Y169677D01*
X103730Y169969D01*
X103688Y170302D01*
X103771Y170719D01*
X103980Y171011D01*
X104230Y171094D01*
X104480Y171052D01*
X104688Y170886D01*
X105105Y170052D01*
X105396Y169677D01*
X105813Y169427D01*
X106188Y169344D01*
Y171094D01*
G01Y173319D02*
X103688D01*
X104188Y172819D01*
G01X106188D02*
Y173819D01*
G01X68732Y217524D02*
X68482Y217649D01*
X68190Y217732D01*
X67857D01*
X67482Y217607D01*
X67190Y217399D01*
X66982Y217149D01*
X66815Y216732D01*
X66773Y216357D01*
X66857Y215982D01*
X66982Y215732D01*
X67232Y215482D01*
X67523Y215315D01*
X67815Y215232D01*
X68107D01*
X68398Y215315D01*
X68648Y215440D01*
X68857Y215607D01*
G01X70915Y215232D02*
Y217732D01*
X70415Y217232D01*
G01Y215232D02*
X71415D01*
G01X74848D02*
X73182D01*
Y217732D01*
X74848D01*
G01X74182Y216524D02*
X73182D01*
G01X77115Y215232D02*
Y217732D01*
X76615Y217232D01*
G01Y215232D02*
X77615D01*
G01X79423Y217315D02*
X79673Y217565D01*
X79965Y217690D01*
X80298Y217732D01*
X80715Y217649D01*
X81007Y217440D01*
X81090Y217190D01*
X81048Y216940D01*
X80882Y216732D01*
X80048Y216315D01*
X79673Y216024D01*
X79423Y215607D01*
X79340Y215232D01*
X81090D01*
G01X64440Y183607D02*
Y186107D01*
X65481D01*
X65815Y185982D01*
X66023Y185815D01*
X66106Y185482D01*
X66023Y185149D01*
X65773Y184940D01*
X65481Y184815D01*
X64440D01*
G01X65481D02*
X66106Y183607D01*
G01X68373D02*
Y186107D01*
X67873Y185607D01*
G01Y183607D02*
X68873D01*
G01X72306D02*
X70640D01*
Y186107D01*
X72306D01*
G01X71640Y184899D02*
X70640D01*
G01X74573Y183607D02*
Y186107D01*
X74073Y185607D01*
G01Y183607D02*
X75073D01*
G01X77673D02*
Y186107D01*
X77173Y185607D01*
G01Y183607D02*
X78173D01*
G01X85436Y164786D02*
X82936D01*
Y165827D01*
X83061Y166161D01*
X83228Y166369D01*
X83561Y166452D01*
X83894Y166369D01*
X84103Y166119D01*
X84228Y165827D01*
Y164786D01*
G01Y165827D02*
X85436Y166452D01*
G01Y168719D02*
X82936D01*
X83436Y168219D01*
G01X85436D02*
Y169219D01*
G01Y172652D02*
Y170986D01*
X82936D01*
Y172652D01*
G01X84144Y171986D02*
Y170986D01*
G01X85436Y174919D02*
X82936D01*
X83436Y174419D01*
G01X85436D02*
Y175419D01*
G01X83353Y177227D02*
X83103Y177477D01*
X82978Y177769D01*
X82936Y178102D01*
X83019Y178519D01*
X83228Y178811D01*
X83478Y178894D01*
X83728Y178852D01*
X83936Y178686D01*
X84353Y177852D01*
X84644Y177477D01*
X85061Y177227D01*
X85436Y177144D01*
Y178894D01*
G01X98740Y214785D02*
Y217285D01*
X99781D01*
X100115Y217160D01*
X100323Y216993D01*
X100406Y216660D01*
X100323Y216327D01*
X100073Y216118D01*
X99781Y215993D01*
X98740D01*
G01X99781D02*
X100406Y214785D01*
G01X102673D02*
Y217285D01*
X102173Y216785D01*
G01Y214785D02*
X103173D01*
G01X106606D02*
X104940D01*
Y217285D01*
X106606D01*
G01X105940Y216077D02*
X104940D01*
G01X108873Y214785D02*
Y217285D01*
X108373Y216785D01*
G01Y214785D02*
X109373D01*
G01X112473D02*
Y217285D01*
X110931Y215493D01*
X113015D01*
G01X78749Y171144D02*
X80541D01*
X80916Y171311D01*
X81166Y171644D01*
X81249Y172061D01*
X81166Y172478D01*
X80916Y172811D01*
X80541Y172978D01*
X78749D01*
G01X81249Y175161D02*
X78749D01*
X79249Y174661D01*
G01X81249D02*
Y175661D01*
G01Y179094D02*
Y177428D01*
X78749D01*
Y179094D01*
G01X79957Y178428D02*
Y177428D01*
G01X79166Y180569D02*
X78916Y180819D01*
X78791Y181111D01*
X78749Y181444D01*
X78832Y181861D01*
X79041Y182153D01*
X79291Y182236D01*
X79541Y182194D01*
X79749Y182028D01*
X80166Y181194D01*
X80457Y180819D01*
X80874Y180569D01*
X81249Y180486D01*
Y182236D01*
G01X64692Y181966D02*
X64442Y182091D01*
X64150Y182174D01*
X63817D01*
X63442Y182049D01*
X63150Y181841D01*
X62942Y181591D01*
X62775Y181174D01*
X62733Y180799D01*
X62817Y180424D01*
X62942Y180174D01*
X63192Y179924D01*
X63483Y179757D01*
X63775Y179674D01*
X64067D01*
X64358Y179757D01*
X64608Y179882D01*
X64817Y180049D01*
G01X66875Y179674D02*
Y182174D01*
X66375Y181674D01*
G01Y179674D02*
X67375D01*
G01X70808D02*
X69142D01*
Y182174D01*
X70808D01*
G01X70142Y180966D02*
X69142D01*
G01X72283Y181757D02*
X72533Y182007D01*
X72825Y182132D01*
X73158Y182174D01*
X73575Y182091D01*
X73867Y181882D01*
X73950Y181632D01*
X73908Y181382D01*
X73742Y181174D01*
X72908Y180757D01*
X72533Y180466D01*
X72283Y180049D01*
X72200Y179674D01*
X73950D01*
G01X75383Y181757D02*
X75633Y182007D01*
X75925Y182132D01*
X76258Y182174D01*
X76675Y182091D01*
X76967Y181882D01*
X77050Y181632D01*
X77008Y181382D01*
X76842Y181174D01*
X76008Y180757D01*
X75633Y180466D01*
X75383Y180049D01*
X75300Y179674D01*
X77050D01*
G01X92888Y209264D02*
X92638Y209389D01*
X92346Y209472D01*
X92013D01*
X91638Y209347D01*
X91346Y209139D01*
X91138Y208889D01*
X90971Y208472D01*
X90929Y208097D01*
X91013Y207722D01*
X91138Y207472D01*
X91388Y207222D01*
X91679Y207055D01*
X91971Y206972D01*
X92263D01*
X92554Y207055D01*
X92804Y207180D01*
X93013Y207347D01*
G01X95071Y206972D02*
Y209472D01*
X94571Y208972D01*
G01Y206972D02*
X95571D01*
G01X99004D02*
X97338D01*
Y209472D01*
X99004D01*
G01X98338Y208264D02*
X97338D01*
G01X101271Y206972D02*
Y209472D01*
X100771Y208972D01*
G01Y206972D02*
X101771D01*
G01X104288D02*
X104371Y207514D01*
X104496Y207972D01*
X104663Y208389D01*
X104871Y208847D01*
X105204Y209472D01*
X103538D01*
G01X93312Y212995D02*
X93062Y213120D01*
X92770Y213203D01*
X92437D01*
X92062Y213078D01*
X91770Y212870D01*
X91562Y212620D01*
X91395Y212203D01*
X91353Y211828D01*
X91437Y211453D01*
X91562Y211203D01*
X91812Y210953D01*
X92103Y210786D01*
X92395Y210703D01*
X92687D01*
X92978Y210786D01*
X93228Y210911D01*
X93437Y211078D01*
G01X95495Y210703D02*
Y213203D01*
X94995Y212703D01*
G01Y210703D02*
X95995D01*
G01X99428D02*
X97762D01*
Y213203D01*
X99428D01*
G01X98762Y211995D02*
X97762D01*
G01X101695Y210703D02*
Y213203D01*
X101195Y212703D01*
G01Y210703D02*
X102195D01*
G01X104003Y211745D02*
X104295Y212036D01*
X104545Y212203D01*
X104878Y212286D01*
X105170Y212203D01*
X105378Y212036D01*
X105545Y211786D01*
X105587Y211495D01*
X105545Y211245D01*
X105378Y210995D01*
X105128Y210786D01*
X104837Y210703D01*
X104503Y210786D01*
X104212Y211036D01*
X104045Y211411D01*
X104003Y211828D01*
X104087Y212370D01*
X104212Y212661D01*
X104420Y212953D01*
X104712Y213161D01*
X105003Y213203D01*
X105295Y213120D01*
X105503Y212911D01*
G01X104050Y192249D02*
X104750D01*
Y205249D01*
X104050D01*
G01X98350D02*
X97650D01*
Y192249D01*
X98350D01*
G01X104750Y174614D02*
X114586D01*
Y198386D01*
X111586Y201386D01*
X104750D01*
G01X97650D02*
X90814D01*
X87814Y198386D01*
Y174614D01*
G01D02*
X97650D01*
G01X82942Y182407D02*
X82817Y182157D01*
X82734Y181865D01*
Y181532D01*
X82859Y181157D01*
X83067Y180865D01*
X83317Y180657D01*
X83734Y180490D01*
X84109Y180448D01*
X84484Y180532D01*
X84734Y180657D01*
X84984Y180907D01*
X85151Y181198D01*
X85234Y181490D01*
Y181782D01*
X85151Y182073D01*
X85026Y182323D01*
X84859Y182532D01*
G01X85234Y183757D02*
X82734D01*
Y184798D01*
X82859Y185132D01*
X83026Y185340D01*
X83359Y185423D01*
X83692Y185340D01*
X83901Y185090D01*
X84026Y184798D01*
Y183757D01*
G01Y184798D02*
X85234Y185423D01*
G01Y187690D02*
X82734D01*
X83234Y187190D01*
G01X85234D02*
Y188190D01*
G01Y191623D02*
Y189957D01*
X82734D01*
Y191623D01*
G01X83942Y190957D02*
Y189957D01*
G01X85234Y193890D02*
X82734D01*
X83234Y193390D01*
G01X85234D02*
Y194390D01*
G01X87272Y171659D02*
X90861D01*
Y173552D01*
X94140Y171659D01*
X90861Y169766D01*
Y171659D01*
G01X94140Y169766D02*
Y173552D01*
G01X98563Y171659D02*
X94140D01*
G01X52415Y196689D02*
X52645Y196999D01*
X52913Y197154D01*
X53220Y197206D01*
X53603Y197103D01*
X53871Y196844D01*
X53948Y196534D01*
X53910Y196224D01*
X53756Y195966D01*
X52990Y195449D01*
X52645Y195088D01*
X52415Y194571D01*
X52338Y194106D01*
X53948D01*
G01X56677Y193834D02*
X56907Y193472D01*
X57213Y193266D01*
X57558Y193214D01*
X57865Y193266D01*
X58172Y193524D01*
X58363Y193834D01*
X58402Y194144D01*
X58325Y194506D01*
X58057Y194764D01*
X57788Y194867D01*
X57443D01*
G01X57788D02*
X58018Y195022D01*
X58210Y195281D01*
X58287Y195591D01*
X58210Y195901D01*
X58018Y196159D01*
X57673Y196314D01*
X57328Y196262D01*
X56983Y196056D01*
G01X62467Y187400D02*
Y189900D01*
X63508D01*
X63842Y189775D01*
X64050Y189608D01*
X64133Y189275D01*
X64050Y188942D01*
X63800Y188733D01*
X63508Y188608D01*
X62467D01*
G01X63508D02*
X64133Y187400D01*
G01X65317D02*
Y189900D01*
X66400Y187817D01*
X67483Y189900D01*
Y187400D01*
G01X69500D02*
Y189900D01*
X69000Y189400D01*
G01Y187400D02*
X70000D01*
G01X73433D02*
X71767D01*
Y189900D01*
X73433D01*
G01X72767Y188692D02*
X71767D01*
G01X75700Y187400D02*
Y189900D01*
X75200Y189400D01*
G01Y187400D02*
X76200D01*
G01X62872Y193361D02*
X62539Y193403D01*
X62247Y193569D01*
X61997Y193819D01*
X61830Y194111D01*
X61747Y194444D01*
Y194778D01*
X61830Y195111D01*
X61997Y195403D01*
X62247Y195653D01*
X62539Y195819D01*
X62872Y195861D01*
X63205Y195819D01*
X63497Y195653D01*
X63747Y195403D01*
X63914Y195111D01*
X63997Y194778D01*
Y194444D01*
X63914Y194111D01*
X63747Y193819D01*
X63497Y193569D01*
X63205Y193403D01*
X62872Y193361D01*
G01X63205Y194028D02*
X63705Y193361D01*
G01X65972D02*
Y195861D01*
X65472Y195361D01*
G01Y193361D02*
X66472D01*
G01X69905D02*
X68239D01*
Y195861D01*
X69905D01*
G01X69239Y194653D02*
X68239D01*
G01X72172Y193361D02*
Y195861D01*
X71672Y195361D01*
G01Y193361D02*
X72672D01*
G01X62726Y205550D02*
G02X83146I10210J-2450D01*
G01X86036D01*
Y199050D01*
X82624D01*
G02X81553Y197100I-9688J4052D01*
G01X64319D01*
G02X63248Y199050I8617J6002D01*
G01X59836D01*
Y205550D01*
X62726D01*
G01X50133Y243087D02*
X50325Y242777D01*
X50555Y242570D01*
X50823Y242467D01*
X51130Y242570D01*
X51360Y242777D01*
X51590Y243087D01*
X51667Y243500D01*
Y245567D01*
G01X53502Y243500D02*
X54498D01*
G01X57100Y242467D02*
Y245567D01*
X56640Y244947D01*
G01Y242467D02*
X57560D01*
G01X101427Y240598D02*
X119731D01*
Y237069D01*
X121243D01*
G01X89000Y273500D02*
X89001D01*
Y264886D01*
X92114D01*
Y260589D01*
X100356D01*
Y252742D01*
X100331D01*
G01X94345Y283848D02*
Y280599D01*
X89000D01*
Y273500D01*
X71000D01*
Y280342D01*
G01X99775Y236627D02*
Y239127D01*
X100816D01*
X101150Y239002D01*
X101358Y238835D01*
X101441Y238502D01*
X101358Y238169D01*
X101108Y237960D01*
X100816Y237835D01*
X99775D01*
G01X100816D02*
X101441Y236627D01*
G01X103708D02*
Y239127D01*
X103208Y238627D01*
G01Y236627D02*
X104208D01*
G01X107641D02*
X105975D01*
Y239127D01*
X107641D01*
G01X106975Y237919D02*
X105975D01*
G01X109908Y236627D02*
Y239127D01*
X109408Y238627D01*
G01Y236627D02*
X110408D01*
G01X107836Y222621D02*
Y225121D01*
X108877D01*
X109211Y224996D01*
X109419Y224829D01*
X109502Y224496D01*
X109419Y224163D01*
X109169Y223954D01*
X108877Y223829D01*
X107836D01*
G01X108877D02*
X109502Y222621D01*
G01X111769Y225121D02*
Y222621D01*
G01X110811Y225121D02*
X112727D01*
G01X114869Y222621D02*
Y225121D01*
X114369Y224621D01*
G01Y222621D02*
X115369D01*
G01X117052Y222996D02*
X117302Y222788D01*
X117594Y222663D01*
X117969Y222621D01*
X118344Y222704D01*
X118636Y222871D01*
X118844Y223163D01*
X118886Y223496D01*
X118802Y223829D01*
X118594Y224038D01*
X118302Y224204D01*
X118011Y224246D01*
X117719Y224204D01*
X117344Y224038D01*
X117469Y225121D01*
X118594D01*
G01X98638Y235656D02*
X98388Y235781D01*
X98096Y235864D01*
X97763D01*
X97388Y235739D01*
X97096Y235531D01*
X96888Y235281D01*
X96721Y234864D01*
X96679Y234489D01*
X96763Y234114D01*
X96888Y233864D01*
X97138Y233614D01*
X97429Y233447D01*
X97721Y233364D01*
X98013D01*
X98304Y233447D01*
X98554Y233572D01*
X98763Y233739D01*
G01X100821Y233364D02*
Y235864D01*
X100321Y235364D01*
G01Y233364D02*
X101321D01*
G01X104754D02*
X103088D01*
Y235864D01*
X104754D01*
G01X104088Y234656D02*
X103088D01*
G01X107021Y233364D02*
Y235864D01*
X106521Y235364D01*
G01Y233364D02*
X107521D01*
G01X109204Y233864D02*
X109454Y233572D01*
X109788Y233406D01*
X110163Y233364D01*
X110496Y233406D01*
X110829Y233614D01*
X111038Y233864D01*
X111079Y234114D01*
X110996Y234406D01*
X110704Y234614D01*
X110413Y234697D01*
X110038D01*
G01X110413D02*
X110663Y234822D01*
X110871Y235031D01*
X110954Y235281D01*
X110871Y235531D01*
X110663Y235739D01*
X110288Y235864D01*
X109913Y235822D01*
X109538Y235656D01*
G01X99377Y232022D02*
X99127Y232147D01*
X98835Y232230D01*
X98502D01*
X98127Y232105D01*
X97835Y231897D01*
X97627Y231647D01*
X97460Y231230D01*
X97418Y230855D01*
X97502Y230480D01*
X97627Y230230D01*
X97877Y229980D01*
X98168Y229813D01*
X98460Y229730D01*
X98752D01*
X99043Y229813D01*
X99293Y229938D01*
X99502Y230105D01*
G01X101560Y229730D02*
Y232230D01*
X101060Y231730D01*
G01Y229730D02*
X102060D01*
G01X105493D02*
X103827D01*
Y232230D01*
X105493D01*
G01X104827Y231022D02*
X103827D01*
G01X107760Y229730D02*
Y232230D01*
X107260Y231730D01*
G01Y229730D02*
X108260D01*
G01X110860D02*
Y232230D01*
X110360Y231730D01*
G01Y229730D02*
X111360D01*
G01X71137Y270483D02*
X70887Y270608D01*
X70595Y270691D01*
X70262D01*
X69887Y270566D01*
X69595Y270358D01*
X69387Y270108D01*
X69220Y269691D01*
X69178Y269316D01*
X69262Y268941D01*
X69387Y268691D01*
X69637Y268441D01*
X69928Y268274D01*
X70220Y268191D01*
X70512D01*
X70803Y268274D01*
X71053Y268399D01*
X71262Y268566D01*
G01X73320Y268191D02*
Y270691D01*
X72820Y270191D01*
G01Y268191D02*
X73820D01*
G01X75170Y270691D02*
X75753Y268191D01*
X76420Y270691D01*
X77087Y268191D01*
X77670Y270691D01*
G01X79520Y268191D02*
Y270691D01*
X79020Y270191D01*
G01Y268191D02*
X80020D01*
G01X81828Y269233D02*
X82120Y269524D01*
X82370Y269691D01*
X82703Y269774D01*
X82995Y269691D01*
X83203Y269524D01*
X83370Y269274D01*
X83412Y268983D01*
X83370Y268733D01*
X83203Y268483D01*
X82953Y268274D01*
X82662Y268191D01*
X82328Y268274D01*
X82037Y268524D01*
X81870Y268899D01*
X81828Y269316D01*
X81912Y269858D01*
X82037Y270149D01*
X82245Y270441D01*
X82537Y270649D01*
X82828Y270691D01*
X83120Y270608D01*
X83328Y270399D01*
G01X81400Y265201D02*
Y265650D01*
X64100D01*
Y265201D01*
G01X81400Y245199D02*
Y244750D01*
X64100D01*
Y245199D01*
G01X92031Y223018D02*
X90365D01*
Y225518D01*
X92031D01*
G01X91365Y224310D02*
X90365D01*
G01X93381Y225518D02*
Y223726D01*
X93548Y223351D01*
X93881Y223101D01*
X94298Y223018D01*
X94715Y223101D01*
X95048Y223351D01*
X95215Y223726D01*
Y225518D01*
G01X97398Y223018D02*
Y225518D01*
X96898Y225018D01*
G01Y223018D02*
X97898D01*
G01X101331D02*
X99665D01*
Y225518D01*
X101331D01*
G01X100665Y224310D02*
X99665D01*
G01X102681Y223518D02*
X102931Y223226D01*
X103265Y223060D01*
X103640Y223018D01*
X103973Y223060D01*
X104306Y223268D01*
X104515Y223518D01*
X104556Y223768D01*
X104473Y224060D01*
X104181Y224268D01*
X103890Y224351D01*
X103515D01*
G01X103890D02*
X104140Y224476D01*
X104348Y224685D01*
X104431Y224935D01*
X104348Y225185D01*
X104140Y225393D01*
X103765Y225518D01*
X103390Y225476D01*
X103015Y225310D01*
G01X81953Y242301D02*
Y242750D01*
X64653D01*
Y242301D01*
G01X81953Y222299D02*
Y221850D01*
X64653D01*
Y222299D01*
G01X100450Y246311D02*
Y250756D01*
G01X107550Y246308D02*
Y250754D01*
G01Y276650D02*
Y279900D01*
X104050D01*
G01X95550Y276650D02*
Y279900D01*
X99050D01*
G01X100300Y274400D02*
X102800D01*
G01X51647Y220870D02*
X51855Y220620D01*
X52105Y220453D01*
X52397Y220370D01*
X52730Y220453D01*
X52980Y220620D01*
X53230Y220870D01*
X53313Y221203D01*
Y222870D01*
G01X55580Y220370D02*
Y222870D01*
X55080Y222370D01*
G01Y220370D02*
X56080D01*
G01X59513D02*
X57847D01*
Y222870D01*
X59513D01*
G01X58847Y221662D02*
X57847D01*
G01X61780Y220370D02*
Y222870D01*
X61280Y222370D01*
G01Y220370D02*
X62280D01*
G01X105627Y334977D02*
Y341977D01*
X108293D01*
X109360Y341627D01*
X110160Y341160D01*
X110827Y340460D01*
X111360Y339644D01*
X111493Y338477D01*
X111360Y337310D01*
X110827Y336494D01*
X110160Y335793D01*
X109360Y335327D01*
X108293Y334977D01*
X105627D01*
G01X58500Y305000D02*
Y309200D01*
X51401D01*
X51400Y309201D01*
Y344551D01*
G01X71000Y283319D02*
Y285000D01*
X58500D01*
Y295153D01*
G01X94345Y298491D02*
Y290490D01*
G01X82899Y309200D02*
X82900Y309199D01*
G01X94389Y287816D02*
Y286215D01*
G01X97021Y300573D02*
X109000D01*
Y304500D01*
X110000D01*
Y312208D01*
X105751D01*
Y325290D01*
X107329D01*
X107330Y325291D01*
Y334000D01*
X104500D01*
Y341000D01*
G01X108450Y307650D02*
Y310900D01*
X104950D01*
G01X96450Y307650D02*
Y310900D01*
X99950D01*
G01X101200Y305400D02*
X103700D01*
G01X83150Y286350D02*
X59850D01*
Y309650D01*
X83150D01*
Y286350D01*
G01X80388Y308040D02*
X81540D01*
Y306888D01*
X81538D01*
G01X61460D02*
Y308040D01*
X62612D01*
Y308038D01*
G01Y287960D02*
X61460D01*
Y289112D01*
X61462D01*
G01X81540D02*
Y287960D01*
X80388D01*
Y287962D01*
G01X68600Y393550D02*
X68558Y393217D01*
X68392Y392925D01*
X68142Y392675D01*
X67850Y392508D01*
X67517Y392425D01*
X67183D01*
X66850Y392508D01*
X66558Y392675D01*
X66308Y392925D01*
X66142Y393217D01*
X66100Y393550D01*
X66142Y393883D01*
X66308Y394175D01*
X66558Y394425D01*
X66850Y394592D01*
X67183Y394675D01*
X67517D01*
X67850Y394592D01*
X68142Y394425D01*
X68392Y394175D01*
X68558Y393883D01*
X68600Y393550D01*
G01X66308Y397567D02*
X66183Y397317D01*
X66100Y397025D01*
Y396692D01*
X66225Y396317D01*
X66433Y396025D01*
X66683Y395817D01*
X67100Y395650D01*
X67475Y395608D01*
X67850Y395692D01*
X68100Y395817D01*
X68350Y396067D01*
X68517Y396358D01*
X68600Y396650D01*
Y396942D01*
X68517Y397233D01*
X68392Y397483D01*
X68225Y397692D01*
G01X68600Y398917D02*
X66100D01*
Y399917D01*
X66225Y400250D01*
X66517Y400500D01*
X66850Y400583D01*
X67183Y400500D01*
X67433Y400292D01*
X67558Y399917D01*
Y398917D01*
G01X66308Y406867D02*
X66183Y406617D01*
X66100Y406325D01*
Y405992D01*
X66225Y405617D01*
X66433Y405325D01*
X66683Y405117D01*
X67100Y404950D01*
X67475Y404908D01*
X67850Y404992D01*
X68100Y405117D01*
X68350Y405367D01*
X68517Y405658D01*
X68600Y405950D01*
Y406242D01*
X68517Y406533D01*
X68392Y406783D01*
X68225Y406992D01*
G01X68600Y408217D02*
X66100D01*
Y409258D01*
X66225Y409592D01*
X66392Y409800D01*
X66725Y409883D01*
X67058Y409800D01*
X67267Y409550D01*
X67392Y409258D01*
Y408217D01*
G01Y409258D02*
X68600Y409883D01*
G01Y411192D02*
X66100D01*
X68600Y413108D01*
X66100D01*
G01Y415250D02*
X68600D01*
G01X66100Y414292D02*
Y416208D01*
G01X68600Y421450D02*
X68558Y421117D01*
X68392Y420825D01*
X68142Y420575D01*
X67850Y420408D01*
X67517Y420325D01*
X67183D01*
X66850Y420408D01*
X66558Y420575D01*
X66308Y420825D01*
X66142Y421117D01*
X66100Y421450D01*
X66142Y421783D01*
X66308Y422075D01*
X66558Y422325D01*
X66850Y422492D01*
X67183Y422575D01*
X67517D01*
X67850Y422492D01*
X68142Y422325D01*
X68392Y422075D01*
X68558Y421783D01*
X68600Y421450D01*
G01Y423717D02*
X66100D01*
Y424717D01*
X66225Y425050D01*
X66517Y425300D01*
X66850Y425383D01*
X67183Y425300D01*
X67433Y425092D01*
X67558Y424717D01*
Y423717D01*
G01X66100Y427650D02*
X68600D01*
G01X66100Y426692D02*
Y428608D01*
G01X64759Y393556D02*
X62259Y394598D01*
X64759Y395640D01*
G01X63884Y395265D02*
Y393931D01*
G01X62259Y397198D02*
Y398198D01*
G01Y397698D02*
X64759D01*
G01Y397198D02*
Y398198D01*
G01Y399965D02*
X62259D01*
Y401006D01*
X62384Y401340D01*
X62551Y401548D01*
X62884Y401631D01*
X63217Y401548D01*
X63426Y401298D01*
X63551Y401006D01*
Y399965D01*
G01Y401006D02*
X64759Y401631D01*
G01Y402815D02*
X62259D01*
X64342Y403898D01*
X62259Y404981D01*
X64759D01*
G01Y405956D02*
X62259Y406998D01*
X64759Y408040D01*
G01X63884Y407665D02*
Y406331D01*
G01X64759Y409223D02*
X62259Y410973D01*
G01Y409223D02*
X64759Y410973D01*
G01X63426Y416631D02*
X63301Y416798D01*
X63092Y416923D01*
X62801Y417006D01*
X62551Y416923D01*
X62384Y416756D01*
X62259Y416465D01*
Y415340D01*
X64759D01*
Y416715D01*
X64592Y417006D01*
X64342Y417173D01*
X64051Y417256D01*
X63759Y417173D01*
X63509Y416923D01*
X63426Y416631D01*
Y415340D01*
G01X56145Y369914D02*
X55345Y370264D01*
X54412Y370497D01*
X53345D01*
X52145Y370147D01*
X51212Y369564D01*
X50545Y368864D01*
X50012Y367697D01*
X49879Y366647D01*
X50145Y365597D01*
X50545Y364897D01*
X51345Y364197D01*
X52279Y363730D01*
X53212Y363497D01*
X54145D01*
X55079Y363730D01*
X55879Y364080D01*
X56545Y364547D01*
G01X53730Y378000D02*
Y372800D01*
G01X51400Y348032D02*
Y362690D01*
X49787D01*
Y364353D01*
G01X89500Y388644D02*
X75608D01*
Y390025D01*
X66292D01*
Y387044D01*
X59255D01*
Y381549D01*
X68900D01*
G01X107330Y349400D02*
Y343500D01*
X106000D01*
G01X74000Y381549D02*
X83400D01*
G01X91147Y372408D02*
X96938D01*
Y379006D01*
X103150D01*
G01X111500Y397500D02*
Y392509D01*
X104298D01*
Y388980D01*
X98312D01*
G01X119000Y374000D02*
X107330D01*
Y362800D01*
G01X107200Y358400D02*
Y353200D01*
G01X105550Y379006D02*
X107330D01*
Y377000D01*
G01X85800Y381549D02*
X90181D01*
Y378480D01*
G01X72010Y397454D02*
X69510D01*
Y398495D01*
X69635Y398829D01*
X69802Y399037D01*
X70135Y399120D01*
X70468Y399037D01*
X70677Y398787D01*
X70802Y398495D01*
Y397454D01*
G01Y398495D02*
X72010Y399120D01*
G01Y401387D02*
X69510D01*
X70010Y400887D01*
G01X72010D02*
Y401887D01*
G01X69718Y405404D02*
X69593Y405154D01*
X69510Y404862D01*
Y404529D01*
X69635Y404154D01*
X69843Y403862D01*
X70093Y403654D01*
X70510Y403487D01*
X70885Y403445D01*
X71260Y403529D01*
X71510Y403654D01*
X71760Y403904D01*
X71927Y404195D01*
X72010Y404487D01*
Y404779D01*
X71927Y405070D01*
X71802Y405320D01*
X71635Y405529D01*
G01X72010Y407587D02*
X69510D01*
X70010Y407087D01*
G01X72010D02*
Y408087D01*
G01X71510Y409770D02*
X71802Y410020D01*
X71968Y410354D01*
X72010Y410729D01*
X71968Y411062D01*
X71760Y411395D01*
X71510Y411604D01*
X71260Y411645D01*
X70968Y411562D01*
X70760Y411270D01*
X70677Y410979D01*
Y410604D01*
G01Y410979D02*
X70552Y411229D01*
X70343Y411437D01*
X70093Y411520D01*
X69843Y411437D01*
X69635Y411229D01*
X69510Y410854D01*
X69552Y410479D01*
X69718Y410104D01*
G01X46777Y393760D02*
Y396260D01*
X47818D01*
X48152Y396135D01*
X48360Y395968D01*
X48443Y395635D01*
X48360Y395302D01*
X48110Y395093D01*
X47818Y394968D01*
X46777D01*
G01X47818D02*
X48443Y393760D01*
G01X50710D02*
Y396260D01*
X50210Y395760D01*
G01Y393760D02*
X51210D01*
G01X54727Y396052D02*
X54477Y396177D01*
X54185Y396260D01*
X53852D01*
X53477Y396135D01*
X53185Y395927D01*
X52977Y395677D01*
X52810Y395260D01*
X52768Y394885D01*
X52852Y394510D01*
X52977Y394260D01*
X53227Y394010D01*
X53518Y393843D01*
X53810Y393760D01*
X54102D01*
X54393Y393843D01*
X54643Y393968D01*
X54852Y394135D01*
G01X56910Y393760D02*
Y396260D01*
X56410Y395760D01*
G01Y393760D02*
X57410D01*
G01X60510D02*
Y396260D01*
X58968Y394468D01*
X61052D01*
G01X50001Y373487D02*
X49876Y373237D01*
X49793Y372945D01*
Y372612D01*
X49918Y372237D01*
X50126Y371945D01*
X50376Y371737D01*
X50793Y371570D01*
X51168Y371528D01*
X51543Y371612D01*
X51793Y371737D01*
X52043Y371987D01*
X52210Y372278D01*
X52293Y372570D01*
Y372862D01*
X52210Y373153D01*
X52085Y373403D01*
X51918Y373612D01*
G01X52293Y375670D02*
X49793D01*
X50293Y375170D01*
G01X52293D02*
Y376170D01*
G01X50001Y379687D02*
X49876Y379437D01*
X49793Y379145D01*
Y378812D01*
X49918Y378437D01*
X50126Y378145D01*
X50376Y377937D01*
X50793Y377770D01*
X51168Y377728D01*
X51543Y377812D01*
X51793Y377937D01*
X52043Y378187D01*
X52210Y378478D01*
X52293Y378770D01*
Y379062D01*
X52210Y379353D01*
X52085Y379603D01*
X51918Y379812D01*
G01X52293Y381870D02*
X49793D01*
X50293Y381370D01*
G01X52293D02*
Y382370D01*
G01Y385470D02*
X49793D01*
X51585Y383928D01*
Y386012D01*
G01X46501Y373487D02*
X46376Y373237D01*
X46293Y372945D01*
Y372612D01*
X46418Y372237D01*
X46626Y371945D01*
X46876Y371737D01*
X47293Y371570D01*
X47668Y371528D01*
X48043Y371612D01*
X48293Y371737D01*
X48543Y371987D01*
X48710Y372278D01*
X48793Y372570D01*
Y372862D01*
X48710Y373153D01*
X48585Y373403D01*
X48418Y373612D01*
G01X48793Y375670D02*
X46293D01*
X46793Y375170D01*
G01X48793D02*
Y376170D01*
G01X46501Y379687D02*
X46376Y379437D01*
X46293Y379145D01*
Y378812D01*
X46418Y378437D01*
X46626Y378145D01*
X46876Y377937D01*
X47293Y377770D01*
X47668Y377728D01*
X48043Y377812D01*
X48293Y377937D01*
X48543Y378187D01*
X48710Y378478D01*
X48793Y378770D01*
Y379062D01*
X48710Y379353D01*
X48585Y379603D01*
X48418Y379812D01*
G01X48793Y381870D02*
X46293D01*
X46793Y381370D01*
G01X48793D02*
Y382370D01*
G01X48293Y384053D02*
X48585Y384303D01*
X48751Y384637D01*
X48793Y385012D01*
X48751Y385345D01*
X48543Y385678D01*
X48293Y385887D01*
X48043Y385928D01*
X47751Y385845D01*
X47543Y385553D01*
X47460Y385262D01*
Y384887D01*
G01Y385262D02*
X47335Y385512D01*
X47126Y385720D01*
X46876Y385803D01*
X46626Y385720D01*
X46418Y385512D01*
X46293Y385137D01*
X46335Y384762D01*
X46501Y384387D01*
G01X76591Y399630D02*
Y389794D01*
X100363D01*
X103363Y392794D01*
Y399630D01*
G01X94226Y400330D02*
Y399630D01*
X107226D01*
Y400330D01*
G01X48464Y356833D02*
X48714Y357041D01*
X48881Y357291D01*
X48964Y357583D01*
X48881Y357916D01*
X48714Y358166D01*
X48464Y358416D01*
X48131Y358499D01*
X46464D01*
G01X48964Y360766D02*
X46464D01*
X46964Y360266D01*
G01X48964D02*
Y361266D01*
G01X46672Y364783D02*
X46547Y364533D01*
X46464Y364241D01*
Y363908D01*
X46589Y363533D01*
X46797Y363241D01*
X47047Y363033D01*
X47464Y362866D01*
X47839Y362824D01*
X48214Y362908D01*
X48464Y363033D01*
X48714Y363283D01*
X48881Y363574D01*
X48964Y363866D01*
Y364158D01*
X48881Y364449D01*
X48756Y364699D01*
X48589Y364908D01*
G01X48964Y366966D02*
X46464D01*
X46964Y366466D01*
G01X48964D02*
Y367466D01*
G01X62700Y377800D02*
X90300D01*
Y350200D01*
X62700D01*
Y377800D01*
G01X65673Y352189D02*
X64689D01*
Y353173D01*
G01X88311D02*
Y352189D01*
X87327D01*
G01Y375811D02*
X88311D01*
Y374827D01*
G01X64689D02*
Y375811D01*
X65673D01*
G01X63693Y454842D02*
X63463Y454997D01*
X63195Y455100D01*
X62888D01*
X62543Y454945D01*
X62275Y454687D01*
X62083Y454377D01*
X61930Y453860D01*
X61892Y453395D01*
X61968Y452930D01*
X62083Y452620D01*
X62313Y452310D01*
X62582Y452103D01*
X62850Y452000D01*
X63118D01*
X63387Y452103D01*
X63617Y452258D01*
X63808Y452465D01*
G01X65183Y452000D02*
Y455100D01*
X66103D01*
X66410Y454945D01*
X66640Y454583D01*
X66717Y454170D01*
X66640Y453757D01*
X66448Y453447D01*
X66103Y453292D01*
X65183D01*
G01X68207Y455100D02*
Y452878D01*
X68360Y452413D01*
X68667Y452103D01*
X69050Y452000D01*
X69433Y452103D01*
X69740Y452413D01*
X69893Y452878D01*
Y455100D01*
G01X71000Y450967D02*
X73300D01*
G01X75250Y452000D02*
Y455100D01*
X74790Y454480D01*
G01Y452000D02*
X75710D01*
G01X77200Y450967D02*
X79500D01*
G01X80722Y452000D02*
Y455100D01*
X82178D01*
G01X81642Y453602D02*
X80722D01*
G01X83592Y452000D02*
X84550Y455100D01*
X85508Y452000D01*
G01X85163Y453085D02*
X83937D01*
G01X86768Y452000D02*
Y455100D01*
X88532Y452000D01*
Y455100D01*
G01X53325Y404886D02*
X50825D01*
Y405927D01*
X50950Y406261D01*
X51117Y406469D01*
X51450Y406552D01*
X51783Y406469D01*
X51992Y406219D01*
X52117Y405927D01*
Y404886D01*
G01Y405927D02*
X53325Y406552D01*
G01Y408819D02*
X50825D01*
X51325Y408319D01*
G01X53325D02*
Y409319D01*
G01X51033Y412836D02*
X50908Y412586D01*
X50825Y412294D01*
Y411961D01*
X50950Y411586D01*
X51158Y411294D01*
X51408Y411086D01*
X51825Y410919D01*
X52200Y410877D01*
X52575Y410961D01*
X52825Y411086D01*
X53075Y411336D01*
X53242Y411627D01*
X53325Y411919D01*
Y412211D01*
X53242Y412502D01*
X53117Y412752D01*
X52950Y412961D01*
G01X53033Y414311D02*
X53242Y414602D01*
X53325Y414936D01*
X53242Y415269D01*
X52992Y415561D01*
X52617Y415769D01*
X52242Y415852D01*
X51783D01*
X51408Y415769D01*
X51075Y415561D01*
X50908Y415311D01*
X50825Y415019D01*
X50908Y414686D01*
X51075Y414436D01*
X51325Y414269D01*
X51658Y414186D01*
X51950Y414269D01*
X52242Y414477D01*
X52408Y414727D01*
X52450Y415019D01*
X52367Y415352D01*
X52158Y415602D01*
X51783Y415852D01*
G01X57425Y405086D02*
X54925D01*
Y406127D01*
X55050Y406461D01*
X55217Y406669D01*
X55550Y406752D01*
X55883Y406669D01*
X56092Y406419D01*
X56217Y406127D01*
Y405086D01*
G01Y406127D02*
X57425Y406752D01*
G01Y409019D02*
X54925D01*
X55425Y408519D01*
G01X57425D02*
Y409519D01*
G01X55133Y413036D02*
X55008Y412786D01*
X54925Y412494D01*
Y412161D01*
X55050Y411786D01*
X55258Y411494D01*
X55508Y411286D01*
X55925Y411119D01*
X56300Y411077D01*
X56675Y411161D01*
X56925Y411286D01*
X57175Y411536D01*
X57342Y411827D01*
X57425Y412119D01*
Y412411D01*
X57342Y412702D01*
X57217Y412952D01*
X57050Y413161D01*
G01X57425Y415219D02*
X54925D01*
X55425Y414719D01*
G01X57425D02*
Y415719D01*
G01X54925Y418319D02*
X55008Y417986D01*
X55217Y417736D01*
X55467Y417569D01*
X55800Y417444D01*
X56175Y417402D01*
X56550Y417444D01*
X56883Y417569D01*
X57133Y417736D01*
X57342Y417986D01*
X57425Y418319D01*
X57342Y418652D01*
X57133Y418902D01*
X56883Y419069D01*
X56550Y419194D01*
X56175Y419236D01*
X55800Y419194D01*
X55467Y419069D01*
X55217Y418902D01*
X55008Y418652D01*
X54925Y418319D01*
G01X61125Y405186D02*
X58625D01*
Y406227D01*
X58750Y406561D01*
X58917Y406769D01*
X59250Y406852D01*
X59583Y406769D01*
X59792Y406519D01*
X59917Y406227D01*
Y405186D01*
G01Y406227D02*
X61125Y406852D01*
G01Y409119D02*
X58625D01*
X59125Y408619D01*
G01X61125D02*
Y409619D01*
G01X58833Y413136D02*
X58708Y412886D01*
X58625Y412594D01*
Y412261D01*
X58750Y411886D01*
X58958Y411594D01*
X59208Y411386D01*
X59625Y411219D01*
X60000Y411177D01*
X60375Y411261D01*
X60625Y411386D01*
X60875Y411636D01*
X61042Y411927D01*
X61125Y412219D01*
Y412511D01*
X61042Y412802D01*
X60917Y413052D01*
X60750Y413261D01*
G01X61125Y415319D02*
X58625D01*
X59125Y414819D01*
G01X61125D02*
Y415819D01*
G01Y418419D02*
X58625D01*
X59125Y417919D01*
G01X61125D02*
Y418919D01*
G01X49825Y404786D02*
X47325D01*
Y405827D01*
X47450Y406161D01*
X47617Y406369D01*
X47950Y406452D01*
X48283Y406369D01*
X48492Y406119D01*
X48617Y405827D01*
Y404786D01*
G01Y405827D02*
X49825Y406452D01*
G01Y408719D02*
X47325D01*
X47825Y408219D01*
G01X49825D02*
Y409219D01*
G01X47533Y412736D02*
X47408Y412486D01*
X47325Y412194D01*
Y411861D01*
X47450Y411486D01*
X47658Y411194D01*
X47908Y410986D01*
X48325Y410819D01*
X48700Y410777D01*
X49075Y410861D01*
X49325Y410986D01*
X49575Y411236D01*
X49742Y411527D01*
X49825Y411819D01*
Y412111D01*
X49742Y412402D01*
X49617Y412652D01*
X49450Y412861D01*
G01X49325Y414002D02*
X49617Y414252D01*
X49783Y414586D01*
X49825Y414961D01*
X49783Y415294D01*
X49575Y415627D01*
X49325Y415836D01*
X49075Y415877D01*
X48783Y415794D01*
X48575Y415502D01*
X48492Y415211D01*
Y414836D01*
G01Y415211D02*
X48367Y415461D01*
X48158Y415669D01*
X47908Y415752D01*
X47658Y415669D01*
X47450Y415461D01*
X47325Y415086D01*
X47367Y414711D01*
X47533Y414336D01*
G01X49825Y418019D02*
X47325D01*
X47825Y417519D01*
G01X49825D02*
Y418519D01*
G01X73389Y407985D02*
X73264Y407735D01*
X73181Y407443D01*
Y407110D01*
X73306Y406735D01*
X73514Y406443D01*
X73764Y406235D01*
X74181Y406068D01*
X74556Y406026D01*
X74931Y406110D01*
X75181Y406235D01*
X75431Y406485D01*
X75598Y406776D01*
X75681Y407068D01*
Y407360D01*
X75598Y407651D01*
X75473Y407901D01*
X75306Y408110D01*
G01X75681Y410168D02*
X73181D01*
X73681Y409668D01*
G01X75681D02*
Y410668D01*
G01X73389Y414185D02*
X73264Y413935D01*
X73181Y413643D01*
Y413310D01*
X73306Y412935D01*
X73514Y412643D01*
X73764Y412435D01*
X74181Y412268D01*
X74556Y412226D01*
X74931Y412310D01*
X75181Y412435D01*
X75431Y412685D01*
X75598Y412976D01*
X75681Y413268D01*
Y413560D01*
X75598Y413851D01*
X75473Y414101D01*
X75306Y414310D01*
G01X73598Y415576D02*
X73348Y415826D01*
X73223Y416118D01*
X73181Y416451D01*
X73264Y416868D01*
X73473Y417160D01*
X73723Y417243D01*
X73973Y417201D01*
X74181Y417035D01*
X74598Y416201D01*
X74889Y415826D01*
X75306Y415576D01*
X75681Y415493D01*
Y417243D01*
G01X76591Y416566D02*
Y406730D01*
G01X103363D02*
Y413566D01*
X100363Y416566D01*
X76591D01*
G01X107226Y406030D02*
Y406730D01*
X94226D01*
Y406030D01*
G01X76587Y444657D02*
Y434821D01*
G01X103359D02*
Y441657D01*
X100359Y444657D01*
X76587D01*
G01Y427721D02*
Y417885D01*
X100359D01*
X103359Y420885D01*
Y427721D01*
G01X107222Y434121D02*
Y434821D01*
X94222D01*
Y434121D01*
G01Y428421D02*
Y427721D01*
X107222D01*
Y428421D01*
G01X74850Y433847D02*
X75100Y434055D01*
X75267Y434305D01*
X75350Y434597D01*
X75267Y434930D01*
X75100Y435180D01*
X74850Y435430D01*
X74517Y435513D01*
X72850D01*
G01X75350Y437780D02*
X72850D01*
X73350Y437280D01*
G01X75350D02*
Y438280D01*
G01X74017Y441213D02*
X73892Y441380D01*
X73683Y441505D01*
X73392Y441588D01*
X73142Y441505D01*
X72975Y441338D01*
X72850Y441047D01*
Y439922D01*
X75350D01*
Y441297D01*
X75183Y441588D01*
X74933Y441755D01*
X74642Y441838D01*
X74350Y441755D01*
X74100Y441505D01*
X74017Y441213D01*
Y439922D01*
G01X75350Y444480D02*
X72850D01*
X74642Y442938D01*
Y445022D01*
G01X47339Y446656D02*
X54389D01*
Y448656D01*
X64289D01*
Y438806D01*
X71339D01*
Y432906D01*
X64289D01*
Y423056D01*
X54389D01*
Y425056D01*
X47339D01*
Y430956D01*
X54389D01*
Y440756D01*
X47339D01*
Y446656D01*
G01X103906Y446701D02*
Y444201D01*
X105572D01*
G01X107839D02*
Y446701D01*
X107339Y446201D01*
G01Y444201D02*
X108339D01*
G01X111272Y445534D02*
X111439Y445659D01*
X111564Y445868D01*
X111647Y446159D01*
X111564Y446409D01*
X111397Y446576D01*
X111106Y446701D01*
X109981D01*
Y444201D01*
X111356D01*
X111647Y444368D01*
X111814Y444618D01*
X111897Y444909D01*
X111814Y445201D01*
X111564Y445451D01*
X111272Y445534D01*
X109981D01*
G01X113247Y446284D02*
X113497Y446534D01*
X113789Y446659D01*
X114122Y446701D01*
X114539Y446618D01*
X114831Y446409D01*
X114914Y446159D01*
X114872Y445909D01*
X114706Y445701D01*
X113872Y445284D01*
X113497Y444993D01*
X113247Y444576D01*
X113164Y444201D01*
X114914D01*
G01X91941Y448425D02*
Y475625D01*
X114441D01*
Y448425D01*
X91941D01*
G01X103417Y509942D02*
X103167Y510067D01*
X102875Y510150D01*
X102542D01*
X102167Y510025D01*
X101875Y509817D01*
X101667Y509567D01*
X101500Y509150D01*
X101458Y508775D01*
X101542Y508400D01*
X101667Y508150D01*
X101917Y507900D01*
X102208Y507733D01*
X102500Y507650D01*
X102792D01*
X103083Y507733D01*
X103333Y507858D01*
X103542Y508025D01*
G01X105600Y507650D02*
Y510150D01*
X105100Y509650D01*
G01Y507650D02*
X106100D01*
G01X109033Y508983D02*
X109200Y509108D01*
X109325Y509317D01*
X109408Y509608D01*
X109325Y509858D01*
X109158Y510025D01*
X108867Y510150D01*
X107742D01*
Y507650D01*
X109117D01*
X109408Y507817D01*
X109575Y508067D01*
X109658Y508358D01*
X109575Y508650D01*
X109325Y508900D01*
X109033Y508983D01*
X107742D01*
G01X111717Y507650D02*
X111800Y508192D01*
X111925Y508650D01*
X112092Y509067D01*
X112300Y509525D01*
X112633Y510150D01*
X110967D01*
G01X100473Y484055D02*
Y486555D01*
X101514D01*
X101848Y486430D01*
X102056Y486263D01*
X102139Y485930D01*
X102056Y485597D01*
X101806Y485388D01*
X101514Y485263D01*
X100473D01*
G01X101514D02*
X102139Y484055D01*
G01X104406D02*
Y486555D01*
X103906Y486055D01*
G01Y484055D02*
X104906D01*
G01X107839Y485388D02*
X108006Y485513D01*
X108131Y485722D01*
X108214Y486013D01*
X108131Y486263D01*
X107964Y486430D01*
X107673Y486555D01*
X106548D01*
Y484055D01*
X107923D01*
X108214Y484222D01*
X108381Y484472D01*
X108464Y484763D01*
X108381Y485055D01*
X108131Y485305D01*
X107839Y485388D01*
X106548D01*
G01X109814Y486138D02*
X110064Y486388D01*
X110356Y486513D01*
X110689Y486555D01*
X111106Y486472D01*
X111398Y486263D01*
X111481Y486013D01*
X111439Y485763D01*
X111273Y485555D01*
X110439Y485138D01*
X110064Y484847D01*
X109814Y484430D01*
X109731Y484055D01*
X111481D01*
G01X112914Y486138D02*
X113164Y486388D01*
X113456Y486513D01*
X113789Y486555D01*
X114206Y486472D01*
X114498Y486263D01*
X114581Y486013D01*
X114539Y485763D01*
X114373Y485555D01*
X113539Y485138D01*
X113164Y484847D01*
X112914Y484430D01*
X112831Y484055D01*
X114581D01*
G01X100677Y480723D02*
Y483223D01*
X101718D01*
X102052Y483098D01*
X102260Y482931D01*
X102343Y482598D01*
X102260Y482265D01*
X102010Y482056D01*
X101718Y481931D01*
X100677D01*
G01X101718D02*
X102343Y480723D01*
G01X104610D02*
Y483223D01*
X104110Y482723D01*
G01Y480723D02*
X105110D01*
G01X108043Y482056D02*
X108210Y482181D01*
X108335Y482390D01*
X108418Y482681D01*
X108335Y482931D01*
X108168Y483098D01*
X107877Y483223D01*
X106752D01*
Y480723D01*
X108127D01*
X108418Y480890D01*
X108585Y481140D01*
X108668Y481431D01*
X108585Y481723D01*
X108335Y481973D01*
X108043Y482056D01*
X106752D01*
G01X110018Y482806D02*
X110268Y483056D01*
X110560Y483181D01*
X110893Y483223D01*
X111310Y483140D01*
X111602Y482931D01*
X111685Y482681D01*
X111643Y482431D01*
X111477Y482223D01*
X110643Y481806D01*
X110268Y481515D01*
X110018Y481098D01*
X109935Y480723D01*
X111685D01*
G01X113910D02*
Y483223D01*
X113410Y482723D01*
G01Y480723D02*
X114410D01*
G01X96827Y478570D02*
X96702Y478320D01*
X96619Y478028D01*
Y477695D01*
X96744Y477320D01*
X96952Y477028D01*
X97202Y476820D01*
X97619Y476653D01*
X97994Y476611D01*
X98369Y476695D01*
X98619Y476820D01*
X98869Y477070D01*
X99036Y477361D01*
X99119Y477653D01*
Y477945D01*
X99036Y478236D01*
X98911Y478486D01*
X98744Y478695D01*
G01X99119Y480753D02*
X96619D01*
X97119Y480253D01*
G01X99119D02*
Y481253D01*
G01X97786Y484186D02*
X97661Y484353D01*
X97452Y484478D01*
X97161Y484561D01*
X96911Y484478D01*
X96744Y484311D01*
X96619Y484020D01*
Y482895D01*
X99119D01*
Y484270D01*
X98952Y484561D01*
X98702Y484728D01*
X98411Y484811D01*
X98119Y484728D01*
X97869Y484478D01*
X97786Y484186D01*
Y482895D01*
G01X99119Y486953D02*
X96619D01*
X97119Y486453D01*
G01X99119D02*
Y487453D01*
G01X98744Y489136D02*
X98952Y489386D01*
X99077Y489678D01*
X99119Y490053D01*
X99036Y490428D01*
X98869Y490720D01*
X98577Y490928D01*
X98244Y490970D01*
X97911Y490886D01*
X97702Y490678D01*
X97536Y490386D01*
X97494Y490095D01*
X97536Y489803D01*
X97702Y489428D01*
X96619Y489553D01*
Y490678D01*
G01X70407Y515469D02*
X70157Y515594D01*
X69865Y515677D01*
X69532D01*
X69157Y515552D01*
X68865Y515344D01*
X68657Y515094D01*
X68490Y514677D01*
X68448Y514302D01*
X68532Y513927D01*
X68657Y513677D01*
X68907Y513427D01*
X69198Y513260D01*
X69490Y513177D01*
X69782D01*
X70073Y513260D01*
X70323Y513385D01*
X70532Y513552D01*
G01X72590Y513177D02*
Y515677D01*
X72090Y515177D01*
G01Y513177D02*
X73090D01*
G01X76023Y514510D02*
X76190Y514635D01*
X76315Y514844D01*
X76398Y515135D01*
X76315Y515385D01*
X76148Y515552D01*
X75857Y515677D01*
X74732D01*
Y513177D01*
X76107D01*
X76398Y513344D01*
X76565Y513594D01*
X76648Y513885D01*
X76565Y514177D01*
X76315Y514427D01*
X76023Y514510D01*
X74732D01*
G01X78790Y513177D02*
Y515677D01*
X78290Y515177D01*
G01Y513177D02*
X79290D01*
G01X81890Y515677D02*
X81557Y515594D01*
X81307Y515385D01*
X81140Y515135D01*
X81015Y514802D01*
X80973Y514427D01*
X81015Y514052D01*
X81140Y513719D01*
X81307Y513469D01*
X81557Y513260D01*
X81890Y513177D01*
X82223Y513260D01*
X82473Y513469D01*
X82640Y513719D01*
X82765Y514052D01*
X82807Y514427D01*
X82765Y514802D01*
X82640Y515135D01*
X82473Y515385D01*
X82223Y515594D01*
X81890Y515677D01*
G01X64151Y501600D02*
Y502300D01*
X51151D01*
Y501600D01*
G01Y495900D02*
Y495200D01*
X64151D01*
Y495900D01*
G01X81786Y502300D02*
Y512136D01*
X58014D01*
X55014Y509136D01*
Y502300D01*
G01Y495200D02*
Y488364D01*
X58014Y485364D01*
X81786D01*
G01D02*
Y495200D01*
G01X101943Y493313D02*
X101693Y493438D01*
X101401Y493521D01*
X101068D01*
X100693Y493396D01*
X100401Y493188D01*
X100193Y492938D01*
X100026Y492521D01*
X99984Y492146D01*
X100068Y491771D01*
X100193Y491521D01*
X100443Y491271D01*
X100734Y491104D01*
X101026Y491021D01*
X101318D01*
X101609Y491104D01*
X101859Y491229D01*
X102068Y491396D01*
G01X103293Y491021D02*
Y493521D01*
X104334D01*
X104668Y493396D01*
X104876Y493229D01*
X104959Y492896D01*
X104876Y492563D01*
X104626Y492354D01*
X104334Y492229D01*
X103293D01*
G01X104334D02*
X104959Y491021D01*
G01X107226D02*
Y493521D01*
X106726Y493021D01*
G01Y491021D02*
X107726D01*
G01X110659Y492354D02*
X110826Y492479D01*
X110951Y492688D01*
X111034Y492979D01*
X110951Y493229D01*
X110784Y493396D01*
X110493Y493521D01*
X109368D01*
Y491021D01*
X110743D01*
X111034Y491188D01*
X111201Y491438D01*
X111284Y491729D01*
X111201Y492021D01*
X110951Y492271D01*
X110659Y492354D01*
X109368D01*
G01X113426Y491021D02*
Y493521D01*
X112926Y493021D01*
G01Y491021D02*
X113926D01*
G01X73678Y483337D02*
X77267D01*
Y485230D01*
X80546Y483337D01*
X77267Y481444D01*
Y483337D01*
G01X80546Y481444D02*
Y485230D01*
G01X84969Y483337D02*
X80546D01*
G01X101899Y489795D02*
X101649Y489920D01*
X101357Y490003D01*
X101024D01*
X100649Y489878D01*
X100357Y489670D01*
X100149Y489420D01*
X99982Y489003D01*
X99940Y488628D01*
X100024Y488253D01*
X100149Y488003D01*
X100399Y487753D01*
X100690Y487586D01*
X100982Y487503D01*
X101274D01*
X101565Y487586D01*
X101815Y487711D01*
X102024Y487878D01*
G01X103249Y487503D02*
Y490003D01*
X104290D01*
X104624Y489878D01*
X104832Y489711D01*
X104915Y489378D01*
X104832Y489045D01*
X104582Y488836D01*
X104290Y488711D01*
X103249D01*
G01X104290D02*
X104915Y487503D01*
G01X107182D02*
Y490003D01*
X106682Y489503D01*
G01Y487503D02*
X107682D01*
G01X110615Y488836D02*
X110782Y488961D01*
X110907Y489170D01*
X110990Y489461D01*
X110907Y489711D01*
X110740Y489878D01*
X110449Y490003D01*
X109324D01*
Y487503D01*
X110699D01*
X110990Y487670D01*
X111157Y487920D01*
X111240Y488211D01*
X111157Y488503D01*
X110907Y488753D01*
X110615Y488836D01*
X109324D01*
G01X112590Y489586D02*
X112840Y489836D01*
X113132Y489961D01*
X113465Y490003D01*
X113882Y489920D01*
X114174Y489711D01*
X114257Y489461D01*
X114215Y489211D01*
X114049Y489003D01*
X113215Y488586D01*
X112840Y488295D01*
X112590Y487878D01*
X112507Y487503D01*
X114257D01*
G01X75853Y474642D02*
X79442D01*
Y476535D01*
X82721Y474642D01*
X79442Y472749D01*
Y474642D01*
G01X82721Y472749D02*
Y476535D01*
G01X87144Y474642D02*
X82721D01*
G01X60517Y482200D02*
X60725Y481950D01*
X60975Y481783D01*
X61267Y481700D01*
X61600Y481783D01*
X61850Y481950D01*
X62100Y482200D01*
X62183Y482533D01*
Y484200D01*
G01X64450Y481700D02*
Y484200D01*
X63950Y483700D01*
G01Y481700D02*
X64950D01*
G01X67883Y483033D02*
X68050Y483158D01*
X68175Y483367D01*
X68258Y483658D01*
X68175Y483908D01*
X68008Y484075D01*
X67717Y484200D01*
X66592D01*
Y481700D01*
X67967D01*
X68258Y481867D01*
X68425Y482117D01*
X68508Y482408D01*
X68425Y482700D01*
X68175Y482950D01*
X67883Y483033D01*
X66592D01*
G01X69858Y483783D02*
X70108Y484033D01*
X70400Y484158D01*
X70733Y484200D01*
X71150Y484117D01*
X71442Y483908D01*
X71525Y483658D01*
X71483Y483408D01*
X71317Y483200D01*
X70483Y482783D01*
X70108Y482492D01*
X69858Y482075D01*
X69775Y481700D01*
X71525D01*
G01X111100Y520160D02*
X86710D01*
Y545750D01*
X111100D01*
G01X50474Y486762D02*
X47974D01*
Y487803D01*
X48099Y488137D01*
X48266Y488345D01*
X48599Y488428D01*
X48932Y488345D01*
X49141Y488095D01*
X49266Y487803D01*
Y486762D01*
G01Y487803D02*
X50474Y488428D01*
G01Y490695D02*
X47974D01*
X48474Y490195D01*
G01X50474D02*
Y491195D01*
G01X48391Y493003D02*
X48141Y493253D01*
X48016Y493545D01*
X47974Y493878D01*
X48057Y494295D01*
X48266Y494587D01*
X48516Y494670D01*
X48766Y494628D01*
X48974Y494462D01*
X49391Y493628D01*
X49682Y493253D01*
X50099Y493003D01*
X50474Y492920D01*
Y494670D01*
G01X47974Y495645D02*
X50474Y496228D01*
X47974Y496895D01*
X50474Y497562D01*
X47974Y498145D01*
G01X50474Y499995D02*
X47974D01*
X48474Y499495D01*
G01X50474D02*
Y500495D01*
G01Y503012D02*
X49932Y503095D01*
X49474Y503220D01*
X49057Y503387D01*
X48599Y503595D01*
X47974Y503928D01*
Y502262D01*
G01X46724Y488052D02*
Y495052D01*
G01X46782Y495819D02*
Y502819D01*
G01X78317Y587542D02*
X78067Y587667D01*
X77775Y587750D01*
X77442D01*
X77067Y587625D01*
X76775Y587417D01*
X76567Y587167D01*
X76400Y586750D01*
X76358Y586375D01*
X76442Y586000D01*
X76567Y585750D01*
X76817Y585500D01*
X77108Y585333D01*
X77400Y585250D01*
X77692D01*
X77983Y585333D01*
X78233Y585458D01*
X78442Y585625D01*
G01X80500Y585250D02*
Y587750D01*
X80000Y587250D01*
G01Y585250D02*
X81000D01*
G01X82558D02*
X83600Y587750D01*
X84642Y585250D01*
G01X84267Y586125D02*
X82933D01*
G01X87200Y585250D02*
Y587750D01*
X85658Y585958D01*
X87742D01*
G01X76167Y549442D02*
X75917Y549567D01*
X75625Y549650D01*
X75292D01*
X74917Y549525D01*
X74625Y549317D01*
X74417Y549067D01*
X74250Y548650D01*
X74208Y548275D01*
X74292Y547900D01*
X74417Y547650D01*
X74667Y547400D01*
X74958Y547233D01*
X75250Y547150D01*
X75542D01*
X75833Y547233D01*
X76083Y547358D01*
X76292Y547525D01*
G01X78350Y547150D02*
Y549650D01*
X77850Y549150D01*
G01Y547150D02*
X78850D01*
G01X80408D02*
X81450Y549650D01*
X82492Y547150D01*
G01X82117Y548025D02*
X80783D01*
G01X84550Y547150D02*
Y549650D01*
X84050Y549150D01*
G01Y547150D02*
X85050D01*
G01X86858Y548192D02*
X87150Y548483D01*
X87400Y548650D01*
X87733Y548733D01*
X88025Y548650D01*
X88233Y548483D01*
X88400Y548233D01*
X88442Y547942D01*
X88400Y547692D01*
X88233Y547442D01*
X87983Y547233D01*
X87692Y547150D01*
X87358Y547233D01*
X87067Y547483D01*
X86900Y547858D01*
X86858Y548275D01*
X86942Y548817D01*
X87067Y549108D01*
X87275Y549400D01*
X87567Y549608D01*
X87858Y549650D01*
X88150Y549567D01*
X88358Y549358D01*
G01X60124Y565912D02*
X59874Y566037D01*
X59582Y566120D01*
X59249D01*
X58874Y565995D01*
X58582Y565787D01*
X58374Y565537D01*
X58207Y565120D01*
X58165Y564745D01*
X58249Y564370D01*
X58374Y564120D01*
X58624Y563870D01*
X58915Y563703D01*
X59207Y563620D01*
X59499D01*
X59790Y563703D01*
X60040Y563828D01*
X60249Y563995D01*
G01X62307Y563620D02*
Y566120D01*
X61807Y565620D01*
G01Y563620D02*
X62807D01*
G01X64365D02*
X65407Y566120D01*
X66449Y563620D01*
G01X66074Y564495D02*
X64740D01*
G01X68507Y563620D02*
Y566120D01*
X68007Y565620D01*
G01Y563620D02*
X69007D01*
G01X70815Y565703D02*
X71065Y565953D01*
X71357Y566078D01*
X71690Y566120D01*
X72107Y566037D01*
X72399Y565828D01*
X72482Y565578D01*
X72440Y565328D01*
X72274Y565120D01*
X71440Y564703D01*
X71065Y564412D01*
X70815Y563995D01*
X70732Y563620D01*
X72482D01*
G01X84520Y527817D02*
X84770Y528025D01*
X84937Y528275D01*
X85020Y528567D01*
X84937Y528900D01*
X84770Y529150D01*
X84520Y529400D01*
X84187Y529483D01*
X82520D01*
G01X85020Y531750D02*
X82520D01*
X83020Y531250D01*
G01X85020D02*
Y532250D01*
G01X83687Y535183D02*
X83562Y535350D01*
X83353Y535475D01*
X83062Y535558D01*
X82812Y535475D01*
X82645Y535308D01*
X82520Y535017D01*
Y533892D01*
X85020D01*
Y535267D01*
X84853Y535558D01*
X84603Y535725D01*
X84312Y535808D01*
X84020Y535725D01*
X83770Y535475D01*
X83687Y535183D01*
Y533892D01*
G01X85020Y537950D02*
X82520D01*
X83020Y537450D01*
G01X85020D02*
Y538450D01*
G01X85080Y563007D02*
X85330Y563215D01*
X85497Y563465D01*
X85580Y563757D01*
X85497Y564090D01*
X85330Y564340D01*
X85080Y564590D01*
X84747Y564673D01*
X83080D01*
G01X85580Y566940D02*
X83080D01*
X83580Y566440D01*
G01X85580D02*
Y567440D01*
G01Y568998D02*
X83080Y570040D01*
X85580Y571082D01*
G01X84705Y570707D02*
Y569373D01*
G01X83497Y572348D02*
X83247Y572598D01*
X83122Y572890D01*
X83080Y573223D01*
X83163Y573640D01*
X83372Y573932D01*
X83622Y574015D01*
X83872Y573973D01*
X84080Y573807D01*
X84497Y572973D01*
X84788Y572598D01*
X85205Y572348D01*
X85580Y572265D01*
Y574015D01*
G01X111100Y557960D02*
X86710D01*
Y583550D01*
X111100D01*
G01X53277Y530437D02*
Y527937D01*
X54943D01*
G01X57210D02*
Y530437D01*
X56710Y529937D01*
G01Y527937D02*
X57710D01*
G01X60643Y529270D02*
X60810Y529395D01*
X60935Y529604D01*
X61018Y529895D01*
X60935Y530145D01*
X60768Y530312D01*
X60477Y530437D01*
X59352D01*
Y527937D01*
X60727D01*
X61018Y528104D01*
X61185Y528354D01*
X61268Y528645D01*
X61185Y528937D01*
X60935Y529187D01*
X60643Y529270D01*
X59352D01*
G01X63410Y527937D02*
Y530437D01*
X62910Y529937D01*
G01Y527937D02*
X63910D01*
G01X70417Y580741D02*
X72917D01*
Y582407D01*
G01Y584674D02*
X70417D01*
X70917Y584174D01*
G01X72917D02*
Y585174D01*
G01Y586732D02*
X70417Y587774D01*
X72917Y588816D01*
G01X72042Y588441D02*
Y587107D01*
G01X72917Y590874D02*
X70417D01*
X70917Y590374D01*
G01X72917D02*
Y591374D01*
G01X69895Y542463D02*
X72395D01*
Y544129D01*
G01Y546396D02*
X69895D01*
X70395Y545896D01*
G01X72395D02*
Y546896D01*
G01Y548454D02*
X69895Y549496D01*
X72395Y550538D01*
G01X71520Y550163D02*
Y548829D01*
G01X70312Y551804D02*
X70062Y552054D01*
X69937Y552346D01*
X69895Y552679D01*
X69978Y553096D01*
X70187Y553388D01*
X70437Y553471D01*
X70687Y553429D01*
X70895Y553263D01*
X71312Y552429D01*
X71603Y552054D01*
X72020Y551804D01*
X72395Y551721D01*
Y553471D01*
G01X48700Y595600D02*
Y594000D01*
G01X49053Y611841D02*
X48803Y611966D01*
X48511Y612049D01*
X48178D01*
X47803Y611924D01*
X47511Y611716D01*
X47303Y611466D01*
X47136Y611049D01*
X47094Y610674D01*
X47178Y610299D01*
X47303Y610049D01*
X47553Y609799D01*
X47844Y609632D01*
X48136Y609549D01*
X48428D01*
X48719Y609632D01*
X48969Y609757D01*
X49178Y609924D01*
G01X51236Y609549D02*
Y612049D01*
X50736Y611549D01*
G01Y609549D02*
X51736D01*
G01X53294D02*
X54336Y612049D01*
X55378Y609549D01*
G01X55003Y610424D02*
X53669D01*
G01X57436Y609549D02*
Y612049D01*
X56936Y611549D01*
G01Y609549D02*
X57936D01*
G01X47223Y613460D02*
Y615960D01*
X48264D01*
X48598Y615835D01*
X48806Y615668D01*
X48889Y615335D01*
X48806Y615002D01*
X48556Y614793D01*
X48264Y614668D01*
X47223D01*
G01X48264D02*
X48889Y613460D01*
G01X51156D02*
Y615960D01*
X50656Y615460D01*
G01Y613460D02*
X51656D01*
G01X53214D02*
X54256Y615960D01*
X55298Y613460D01*
G01X54923Y614335D02*
X53589D01*
G01X57356Y613460D02*
Y615960D01*
X56856Y615460D01*
G01Y613460D02*
X57856D01*
G01X85144Y603334D02*
X85394Y603542D01*
X85561Y603792D01*
X85644Y604084D01*
X85561Y604417D01*
X85394Y604667D01*
X85144Y604917D01*
X84811Y605000D01*
X83144D01*
G01X85644Y607267D02*
X83144D01*
X83644Y606767D01*
G01X85644D02*
Y607767D01*
G01Y609325D02*
X83144Y610367D01*
X85644Y611409D01*
G01X84769Y611034D02*
Y609700D01*
G01X85644Y613467D02*
X83144D01*
X83644Y612967D01*
G01X85644D02*
Y613967D01*
G01X111100Y595760D02*
X86710D01*
Y621350D01*
X111100D01*
G01X144500Y-38250D02*
Y-46250D01*
X126500D01*
Y-38250D01*
X144500D01*
G01Y-48250D02*
Y-56250D01*
X126500D01*
Y-48250D01*
X144500D01*
G01X118960Y7490D02*
Y10590D01*
X118500Y9970D01*
G01Y7490D02*
X119420D01*
G01X122520D02*
Y10590D01*
X121102Y8368D01*
X123018D01*
G01X124317Y7955D02*
X124547Y7697D01*
X124815Y7542D01*
X125160Y7490D01*
X125505Y7593D01*
X125773Y7800D01*
X125965Y8162D01*
X126003Y8575D01*
X125927Y8988D01*
X125735Y9247D01*
X125467Y9453D01*
X125198Y9505D01*
X124930Y9453D01*
X124585Y9247D01*
X124700Y10590D01*
X125735D01*
G01X140630Y45548D02*
X138130D01*
Y46589D01*
X138255Y46923D01*
X138422Y47131D01*
X138755Y47214D01*
X139088Y47131D01*
X139297Y46881D01*
X139422Y46589D01*
Y45548D01*
G01Y46589D02*
X140630Y47214D01*
G01Y49481D02*
X138130D01*
X138630Y48981D01*
G01X140630D02*
Y49981D01*
G01X139380Y52831D02*
Y53664D01*
X140130D01*
X140380Y53414D01*
X140547Y53123D01*
X140630Y52706D01*
X140547Y52289D01*
X140380Y51998D01*
X140130Y51748D01*
X139838Y51581D01*
X139505Y51498D01*
X139213D01*
X138963Y51581D01*
X138672Y51748D01*
X138422Y51998D01*
X138255Y52248D01*
X138130Y52581D01*
Y52873D01*
X138213Y53206D01*
X138380Y53456D01*
G01X140630Y55681D02*
X138130D01*
X138630Y55181D01*
G01X140630D02*
Y56181D01*
G01X145673Y45548D02*
X143173D01*
Y46589D01*
X143298Y46923D01*
X143465Y47131D01*
X143798Y47214D01*
X144131Y47131D01*
X144340Y46881D01*
X144465Y46589D01*
Y45548D01*
G01Y46589D02*
X145673Y47214D01*
G01Y49481D02*
X143173D01*
X143673Y48981D01*
G01X145673D02*
Y49981D01*
G01X144423Y52831D02*
Y53664D01*
X145173D01*
X145423Y53414D01*
X145590Y53123D01*
X145673Y52706D01*
X145590Y52289D01*
X145423Y51998D01*
X145173Y51748D01*
X144881Y51581D01*
X144548Y51498D01*
X144256D01*
X144006Y51581D01*
X143715Y51748D01*
X143465Y51998D01*
X143298Y52248D01*
X143173Y52581D01*
Y52873D01*
X143256Y53206D01*
X143423Y53456D01*
G01X143590Y54889D02*
X143340Y55139D01*
X143215Y55431D01*
X143173Y55764D01*
X143256Y56181D01*
X143465Y56473D01*
X143715Y56556D01*
X143965Y56514D01*
X144173Y56348D01*
X144590Y55514D01*
X144881Y55139D01*
X145298Y54889D01*
X145673Y54806D01*
Y56556D01*
G01X150069Y45548D02*
X147569D01*
Y46589D01*
X147694Y46923D01*
X147861Y47131D01*
X148194Y47214D01*
X148527Y47131D01*
X148736Y46881D01*
X148861Y46589D01*
Y45548D01*
G01Y46589D02*
X150069Y47214D01*
G01Y49481D02*
X147569D01*
X148069Y48981D01*
G01X150069D02*
Y49981D01*
G01X148819Y52831D02*
Y53664D01*
X149569D01*
X149819Y53414D01*
X149986Y53123D01*
X150069Y52706D01*
X149986Y52289D01*
X149819Y51998D01*
X149569Y51748D01*
X149277Y51581D01*
X148944Y51498D01*
X148652D01*
X148402Y51581D01*
X148111Y51748D01*
X147861Y51998D01*
X147694Y52248D01*
X147569Y52581D01*
Y52873D01*
X147652Y53206D01*
X147819Y53456D01*
G01X149569Y54764D02*
X149861Y55014D01*
X150027Y55348D01*
X150069Y55723D01*
X150027Y56056D01*
X149819Y56389D01*
X149569Y56598D01*
X149319Y56639D01*
X149027Y56556D01*
X148819Y56264D01*
X148736Y55973D01*
Y55598D01*
G01Y55973D02*
X148611Y56223D01*
X148402Y56431D01*
X148152Y56514D01*
X147902Y56431D01*
X147694Y56223D01*
X147569Y55848D01*
X147611Y55473D01*
X147777Y55098D01*
G01X143069Y94080D02*
X140569D01*
Y95121D01*
X140694Y95455D01*
X140861Y95663D01*
X141194Y95746D01*
X141527Y95663D01*
X141736Y95413D01*
X141861Y95121D01*
Y94080D01*
G01Y95121D02*
X143069Y95746D01*
G01Y98013D02*
X140569D01*
X141069Y97513D01*
G01X143069D02*
Y98513D01*
G01Y100321D02*
X140569D01*
Y101905D01*
G01X141777Y101321D02*
Y100321D01*
G01X142027Y103421D02*
X141736Y103713D01*
X141569Y103963D01*
X141486Y104296D01*
X141569Y104588D01*
X141736Y104796D01*
X141986Y104963D01*
X142277Y105005D01*
X142527Y104963D01*
X142777Y104796D01*
X142986Y104546D01*
X143069Y104255D01*
X142986Y103921D01*
X142736Y103630D01*
X142361Y103463D01*
X141944Y103421D01*
X141402Y103505D01*
X141111Y103630D01*
X140819Y103838D01*
X140611Y104130D01*
X140569Y104421D01*
X140652Y104713D01*
X140861Y104921D01*
G01X139459Y94098D02*
X136959D01*
Y95139D01*
X137084Y95473D01*
X137251Y95681D01*
X137584Y95764D01*
X137917Y95681D01*
X138126Y95431D01*
X138251Y95139D01*
Y94098D01*
G01Y95139D02*
X139459Y95764D01*
G01Y98031D02*
X136959D01*
X137459Y97531D01*
G01X139459D02*
Y98531D01*
G01Y100339D02*
X136959D01*
Y101923D01*
G01X138167Y101339D02*
Y100339D01*
G01X139084Y103314D02*
X139292Y103564D01*
X139417Y103856D01*
X139459Y104231D01*
X139376Y104606D01*
X139209Y104898D01*
X138917Y105106D01*
X138584Y105148D01*
X138251Y105064D01*
X138042Y104856D01*
X137876Y104564D01*
X137834Y104273D01*
X137876Y103981D01*
X138042Y103606D01*
X136959Y103731D01*
Y104856D01*
G01X135767Y94080D02*
X133267D01*
Y95121D01*
X133392Y95455D01*
X133559Y95663D01*
X133892Y95746D01*
X134225Y95663D01*
X134434Y95413D01*
X134559Y95121D01*
Y94080D01*
G01Y95121D02*
X135767Y95746D01*
G01Y98013D02*
X133267D01*
X133767Y97513D01*
G01X135767D02*
Y98513D01*
G01Y100321D02*
X133267D01*
Y101905D01*
G01X134475Y101321D02*
Y100321D01*
G01X135767Y104713D02*
X133267D01*
X135059Y103171D01*
Y105255D01*
G01X153717Y51959D02*
X153467Y52084D01*
X153175Y52167D01*
X152842D01*
X152467Y52042D01*
X152175Y51834D01*
X151967Y51584D01*
X151800Y51167D01*
X151758Y50792D01*
X151842Y50417D01*
X151967Y50167D01*
X152217Y49917D01*
X152508Y49750D01*
X152800Y49667D01*
X153092D01*
X153383Y49750D01*
X153633Y49875D01*
X153842Y50042D01*
G01X155900Y49667D02*
Y52167D01*
X155400Y51667D01*
G01Y49667D02*
X156400D01*
G01X159250Y50917D02*
X160083D01*
Y50167D01*
X159833Y49917D01*
X159542Y49750D01*
X159125Y49667D01*
X158708Y49750D01*
X158417Y49917D01*
X158167Y50167D01*
X158000Y50459D01*
X157917Y50792D01*
Y51084D01*
X158000Y51334D01*
X158167Y51625D01*
X158417Y51875D01*
X158667Y52042D01*
X159000Y52167D01*
X159292D01*
X159625Y52084D01*
X159875Y51917D01*
G01X162100Y49667D02*
Y52167D01*
X161600Y51667D01*
G01Y49667D02*
X162600D01*
G01X165200Y52167D02*
X164867Y52084D01*
X164617Y51875D01*
X164450Y51625D01*
X164325Y51292D01*
X164283Y50917D01*
X164325Y50542D01*
X164450Y50209D01*
X164617Y49959D01*
X164867Y49750D01*
X165200Y49667D01*
X165533Y49750D01*
X165783Y49959D01*
X165950Y50209D01*
X166075Y50542D01*
X166117Y50917D01*
X166075Y51292D01*
X165950Y51625D01*
X165783Y51875D01*
X165533Y52084D01*
X165200Y52167D01*
G01X133682Y47233D02*
X133557Y46983D01*
X133474Y46691D01*
Y46358D01*
X133599Y45983D01*
X133807Y45691D01*
X134057Y45483D01*
X134474Y45316D01*
X134849Y45274D01*
X135224Y45358D01*
X135474Y45483D01*
X135724Y45733D01*
X135891Y46024D01*
X135974Y46316D01*
Y46608D01*
X135891Y46899D01*
X135766Y47149D01*
X135599Y47358D01*
G01X135974Y49416D02*
X133474D01*
X133974Y48916D01*
G01X135974D02*
Y49916D01*
G01X134724Y52766D02*
Y53599D01*
X135474D01*
X135724Y53349D01*
X135891Y53058D01*
X135974Y52641D01*
X135891Y52224D01*
X135724Y51933D01*
X135474Y51683D01*
X135182Y51516D01*
X134849Y51433D01*
X134557D01*
X134307Y51516D01*
X134016Y51683D01*
X133766Y51933D01*
X133599Y52183D01*
X133474Y52516D01*
Y52808D01*
X133557Y53141D01*
X133724Y53391D01*
G01X135974Y55616D02*
X135932Y55908D01*
X135807Y56241D01*
X135599Y56449D01*
X135307Y56533D01*
X135016Y56449D01*
X134766Y56199D01*
X134641Y55824D01*
Y55408D01*
X134557Y55158D01*
X134349Y54949D01*
X134057Y54866D01*
X133766Y54991D01*
X133557Y55283D01*
X133474Y55616D01*
X133557Y55949D01*
X133766Y56241D01*
X134057Y56366D01*
X134349Y56283D01*
X134557Y56074D01*
X134641Y55824D01*
Y55408D01*
X134766Y55033D01*
X135016Y54783D01*
X135307Y54699D01*
X135599Y54783D01*
X135807Y54991D01*
X135932Y55324D01*
X135974Y55616D01*
G01X129192Y92403D02*
X129067Y92153D01*
X128984Y91861D01*
Y91528D01*
X129109Y91153D01*
X129317Y90861D01*
X129567Y90653D01*
X129984Y90486D01*
X130359Y90444D01*
X130734Y90528D01*
X130984Y90653D01*
X131234Y90903D01*
X131401Y91194D01*
X131484Y91486D01*
Y91778D01*
X131401Y92069D01*
X131276Y92319D01*
X131109Y92528D01*
G01X131484Y94586D02*
X128984D01*
X129484Y94086D01*
G01X131484D02*
Y95086D01*
G01Y96894D02*
X128984D01*
Y98478D01*
G01X130192Y97894D02*
Y96894D01*
G01X131484Y100786D02*
X128984D01*
X129484Y100286D01*
G01X131484D02*
Y101286D01*
G01X131192Y103178D02*
X131401Y103469D01*
X131484Y103803D01*
X131401Y104136D01*
X131151Y104428D01*
X130776Y104636D01*
X130401Y104719D01*
X129942D01*
X129567Y104636D01*
X129234Y104428D01*
X129067Y104178D01*
X128984Y103886D01*
X129067Y103553D01*
X129234Y103303D01*
X129484Y103136D01*
X129817Y103053D01*
X130109Y103136D01*
X130401Y103344D01*
X130567Y103594D01*
X130609Y103886D01*
X130526Y104219D01*
X130317Y104469D01*
X129942Y104719D01*
G01X147158Y96860D02*
X146908Y96985D01*
X146616Y97068D01*
X146283D01*
X145908Y96943D01*
X145616Y96735D01*
X145408Y96485D01*
X145241Y96068D01*
X145199Y95693D01*
X145283Y95318D01*
X145408Y95068D01*
X145658Y94818D01*
X145949Y94651D01*
X146241Y94568D01*
X146533D01*
X146824Y94651D01*
X147074Y94776D01*
X147283Y94943D01*
G01X149341Y94568D02*
Y97068D01*
X148841Y96568D01*
G01Y94568D02*
X149841D01*
G01X151649D02*
Y97068D01*
X153233D01*
G01X152649Y95860D02*
X151649D01*
G01X154749Y96651D02*
X154999Y96901D01*
X155291Y97026D01*
X155624Y97068D01*
X156041Y96985D01*
X156333Y96776D01*
X156416Y96526D01*
X156374Y96276D01*
X156208Y96068D01*
X155374Y95651D01*
X154999Y95360D01*
X154749Y94943D01*
X154666Y94568D01*
X156416D01*
G01X157849Y96651D02*
X158099Y96901D01*
X158391Y97026D01*
X158724Y97068D01*
X159141Y96985D01*
X159433Y96776D01*
X159516Y96526D01*
X159474Y96276D01*
X159308Y96068D01*
X158474Y95651D01*
X158099Y95360D01*
X157849Y94943D01*
X157766Y94568D01*
X159516D01*
G01X118850Y52900D02*
Y56000D01*
X118390Y55380D01*
G01Y52900D02*
X119310D01*
G01X122410D02*
Y56000D01*
X120992Y53778D01*
X122908D01*
G01X124207Y53365D02*
X124437Y53107D01*
X124705Y52952D01*
X125050Y52900D01*
X125395Y53003D01*
X125663Y53210D01*
X125855Y53572D01*
X125893Y53985D01*
X125817Y54398D01*
X125625Y54657D01*
X125357Y54863D01*
X125088Y54915D01*
X124820Y54863D01*
X124475Y54657D01*
X124590Y56000D01*
X125625D01*
G01X118830Y45320D02*
Y48420D01*
X118370Y47800D01*
G01Y45320D02*
X119290D01*
G01X122390D02*
Y48420D01*
X120972Y46198D01*
X122888D01*
G01X124187Y45785D02*
X124417Y45527D01*
X124685Y45372D01*
X125030Y45320D01*
X125375Y45423D01*
X125643Y45630D01*
X125835Y45992D01*
X125873Y46405D01*
X125797Y46818D01*
X125605Y47077D01*
X125337Y47283D01*
X125068Y47335D01*
X124800Y47283D01*
X124455Y47077D01*
X124570Y48420D01*
X125605D01*
G01X145058Y147093D02*
X144903Y146863D01*
X144800Y146595D01*
Y146288D01*
X144955Y145943D01*
X145213Y145675D01*
X145523Y145483D01*
X146040Y145330D01*
X146505Y145292D01*
X146970Y145368D01*
X147280Y145483D01*
X147590Y145713D01*
X147797Y145982D01*
X147900Y146250D01*
Y146518D01*
X147797Y146787D01*
X147642Y147017D01*
X147435Y147208D01*
G01X147900Y148583D02*
X144800D01*
Y149503D01*
X144955Y149810D01*
X145317Y150040D01*
X145730Y150117D01*
X146143Y150040D01*
X146453Y149848D01*
X146608Y149503D01*
Y148583D01*
G01X144800Y151607D02*
X147022D01*
X147487Y151760D01*
X147797Y152067D01*
X147900Y152450D01*
X147797Y152833D01*
X147487Y153140D01*
X147022Y153293D01*
X144800D01*
G01X148933Y154400D02*
Y156700D01*
G01X144800Y158650D02*
X144903Y158343D01*
X145162Y158113D01*
X145472Y157960D01*
X145885Y157845D01*
X146350Y157807D01*
X146815Y157845D01*
X147228Y157960D01*
X147538Y158113D01*
X147797Y158343D01*
X147900Y158650D01*
X147797Y158957D01*
X147538Y159187D01*
X147228Y159340D01*
X146815Y159455D01*
X146350Y159493D01*
X145885Y159455D01*
X145472Y159340D01*
X145162Y159187D01*
X144903Y158957D01*
X144800Y158650D01*
G01X148933Y160600D02*
Y162900D01*
G01X147900Y164122D02*
X144800D01*
Y165578D01*
G01X146298Y165042D02*
Y164122D01*
G01X147900Y166992D02*
X144800Y167950D01*
X147900Y168908D01*
G01X146815Y168563D02*
Y167337D01*
G01X147900Y170168D02*
X144800D01*
X147900Y171932D01*
X144800D01*
G01X119536Y107655D02*
Y110155D01*
X120577D01*
X120911Y110030D01*
X121119Y109863D01*
X121202Y109530D01*
X121119Y109197D01*
X120869Y108988D01*
X120577Y108863D01*
X119536D01*
G01X120577D02*
X121202Y107655D01*
G01X123469D02*
Y110155D01*
X122969Y109655D01*
G01Y107655D02*
X123969D01*
G01X125777Y109738D02*
X126027Y109988D01*
X126319Y110113D01*
X126652Y110155D01*
X127069Y110072D01*
X127361Y109863D01*
X127444Y109613D01*
X127402Y109363D01*
X127236Y109155D01*
X126402Y108738D01*
X126027Y108447D01*
X125777Y108030D01*
X125694Y107655D01*
X127444D01*
G01X128419Y110155D02*
X129002Y107655D01*
X129669Y110155D01*
X130336Y107655D01*
X130919Y110155D01*
G01X132769Y107655D02*
Y110155D01*
X132269Y109655D01*
G01Y107655D02*
X133269D01*
G01X136369D02*
Y110155D01*
X134827Y108363D01*
X136911D01*
G01X135834Y116017D02*
X133334D01*
Y117058D01*
X133459Y117392D01*
X133626Y117600D01*
X133959Y117683D01*
X134292Y117600D01*
X134501Y117350D01*
X134626Y117058D01*
Y116017D01*
G01Y117058D02*
X135834Y117683D01*
G01Y119950D02*
X133334D01*
X133834Y119450D01*
G01X135834D02*
Y120450D01*
G01Y122258D02*
X133334D01*
Y123842D01*
G01X134542Y123258D02*
Y122258D01*
G01X135334Y125233D02*
X135626Y125483D01*
X135792Y125817D01*
X135834Y126192D01*
X135792Y126525D01*
X135584Y126858D01*
X135334Y127067D01*
X135084Y127108D01*
X134792Y127025D01*
X134584Y126733D01*
X134501Y126442D01*
Y126067D01*
G01Y126442D02*
X134376Y126692D01*
X134167Y126900D01*
X133917Y126983D01*
X133667Y126900D01*
X133459Y126692D01*
X133334Y126317D01*
X133376Y125942D01*
X133542Y125567D01*
G01X124900Y122016D02*
Y126458D01*
G01X132000Y122013D02*
Y126338D01*
G01X163266Y145639D02*
X153266D01*
X150266Y149139D01*
Y186139D01*
X164966D01*
G01Y141389D02*
X163266D01*
Y157889D01*
X164966D01*
G01X134249Y133853D02*
X134124Y133603D01*
X134041Y133311D01*
Y132978D01*
X134166Y132603D01*
X134374Y132311D01*
X134624Y132103D01*
X135041Y131936D01*
X135416Y131894D01*
X135791Y131978D01*
X136041Y132103D01*
X136291Y132353D01*
X136458Y132644D01*
X136541Y132936D01*
Y133228D01*
X136458Y133519D01*
X136333Y133769D01*
X136166Y133978D01*
G01X136541Y135203D02*
X134041D01*
Y136244D01*
X134166Y136578D01*
X134333Y136786D01*
X134666Y136869D01*
X134999Y136786D01*
X135208Y136536D01*
X135333Y136244D01*
Y135203D01*
G01Y136244D02*
X136541Y136869D01*
G01Y139136D02*
X134041D01*
X134541Y138636D01*
G01X136541D02*
Y139636D01*
G01Y141444D02*
X134041D01*
Y143028D01*
G01X135249Y142444D02*
Y141444D01*
G01X136166Y144419D02*
X136374Y144669D01*
X136499Y144961D01*
X136541Y145336D01*
X136458Y145711D01*
X136291Y146003D01*
X135999Y146211D01*
X135666Y146253D01*
X135333Y146169D01*
X135124Y145961D01*
X134958Y145669D01*
X134916Y145378D01*
X134958Y145086D01*
X135124Y144711D01*
X134041Y144836D01*
Y145961D01*
G01X162170Y138351D02*
X162171Y107552D01*
G01X137669D02*
X137670Y138351D01*
G01D02*
X142270Y138352D01*
G01X157570D02*
X162170Y138351D01*
G01X157570Y107552D02*
X162171D01*
G01X137669D02*
X142270D01*
G01X120092Y111708D02*
X119759Y111750D01*
X119467Y111916D01*
X119217Y112166D01*
X119050Y112458D01*
X118967Y112791D01*
Y113125D01*
X119050Y113458D01*
X119217Y113750D01*
X119467Y114000D01*
X119759Y114166D01*
X120092Y114208D01*
X120425Y114166D01*
X120717Y114000D01*
X120967Y113750D01*
X121134Y113458D01*
X121217Y113125D01*
Y112791D01*
X121134Y112458D01*
X120967Y112166D01*
X120717Y111916D01*
X120425Y111750D01*
X120092Y111708D01*
G01X120425Y112375D02*
X120925Y111708D01*
G01X123192D02*
Y114208D01*
X122692Y113708D01*
G01Y111708D02*
X123692D01*
G01X125500Y113791D02*
X125750Y114041D01*
X126042Y114166D01*
X126375Y114208D01*
X126792Y114125D01*
X127084Y113916D01*
X127167Y113666D01*
X127125Y113416D01*
X126959Y113208D01*
X126125Y112791D01*
X125750Y112500D01*
X125500Y112083D01*
X125417Y111708D01*
X127167D01*
G01X128142Y114208D02*
X128725Y111708D01*
X129392Y114208D01*
X130059Y111708D01*
X130642Y114208D01*
G01X131575Y112208D02*
X131825Y111916D01*
X132159Y111750D01*
X132534Y111708D01*
X132867Y111750D01*
X133200Y111958D01*
X133409Y112208D01*
X133450Y112458D01*
X133367Y112750D01*
X133075Y112958D01*
X132784Y113041D01*
X132409D01*
G01X132784D02*
X133034Y113166D01*
X133242Y113375D01*
X133325Y113625D01*
X133242Y113875D01*
X133034Y114083D01*
X132659Y114208D01*
X132284Y114166D01*
X131909Y114000D01*
G01X114693Y115203D02*
Y126945D01*
X115335D01*
Y115203D01*
X114693D01*
X115014Y116603D01*
X115335Y115203D01*
G01X161815Y196806D02*
Y199306D01*
X162856D01*
X163190Y199181D01*
X163398Y199014D01*
X163481Y198681D01*
X163398Y198348D01*
X163148Y198139D01*
X162856Y198014D01*
X161815D01*
G01X162856D02*
X163481Y196806D01*
G01X165748D02*
Y199306D01*
X165248Y198806D01*
G01Y196806D02*
X166248D01*
G01X169681D02*
X168015D01*
Y199306D01*
X169681D01*
G01X169015Y198098D02*
X168015D01*
G01X171156Y197848D02*
X171448Y198139D01*
X171698Y198306D01*
X172031Y198389D01*
X172323Y198306D01*
X172531Y198139D01*
X172698Y197889D01*
X172740Y197598D01*
X172698Y197348D01*
X172531Y197098D01*
X172281Y196889D01*
X171990Y196806D01*
X171656Y196889D01*
X171365Y197139D01*
X171198Y197514D01*
X171156Y197931D01*
X171240Y198473D01*
X171365Y198764D01*
X171573Y199056D01*
X171865Y199264D01*
X172156Y199306D01*
X172448Y199223D01*
X172656Y199014D01*
G01X148233Y189287D02*
X145733D01*
Y190328D01*
X145858Y190662D01*
X146025Y190870D01*
X146358Y190953D01*
X146691Y190870D01*
X146900Y190620D01*
X147025Y190328D01*
Y189287D01*
G01Y190328D02*
X148233Y190953D01*
G01Y193220D02*
X145733D01*
X146233Y192720D01*
G01X148233D02*
Y193720D01*
G01Y197153D02*
Y195487D01*
X145733D01*
Y197153D01*
G01X146941Y196487D02*
Y195487D01*
G01X147858Y198503D02*
X148066Y198753D01*
X148191Y199045D01*
X148233Y199420D01*
X148150Y199795D01*
X147983Y200087D01*
X147691Y200295D01*
X147358Y200337D01*
X147025Y200253D01*
X146816Y200045D01*
X146650Y199753D01*
X146608Y199462D01*
X146650Y199170D01*
X146816Y198795D01*
X145733Y198920D01*
Y200045D01*
G01X161368Y191767D02*
Y194267D01*
X162409D01*
X162743Y194142D01*
X162951Y193975D01*
X163034Y193642D01*
X162951Y193309D01*
X162701Y193100D01*
X162409Y192975D01*
X161368D01*
G01X162409D02*
X163034Y191767D01*
G01X165301D02*
Y194267D01*
X164801Y193767D01*
G01Y191767D02*
X165801D01*
G01X169234D02*
X167568D01*
Y194267D01*
X169234D01*
G01X168568Y193059D02*
X167568D01*
G01X171418Y191767D02*
X171501Y192309D01*
X171626Y192767D01*
X171793Y193184D01*
X172001Y193642D01*
X172334Y194267D01*
X170668D01*
G01X119475Y164500D02*
X119350Y164250D01*
X119267Y163958D01*
Y163625D01*
X119392Y163250D01*
X119600Y162958D01*
X119850Y162750D01*
X120267Y162583D01*
X120642Y162541D01*
X121017Y162625D01*
X121267Y162750D01*
X121517Y163000D01*
X121684Y163291D01*
X121767Y163583D01*
Y163875D01*
X121684Y164166D01*
X121559Y164416D01*
X121392Y164625D01*
G01X121767Y166683D02*
X119267D01*
X119767Y166183D01*
G01X121767D02*
Y167183D01*
G01Y170616D02*
Y168950D01*
X119267D01*
Y170616D01*
G01X120475Y169950D02*
Y168950D01*
G01X119684Y172091D02*
X119434Y172341D01*
X119309Y172633D01*
X119267Y172966D01*
X119350Y173383D01*
X119559Y173675D01*
X119809Y173758D01*
X120059Y173716D01*
X120267Y173550D01*
X120684Y172716D01*
X120975Y172341D01*
X121392Y172091D01*
X121767Y172008D01*
Y173758D01*
G01X119267Y175983D02*
X119350Y175650D01*
X119559Y175400D01*
X119809Y175233D01*
X120142Y175108D01*
X120517Y175066D01*
X120892Y175108D01*
X121225Y175233D01*
X121475Y175400D01*
X121684Y175650D01*
X121767Y175983D01*
X121684Y176316D01*
X121475Y176566D01*
X121225Y176733D01*
X120892Y176858D01*
X120517Y176900D01*
X120142Y176858D01*
X119809Y176733D01*
X119559Y176566D01*
X119350Y176316D01*
X119267Y175983D01*
G01X123040Y194405D02*
X122915Y194155D01*
X122832Y193863D01*
Y193530D01*
X122957Y193155D01*
X123165Y192863D01*
X123415Y192655D01*
X123832Y192488D01*
X124207Y192446D01*
X124582Y192530D01*
X124832Y192655D01*
X125082Y192905D01*
X125249Y193196D01*
X125332Y193488D01*
Y193780D01*
X125249Y194071D01*
X125124Y194321D01*
X124957Y194530D01*
G01X125332Y196588D02*
X122832D01*
X123332Y196088D01*
G01X125332D02*
Y197088D01*
G01Y200521D02*
Y198855D01*
X122832D01*
Y200521D01*
G01X124040Y199855D02*
Y198855D01*
G01X125332Y202788D02*
X125290Y203080D01*
X125165Y203413D01*
X124957Y203621D01*
X124665Y203705D01*
X124374Y203621D01*
X124124Y203371D01*
X123999Y202996D01*
Y202580D01*
X123915Y202330D01*
X123707Y202121D01*
X123415Y202038D01*
X123124Y202163D01*
X122915Y202455D01*
X122832Y202788D01*
X122915Y203121D01*
X123124Y203413D01*
X123415Y203538D01*
X123707Y203455D01*
X123915Y203246D01*
X123999Y202996D01*
Y202580D01*
X124124Y202205D01*
X124374Y201955D01*
X124665Y201871D01*
X124957Y201955D01*
X125165Y202163D01*
X125290Y202496D01*
X125332Y202788D01*
G01X116821Y194281D02*
X116696Y194031D01*
X116613Y193739D01*
Y193406D01*
X116738Y193031D01*
X116946Y192739D01*
X117196Y192531D01*
X117613Y192364D01*
X117988Y192322D01*
X118363Y192406D01*
X118613Y192531D01*
X118863Y192781D01*
X119030Y193072D01*
X119113Y193364D01*
Y193656D01*
X119030Y193947D01*
X118905Y194197D01*
X118738Y194406D01*
G01X116613Y196464D02*
X119113D01*
G01X116613Y195506D02*
Y197422D01*
G01X117030Y198772D02*
X116780Y199022D01*
X116655Y199314D01*
X116613Y199647D01*
X116696Y200064D01*
X116905Y200356D01*
X117155Y200439D01*
X117405Y200397D01*
X117613Y200231D01*
X118030Y199397D01*
X118321Y199022D01*
X118738Y198772D01*
X119113Y198689D01*
Y200439D01*
G01Y203164D02*
X116613D01*
X118405Y201622D01*
Y203706D01*
G01X133115Y197514D02*
X132990Y197264D01*
X132907Y196972D01*
Y196639D01*
X133032Y196264D01*
X133240Y195972D01*
X133490Y195764D01*
X133907Y195597D01*
X134282Y195555D01*
X134657Y195639D01*
X134907Y195764D01*
X135157Y196014D01*
X135324Y196305D01*
X135407Y196597D01*
Y196889D01*
X135324Y197180D01*
X135199Y197430D01*
X135032Y197639D01*
G01X135407Y199697D02*
X132907D01*
X133407Y199197D01*
G01X135407D02*
Y200197D01*
G01Y203630D02*
Y201964D01*
X132907D01*
Y203630D01*
G01X134115Y202964D02*
Y201964D01*
G01X135407Y205814D02*
X134865Y205897D01*
X134407Y206022D01*
X133990Y206189D01*
X133532Y206397D01*
X132907Y206730D01*
Y205064D01*
G01X150193Y204014D02*
X149943Y204139D01*
X149651Y204222D01*
X149318D01*
X148943Y204097D01*
X148651Y203889D01*
X148443Y203639D01*
X148276Y203222D01*
X148234Y202847D01*
X148318Y202472D01*
X148443Y202222D01*
X148693Y201972D01*
X148984Y201805D01*
X149276Y201722D01*
X149568D01*
X149859Y201805D01*
X150109Y201930D01*
X150318Y202097D01*
G01X152376Y204222D02*
Y201722D01*
G01X151418Y204222D02*
X153334D01*
G01X154684Y203805D02*
X154934Y204055D01*
X155226Y204180D01*
X155559Y204222D01*
X155976Y204139D01*
X156268Y203930D01*
X156351Y203680D01*
X156309Y203430D01*
X156143Y203222D01*
X155309Y202805D01*
X154934Y202514D01*
X154684Y202097D01*
X154601Y201722D01*
X156351D01*
G01X157659Y202222D02*
X157909Y201930D01*
X158243Y201764D01*
X158618Y201722D01*
X158951Y201764D01*
X159284Y201972D01*
X159493Y202222D01*
X159534Y202472D01*
X159451Y202764D01*
X159159Y202972D01*
X158868Y203055D01*
X158493D01*
G01X158868D02*
X159118Y203180D01*
X159326Y203389D01*
X159409Y203639D01*
X159326Y203889D01*
X159118Y204097D01*
X158743Y204222D01*
X158368Y204180D01*
X157993Y204014D01*
G01X122553Y178595D02*
X122428Y178345D01*
X122345Y178053D01*
Y177720D01*
X122470Y177345D01*
X122678Y177053D01*
X122928Y176845D01*
X123345Y176678D01*
X123720Y176636D01*
X124095Y176720D01*
X124345Y176845D01*
X124595Y177095D01*
X124762Y177386D01*
X124845Y177678D01*
Y177970D01*
X124762Y178261D01*
X124637Y178511D01*
X124470Y178720D01*
G01X124845Y180778D02*
X122345D01*
X122845Y180278D01*
G01X124845D02*
Y181278D01*
G01Y184711D02*
Y183045D01*
X122345D01*
Y184711D01*
G01X123553Y184045D02*
Y183045D01*
G01X124845Y186978D02*
X122345D01*
X122845Y186478D01*
G01X124845D02*
Y187478D01*
G01Y190078D02*
X124803Y190370D01*
X124678Y190703D01*
X124470Y190911D01*
X124178Y190995D01*
X123887Y190911D01*
X123637Y190661D01*
X123512Y190286D01*
Y189870D01*
X123428Y189620D01*
X123220Y189411D01*
X122928Y189328D01*
X122637Y189453D01*
X122428Y189745D01*
X122345Y190078D01*
X122428Y190411D01*
X122637Y190703D01*
X122928Y190828D01*
X123220Y190745D01*
X123428Y190536D01*
X123512Y190286D01*
Y189870D01*
X123637Y189495D01*
X123887Y189245D01*
X124178Y189161D01*
X124470Y189245D01*
X124678Y189453D01*
X124803Y189786D01*
X124845Y190078D01*
G01X145541Y177767D02*
X145416Y177517D01*
X145333Y177225D01*
Y176892D01*
X145458Y176517D01*
X145666Y176225D01*
X145916Y176017D01*
X146333Y175850D01*
X146708Y175808D01*
X147083Y175892D01*
X147333Y176017D01*
X147583Y176267D01*
X147750Y176558D01*
X147833Y176850D01*
Y177142D01*
X147750Y177433D01*
X147625Y177683D01*
X147458Y177892D01*
G01X147833Y179950D02*
X145333D01*
X145833Y179450D01*
G01X147833D02*
Y180450D01*
G01Y182258D02*
X145333D01*
Y183842D01*
G01X146541Y183258D02*
Y182258D01*
G01X147833Y186067D02*
X147291Y186150D01*
X146833Y186275D01*
X146416Y186442D01*
X145958Y186650D01*
X145333Y186983D01*
Y185317D01*
G01X143118Y191287D02*
X140618D01*
Y192328D01*
X140743Y192662D01*
X140910Y192870D01*
X141243Y192953D01*
X141576Y192870D01*
X141785Y192620D01*
X141910Y192328D01*
Y191287D01*
G01Y192328D02*
X143118Y192953D01*
G01X140618Y195220D02*
X143118D01*
G01X140618Y194262D02*
Y196178D01*
G01X143118Y198320D02*
X140618D01*
X141118Y197820D01*
G01X143118D02*
Y198820D01*
G01X142076Y200628D02*
X141785Y200920D01*
X141618Y201170D01*
X141535Y201503D01*
X141618Y201795D01*
X141785Y202003D01*
X142035Y202170D01*
X142326Y202212D01*
X142576Y202170D01*
X142826Y202003D01*
X143035Y201753D01*
X143118Y201462D01*
X143035Y201128D01*
X142785Y200837D01*
X142410Y200670D01*
X141993Y200628D01*
X141451Y200712D01*
X141160Y200837D01*
X140868Y201045D01*
X140660Y201337D01*
X140618Y201628D01*
X140701Y201920D01*
X140910Y202128D01*
G01X115789Y204977D02*
X114123D01*
Y207477D01*
X115789D01*
G01X115123Y206269D02*
X114123D01*
G01X117139Y207477D02*
Y205685D01*
X117306Y205310D01*
X117639Y205060D01*
X118056Y204977D01*
X118473Y205060D01*
X118806Y205310D01*
X118973Y205685D01*
Y207477D01*
G01X121156Y204977D02*
Y207477D01*
X120656Y206977D01*
G01Y204977D02*
X121656D01*
G01X125089D02*
X123423D01*
Y207477D01*
X125089D01*
G01X124423Y206269D02*
X123423D01*
G01X126564Y207060D02*
X126814Y207310D01*
X127106Y207435D01*
X127439Y207477D01*
X127856Y207394D01*
X128148Y207185D01*
X128231Y206935D01*
X128189Y206685D01*
X128023Y206477D01*
X127189Y206060D01*
X126814Y205769D01*
X126564Y205352D01*
X126481Y204977D01*
X128231D01*
G01X147063Y212716D02*
X119763D01*
Y236266D01*
X147063D01*
Y212716D01*
G01X190574Y217983D02*
Y211935D01*
X153174D01*
Y217983D01*
G01X127189Y237046D02*
X129000D01*
G01X135777Y236959D02*
X138078D01*
Y238406D01*
X155308D01*
Y242790D01*
X147986D01*
Y270454D01*
X159999D01*
Y275101D01*
X148162D01*
Y298776D01*
G01X147063Y276716D02*
X119763D01*
Y300266D01*
X147063D01*
Y276716D01*
G01Y244716D02*
X119763D01*
Y268266D01*
X147063D01*
Y244716D01*
G01X190574Y281983D02*
Y275935D01*
X153174D01*
Y281983D01*
G01Y231083D02*
Y237131D01*
G01D02*
X190574D01*
Y231083D01*
G01Y249983D02*
Y243935D01*
X153174D01*
Y249983D01*
G01Y263083D02*
Y269131D01*
G01D02*
X190574D01*
Y263083D01*
G01X155768Y307193D02*
Y303422D01*
X148096D01*
Y302568D01*
G01X146450Y371599D02*
X152632D01*
Y366511D01*
X149083D01*
Y343275D01*
X152436D01*
Y338803D01*
X155198D01*
Y334200D01*
X148425D01*
Y308070D01*
X152108D01*
G01X147063Y340716D02*
X119763D01*
Y364266D01*
X147063D01*
Y340716D01*
G01Y308716D02*
X119763D01*
Y332266D01*
X147063D01*
Y308716D01*
G01X153174Y295083D02*
Y301131D01*
G01D02*
X190574D01*
Y295083D01*
G01Y313983D02*
Y307935D01*
X153174D01*
Y313983D01*
G01Y327083D02*
Y333131D01*
G01D02*
X190574D01*
Y327083D01*
G01Y345483D02*
Y339435D01*
X153174D01*
Y345483D01*
G01X119000Y379000D02*
Y374000D01*
G01X118963Y382996D02*
Y397499D01*
X118964Y397500D01*
X121000D01*
Y428500D01*
X111500D01*
Y400500D01*
G01X158978Y400128D02*
Y402628D01*
X160019D01*
X160353Y402503D01*
X160561Y402336D01*
X160644Y402003D01*
X160561Y401670D01*
X160311Y401461D01*
X160019Y401336D01*
X158978D01*
G01X160019D02*
X160644Y400128D01*
G01X162911D02*
Y402628D01*
X162411Y402128D01*
G01Y400128D02*
X163411D01*
G01X166928Y402420D02*
X166678Y402545D01*
X166386Y402628D01*
X166053D01*
X165678Y402503D01*
X165386Y402295D01*
X165178Y402045D01*
X165011Y401628D01*
X164969Y401253D01*
X165053Y400878D01*
X165178Y400628D01*
X165428Y400378D01*
X165719Y400211D01*
X166011Y400128D01*
X166303D01*
X166594Y400211D01*
X166844Y400336D01*
X167053Y400503D01*
G01X169028Y400128D02*
X169111Y400670D01*
X169236Y401128D01*
X169403Y401545D01*
X169611Y402003D01*
X169944Y402628D01*
X168278D01*
G01X154605Y399282D02*
X152105D01*
Y400323D01*
X152230Y400657D01*
X152397Y400865D01*
X152730Y400948D01*
X153063Y400865D01*
X153272Y400615D01*
X153397Y400323D01*
Y399282D01*
G01Y400323D02*
X154605Y400948D01*
G01Y403215D02*
X152105D01*
X152605Y402715D01*
G01X154605D02*
Y403715D01*
G01X152313Y407232D02*
X152188Y406982D01*
X152105Y406690D01*
Y406357D01*
X152230Y405982D01*
X152438Y405690D01*
X152688Y405482D01*
X153105Y405315D01*
X153480Y405273D01*
X153855Y405357D01*
X154105Y405482D01*
X154355Y405732D01*
X154522Y406023D01*
X154605Y406315D01*
Y406607D01*
X154522Y406898D01*
X154397Y407148D01*
X154230Y407357D01*
G01X153563Y408623D02*
X153272Y408915D01*
X153105Y409165D01*
X153022Y409498D01*
X153105Y409790D01*
X153272Y409998D01*
X153522Y410165D01*
X153813Y410207D01*
X154063Y410165D01*
X154313Y409998D01*
X154522Y409748D01*
X154605Y409457D01*
X154522Y409123D01*
X154272Y408832D01*
X153897Y408665D01*
X153480Y408623D01*
X152938Y408707D01*
X152647Y408832D01*
X152355Y409040D01*
X152147Y409332D01*
X152105Y409623D01*
X152188Y409915D01*
X152397Y410123D01*
G01X126833Y401343D02*
Y399677D01*
X124333D01*
Y401343D01*
G01X125541Y400677D02*
Y399677D01*
G01X124333Y402693D02*
X126125D01*
X126500Y402860D01*
X126750Y403193D01*
X126833Y403610D01*
X126750Y404027D01*
X126500Y404360D01*
X126125Y404527D01*
X124333D01*
G01X126833Y406710D02*
X124333D01*
X124833Y406210D01*
G01X126833D02*
Y407210D01*
G01X124541Y410727D02*
X124416Y410477D01*
X124333Y410185D01*
Y409852D01*
X124458Y409477D01*
X124666Y409185D01*
X124916Y408977D01*
X125333Y408810D01*
X125708Y408768D01*
X126083Y408852D01*
X126333Y408977D01*
X126583Y409227D01*
X126750Y409518D01*
X126833Y409810D01*
Y410102D01*
X126750Y410393D01*
X126625Y410643D01*
X126458Y410852D01*
G01X126833Y412910D02*
X124333D01*
X124833Y412410D01*
G01X126833D02*
Y413410D01*
G01X147063Y372716D02*
X119763D01*
Y396266D01*
X147063D01*
Y372716D01*
G01X190574Y377983D02*
Y371935D01*
X153174D01*
Y377983D01*
G01Y391083D02*
Y397131D01*
G01D02*
X190574D01*
Y391083D01*
G01X153174Y358583D02*
Y364631D01*
G01D02*
X190574D01*
Y358583D01*
G01X117833Y423432D02*
X118366Y423782D01*
X118766Y424366D01*
X119033Y425182D01*
X118766Y425882D01*
X118233Y426349D01*
X117299Y426699D01*
X113699D01*
Y419699D01*
X118099D01*
X119033Y420166D01*
X119566Y420866D01*
X119833Y421682D01*
X119566Y422499D01*
X118766Y423199D01*
X117833Y423432D01*
X113699D01*
G01X174633Y447400D02*
X213671D01*
Y461699D01*
X213672Y461700D01*
X233399D01*
X233400Y461699D01*
Y416300D01*
X194601D01*
X194600Y416301D01*
Y425299D01*
X194599Y425300D01*
X174633D01*
Y447400D01*
X161300D01*
Y508457D01*
X187158D01*
X187159Y508458D01*
Y512074D01*
X203273D01*
G01X159091Y415559D02*
Y418059D01*
X160132D01*
X160466Y417934D01*
X160674Y417767D01*
X160757Y417434D01*
X160674Y417101D01*
X160424Y416892D01*
X160132Y416767D01*
X159091D01*
G01X160132D02*
X160757Y415559D01*
G01X162316Y415851D02*
X162607Y415642D01*
X162941Y415559D01*
X163274Y415642D01*
X163566Y415892D01*
X163774Y416267D01*
X163857Y416642D01*
Y417101D01*
X163774Y417476D01*
X163566Y417809D01*
X163316Y417976D01*
X163024Y418059D01*
X162691Y417976D01*
X162441Y417809D01*
X162274Y417559D01*
X162191Y417226D01*
X162274Y416934D01*
X162482Y416642D01*
X162732Y416476D01*
X163024Y416434D01*
X163357Y416517D01*
X163607Y416726D01*
X163857Y417101D01*
G01X165166Y415559D02*
Y418059D01*
X167082Y415559D01*
Y418059D01*
G01X168432Y417642D02*
X168682Y417892D01*
X168974Y418017D01*
X169307Y418059D01*
X169724Y417976D01*
X170016Y417767D01*
X170099Y417517D01*
X170057Y417267D01*
X169891Y417059D01*
X169057Y416642D01*
X168682Y416351D01*
X168432Y415934D01*
X168349Y415559D01*
X170099D01*
G01X159062Y419258D02*
Y421758D01*
X160103D01*
X160437Y421633D01*
X160645Y421466D01*
X160728Y421133D01*
X160645Y420800D01*
X160395Y420591D01*
X160103Y420466D01*
X159062D01*
G01X160103D02*
X160728Y419258D01*
G01X162287Y419550D02*
X162578Y419341D01*
X162912Y419258D01*
X163245Y419341D01*
X163537Y419591D01*
X163745Y419966D01*
X163828Y420341D01*
Y420800D01*
X163745Y421175D01*
X163537Y421508D01*
X163287Y421675D01*
X162995Y421758D01*
X162662Y421675D01*
X162412Y421508D01*
X162245Y421258D01*
X162162Y420925D01*
X162245Y420633D01*
X162453Y420341D01*
X162703Y420175D01*
X162995Y420133D01*
X163328Y420216D01*
X163578Y420425D01*
X163828Y420800D01*
G01X165137Y419258D02*
Y421758D01*
X167053Y419258D01*
Y421758D01*
G01X169195Y419258D02*
Y421758D01*
X168695Y421258D01*
G01Y419258D02*
X169695D01*
G01X159478Y409969D02*
Y412469D01*
X160519D01*
X160853Y412344D01*
X161061Y412177D01*
X161144Y411844D01*
X161061Y411511D01*
X160811Y411302D01*
X160519Y411177D01*
X159478D01*
G01X160519D02*
X161144Y409969D01*
G01X163411D02*
Y412469D01*
X162911Y411969D01*
G01Y409969D02*
X163911D01*
G01X167428Y412261D02*
X167178Y412386D01*
X166886Y412469D01*
X166553D01*
X166178Y412344D01*
X165886Y412136D01*
X165678Y411886D01*
X165511Y411469D01*
X165469Y411094D01*
X165553Y410719D01*
X165678Y410469D01*
X165928Y410219D01*
X166219Y410052D01*
X166511Y409969D01*
X166803D01*
X167094Y410052D01*
X167344Y410177D01*
X167553Y410344D01*
G01X168694D02*
X168944Y410136D01*
X169236Y410011D01*
X169611Y409969D01*
X169986Y410052D01*
X170278Y410219D01*
X170486Y410511D01*
X170528Y410844D01*
X170444Y411177D01*
X170236Y411386D01*
X169944Y411552D01*
X169653Y411594D01*
X169361Y411552D01*
X168986Y411386D01*
X169111Y412469D01*
X170236D01*
G01X167938Y448623D02*
X165438D01*
Y449664D01*
X165563Y449998D01*
X165730Y450206D01*
X166063Y450289D01*
X166396Y450206D01*
X166605Y449956D01*
X166730Y449664D01*
Y448623D01*
G01Y449664D02*
X167938Y450289D01*
G01Y452556D02*
X165438D01*
X165938Y452056D01*
G01X167938D02*
Y453056D01*
G01X166605Y455989D02*
X166480Y456156D01*
X166271Y456281D01*
X165980Y456364D01*
X165730Y456281D01*
X165563Y456114D01*
X165438Y455823D01*
Y454698D01*
X167938D01*
Y456073D01*
X167771Y456364D01*
X167521Y456531D01*
X167230Y456614D01*
X166938Y456531D01*
X166688Y456281D01*
X166605Y455989D01*
Y454698D01*
G01X167938Y458756D02*
X165438D01*
X165938Y458256D01*
G01X167938D02*
Y459256D01*
G01X166896Y461064D02*
X166605Y461356D01*
X166438Y461606D01*
X166355Y461939D01*
X166438Y462231D01*
X166605Y462439D01*
X166855Y462606D01*
X167146Y462648D01*
X167396Y462606D01*
X167646Y462439D01*
X167855Y462189D01*
X167938Y461898D01*
X167855Y461564D01*
X167605Y461273D01*
X167230Y461106D01*
X166813Y461064D01*
X166271Y461148D01*
X165980Y461273D01*
X165688Y461481D01*
X165480Y461773D01*
X165438Y462064D01*
X165521Y462356D01*
X165730Y462564D01*
G01X164615Y448672D02*
X162115D01*
Y449713D01*
X162240Y450047D01*
X162407Y450255D01*
X162740Y450338D01*
X163073Y450255D01*
X163282Y450005D01*
X163407Y449713D01*
Y448672D01*
G01Y449713D02*
X164615Y450338D01*
G01Y452605D02*
X162115D01*
X162615Y452105D01*
G01X164615D02*
Y453105D01*
G01X162532Y454913D02*
X162282Y455163D01*
X162157Y455455D01*
X162115Y455788D01*
X162198Y456205D01*
X162407Y456497D01*
X162657Y456580D01*
X162907Y456538D01*
X163115Y456372D01*
X163532Y455538D01*
X163823Y455163D01*
X164240Y454913D01*
X164615Y454830D01*
Y456580D01*
G01X162115Y457555D02*
X164615Y458138D01*
X162115Y458805D01*
X164615Y459472D01*
X162115Y460055D01*
G01X164115Y460988D02*
X164407Y461238D01*
X164573Y461572D01*
X164615Y461947D01*
X164573Y462280D01*
X164365Y462613D01*
X164115Y462822D01*
X163865Y462863D01*
X163573Y462780D01*
X163365Y462488D01*
X163282Y462197D01*
Y461822D01*
G01Y462197D02*
X163157Y462447D01*
X162948Y462655D01*
X162698Y462738D01*
X162448Y462655D01*
X162240Y462447D01*
X162115Y462072D01*
X162157Y461697D01*
X162323Y461322D01*
G01X163573Y464213D02*
X163282Y464505D01*
X163115Y464755D01*
X163032Y465088D01*
X163115Y465380D01*
X163282Y465588D01*
X163532Y465755D01*
X163823Y465797D01*
X164073Y465755D01*
X164323Y465588D01*
X164532Y465338D01*
X164615Y465047D01*
X164532Y464713D01*
X164282Y464422D01*
X163907Y464255D01*
X163490Y464213D01*
X162948Y464297D01*
X162657Y464422D01*
X162365Y464630D01*
X162157Y464922D01*
X162115Y465213D01*
X162198Y465505D01*
X162407Y465713D01*
G01X169146Y450373D02*
X169021Y450123D01*
X168938Y449831D01*
Y449498D01*
X169063Y449123D01*
X169271Y448831D01*
X169521Y448623D01*
X169938Y448456D01*
X170313Y448414D01*
X170688Y448498D01*
X170938Y448623D01*
X171188Y448873D01*
X171355Y449164D01*
X171438Y449456D01*
Y449748D01*
X171355Y450039D01*
X171230Y450289D01*
X171063Y450498D01*
G01X171438Y452556D02*
X168938D01*
X169438Y452056D01*
G01X171438D02*
Y453056D01*
G01X170105Y455989D02*
X169980Y456156D01*
X169771Y456281D01*
X169480Y456364D01*
X169230Y456281D01*
X169063Y456114D01*
X168938Y455823D01*
Y454698D01*
X171438D01*
Y456073D01*
X171271Y456364D01*
X171021Y456531D01*
X170730Y456614D01*
X170438Y456531D01*
X170188Y456281D01*
X170105Y455989D01*
Y454698D01*
G01X171438Y458756D02*
X168938D01*
X169438Y458256D01*
G01X171438D02*
Y459256D01*
G01X169355Y461064D02*
X169105Y461314D01*
X168980Y461606D01*
X168938Y461939D01*
X169021Y462356D01*
X169230Y462648D01*
X169480Y462731D01*
X169730Y462689D01*
X169938Y462523D01*
X170355Y461689D01*
X170646Y461314D01*
X171063Y461064D01*
X171438Y460981D01*
Y462731D01*
G01X129822Y410926D02*
X129572Y411051D01*
X129280Y411134D01*
X128947D01*
X128572Y411009D01*
X128280Y410801D01*
X128072Y410551D01*
X127905Y410134D01*
X127863Y409759D01*
X127947Y409384D01*
X128072Y409134D01*
X128322Y408884D01*
X128613Y408717D01*
X128905Y408634D01*
X129197D01*
X129488Y408717D01*
X129738Y408842D01*
X129947Y409009D01*
G01X132005Y408634D02*
Y411134D01*
X131505Y410634D01*
G01Y408634D02*
X132505D01*
G01X136022Y410926D02*
X135772Y411051D01*
X135480Y411134D01*
X135147D01*
X134772Y411009D01*
X134480Y410801D01*
X134272Y410551D01*
X134105Y410134D01*
X134063Y409759D01*
X134147Y409384D01*
X134272Y409134D01*
X134522Y408884D01*
X134813Y408717D01*
X135105Y408634D01*
X135397D01*
X135688Y408717D01*
X135938Y408842D01*
X136147Y409009D01*
G01X138205Y408634D02*
Y411134D01*
X137705Y410634D01*
G01Y408634D02*
X138705D01*
G01X140388Y409009D02*
X140638Y408801D01*
X140930Y408676D01*
X141305Y408634D01*
X141680Y408717D01*
X141972Y408884D01*
X142180Y409176D01*
X142222Y409509D01*
X142138Y409842D01*
X141930Y410051D01*
X141638Y410217D01*
X141347Y410259D01*
X141055Y410217D01*
X140680Y410051D01*
X140805Y411134D01*
X141930D01*
G01X129822Y407024D02*
X129572Y407149D01*
X129280Y407232D01*
X128947D01*
X128572Y407107D01*
X128280Y406899D01*
X128072Y406649D01*
X127905Y406232D01*
X127863Y405857D01*
X127947Y405482D01*
X128072Y405232D01*
X128322Y404982D01*
X128613Y404815D01*
X128905Y404732D01*
X129197D01*
X129488Y404815D01*
X129738Y404940D01*
X129947Y405107D01*
G01X132005Y404732D02*
Y407232D01*
X131505Y406732D01*
G01Y404732D02*
X132505D01*
G01X136022Y407024D02*
X135772Y407149D01*
X135480Y407232D01*
X135147D01*
X134772Y407107D01*
X134480Y406899D01*
X134272Y406649D01*
X134105Y406232D01*
X134063Y405857D01*
X134147Y405482D01*
X134272Y405232D01*
X134522Y404982D01*
X134813Y404815D01*
X135105Y404732D01*
X135397D01*
X135688Y404815D01*
X135938Y404940D01*
X136147Y405107D01*
G01X138205Y404732D02*
Y407232D01*
X137705Y406732D01*
G01Y404732D02*
X138705D01*
G01X141222D02*
X141305Y405274D01*
X141430Y405732D01*
X141597Y406149D01*
X141805Y406607D01*
X142138Y407232D01*
X140472D01*
G01X108900Y431486D02*
X108775Y431236D01*
X108692Y430944D01*
Y430611D01*
X108817Y430236D01*
X109025Y429944D01*
X109275Y429736D01*
X109692Y429569D01*
X110067Y429527D01*
X110442Y429611D01*
X110692Y429736D01*
X110942Y429986D01*
X111109Y430277D01*
X111192Y430569D01*
Y430861D01*
X111109Y431152D01*
X110984Y431402D01*
X110817Y431611D01*
G01X111192Y433669D02*
X108692D01*
X109192Y433169D01*
G01X111192D02*
Y434169D01*
G01X108900Y437686D02*
X108775Y437436D01*
X108692Y437144D01*
Y436811D01*
X108817Y436436D01*
X109025Y436144D01*
X109275Y435936D01*
X109692Y435769D01*
X110067Y435727D01*
X110442Y435811D01*
X110692Y435936D01*
X110942Y436186D01*
X111109Y436477D01*
X111192Y436769D01*
Y437061D01*
X111109Y437352D01*
X110984Y437602D01*
X110817Y437811D01*
G01X111192Y439869D02*
X108692D01*
X109192Y439369D01*
G01X111192D02*
Y440369D01*
G01X145157Y482715D02*
X155157D01*
X158157Y479215D01*
Y442215D01*
X143457D01*
G01X132357D02*
X117657D01*
Y479215D01*
G01X168706Y465664D02*
Y468164D01*
X169747D01*
X170081Y468039D01*
X170289Y467872D01*
X170372Y467539D01*
X170289Y467206D01*
X170039Y466997D01*
X169747Y466872D01*
X168706D01*
G01X169747D02*
X170372Y465664D01*
G01X172639D02*
Y468164D01*
X172139Y467664D01*
G01Y465664D02*
X173139D01*
G01X176072Y466997D02*
X176239Y467122D01*
X176364Y467331D01*
X176447Y467622D01*
X176364Y467872D01*
X176197Y468039D01*
X175906Y468164D01*
X174781D01*
Y465664D01*
X176156D01*
X176447Y465831D01*
X176614Y466081D01*
X176697Y466372D01*
X176614Y466664D01*
X176364Y466914D01*
X176072Y466997D01*
X174781D01*
G01X178839Y465664D02*
Y468164D01*
X178339Y467664D01*
G01Y465664D02*
X179339D01*
G01X181939Y468164D02*
X181606Y468081D01*
X181356Y467872D01*
X181189Y467622D01*
X181064Y467289D01*
X181022Y466914D01*
X181064Y466539D01*
X181189Y466206D01*
X181356Y465956D01*
X181606Y465747D01*
X181939Y465664D01*
X182272Y465747D01*
X182522Y465956D01*
X182689Y466206D01*
X182814Y466539D01*
X182856Y466914D01*
X182814Y467289D01*
X182689Y467622D01*
X182522Y467872D01*
X182272Y468081D01*
X181939Y468164D01*
G01X169275Y481470D02*
X166775D01*
Y482511D01*
X166900Y482845D01*
X167067Y483053D01*
X167400Y483136D01*
X167733Y483053D01*
X167942Y482803D01*
X168067Y482511D01*
Y481470D01*
G01Y482511D02*
X169275Y483136D01*
G01Y485403D02*
X166775D01*
X167275Y484903D01*
G01X169275D02*
Y485903D01*
G01X167942Y488836D02*
X167817Y489003D01*
X167608Y489128D01*
X167317Y489211D01*
X167067Y489128D01*
X166900Y488961D01*
X166775Y488670D01*
Y487545D01*
X169275D01*
Y488920D01*
X169108Y489211D01*
X168858Y489378D01*
X168567Y489461D01*
X168275Y489378D01*
X168025Y489128D01*
X167942Y488836D01*
Y487545D01*
G01X169275Y492103D02*
X166775D01*
X168567Y490561D01*
Y492645D01*
G01X168676Y469477D02*
Y471977D01*
X169717D01*
X170051Y471852D01*
X170259Y471685D01*
X170342Y471352D01*
X170259Y471019D01*
X170009Y470810D01*
X169717Y470685D01*
X168676D01*
G01X169717D02*
X170342Y469477D01*
G01X172609D02*
Y471977D01*
X172109Y471477D01*
G01Y469477D02*
X173109D01*
G01X176042Y470810D02*
X176209Y470935D01*
X176334Y471144D01*
X176417Y471435D01*
X176334Y471685D01*
X176167Y471852D01*
X175876Y471977D01*
X174751D01*
Y469477D01*
X176126D01*
X176417Y469644D01*
X176584Y469894D01*
X176667Y470185D01*
X176584Y470477D01*
X176334Y470727D01*
X176042Y470810D01*
X174751D01*
G01X178809Y469477D02*
X179101Y469519D01*
X179434Y469644D01*
X179642Y469852D01*
X179726Y470144D01*
X179642Y470435D01*
X179392Y470685D01*
X179017Y470810D01*
X178601D01*
X178351Y470894D01*
X178142Y471102D01*
X178059Y471394D01*
X178184Y471685D01*
X178476Y471894D01*
X178809Y471977D01*
X179142Y471894D01*
X179434Y471685D01*
X179559Y471394D01*
X179476Y471102D01*
X179267Y470894D01*
X179017Y470810D01*
X178601D01*
X178226Y470685D01*
X177976Y470435D01*
X177892Y470144D01*
X177976Y469852D01*
X178184Y469644D01*
X178517Y469519D01*
X178809Y469477D01*
G01X167782Y493685D02*
Y496185D01*
X168823D01*
X169157Y496060D01*
X169365Y495893D01*
X169448Y495560D01*
X169365Y495227D01*
X169115Y495018D01*
X168823Y494893D01*
X167782D01*
G01X168823D02*
X169448Y493685D01*
G01X171715D02*
Y496185D01*
X171215Y495685D01*
G01Y493685D02*
X172215D01*
G01X173773D02*
X174815Y496185D01*
X175857Y493685D01*
G01X175482Y494560D02*
X174148D01*
G01X176998Y494185D02*
X177248Y493893D01*
X177582Y493727D01*
X177957Y493685D01*
X178290Y493727D01*
X178623Y493935D01*
X178832Y494185D01*
X178873Y494435D01*
X178790Y494727D01*
X178498Y494935D01*
X178207Y495018D01*
X177832D01*
G01X178207D02*
X178457Y495143D01*
X178665Y495352D01*
X178748Y495602D01*
X178665Y495852D01*
X178457Y496060D01*
X178082Y496185D01*
X177707Y496143D01*
X177332Y495977D01*
G01X165146Y484884D02*
X162646D01*
Y485925D01*
X162771Y486259D01*
X162938Y486467D01*
X163271Y486550D01*
X163604Y486467D01*
X163813Y486217D01*
X163938Y485925D01*
Y484884D01*
G01Y485925D02*
X165146Y486550D01*
G01Y488817D02*
X162646D01*
X163146Y488317D01*
G01X165146D02*
Y489317D01*
G01X163813Y492250D02*
X163688Y492417D01*
X163479Y492542D01*
X163188Y492625D01*
X162938Y492542D01*
X162771Y492375D01*
X162646Y492084D01*
Y490959D01*
X165146D01*
Y492334D01*
X164979Y492625D01*
X164729Y492792D01*
X164438Y492875D01*
X164146Y492792D01*
X163896Y492542D01*
X163813Y492250D01*
Y490959D01*
G01X165146Y495017D02*
X162646D01*
X163146Y494517D01*
G01X165146D02*
Y495517D01*
G01X165147Y468233D02*
X162647D01*
Y469274D01*
X162772Y469608D01*
X162939Y469816D01*
X163272Y469899D01*
X163605Y469816D01*
X163814Y469566D01*
X163939Y469274D01*
Y468233D01*
G01Y469274D02*
X165147Y469899D01*
G01Y472166D02*
X162647D01*
X163147Y471666D01*
G01X165147D02*
Y472666D01*
G01X163814Y475599D02*
X163689Y475766D01*
X163480Y475891D01*
X163189Y475974D01*
X162939Y475891D01*
X162772Y475724D01*
X162647Y475433D01*
Y474308D01*
X165147D01*
Y475683D01*
X164980Y475974D01*
X164730Y476141D01*
X164439Y476224D01*
X164147Y476141D01*
X163897Y475891D01*
X163814Y475599D01*
Y474308D01*
G01X165147Y478366D02*
X162647D01*
X163147Y477866D01*
G01X165147D02*
Y478866D01*
G01X164647Y480549D02*
X164939Y480799D01*
X165105Y481133D01*
X165147Y481508D01*
X165105Y481841D01*
X164897Y482174D01*
X164647Y482383D01*
X164397Y482424D01*
X164105Y482341D01*
X163897Y482049D01*
X163814Y481758D01*
Y481383D01*
G01Y481758D02*
X163689Y482008D01*
X163480Y482216D01*
X163230Y482299D01*
X162980Y482216D01*
X162772Y482008D01*
X162647Y481633D01*
X162689Y481258D01*
X162855Y480883D01*
G01X168576Y476877D02*
Y479377D01*
X169617D01*
X169951Y479252D01*
X170159Y479085D01*
X170242Y478752D01*
X170159Y478419D01*
X169909Y478210D01*
X169617Y478085D01*
X168576D01*
G01X169617D02*
X170242Y476877D01*
G01X172509D02*
Y479377D01*
X172009Y478877D01*
G01Y476877D02*
X173009D01*
G01X174817Y478960D02*
X175067Y479210D01*
X175359Y479335D01*
X175692Y479377D01*
X176109Y479294D01*
X176401Y479085D01*
X176484Y478835D01*
X176442Y478585D01*
X176276Y478377D01*
X175442Y477960D01*
X175067Y477669D01*
X174817Y477252D01*
X174734Y476877D01*
X176484D01*
G01X177459Y479377D02*
X178042Y476877D01*
X178709Y479377D01*
X179376Y476877D01*
X179959Y479377D01*
G01X180892Y477377D02*
X181142Y477085D01*
X181476Y476919D01*
X181851Y476877D01*
X182184Y476919D01*
X182517Y477127D01*
X182726Y477377D01*
X182767Y477627D01*
X182684Y477919D01*
X182392Y478127D01*
X182101Y478210D01*
X181726D01*
G01X182101D02*
X182351Y478335D01*
X182559Y478544D01*
X182642Y478794D01*
X182559Y479044D01*
X182351Y479252D01*
X181976Y479377D01*
X181601Y479335D01*
X181226Y479169D01*
G01X185409Y476877D02*
Y479377D01*
X183867Y477585D01*
X185951D01*
G01X168576Y473177D02*
Y475677D01*
X169617D01*
X169951Y475552D01*
X170159Y475385D01*
X170242Y475052D01*
X170159Y474719D01*
X169909Y474510D01*
X169617Y474385D01*
X168576D01*
G01X169617D02*
X170242Y473177D01*
G01X172509D02*
Y475677D01*
X172009Y475177D01*
G01Y473177D02*
X173009D01*
G01X174817Y475260D02*
X175067Y475510D01*
X175359Y475635D01*
X175692Y475677D01*
X176109Y475594D01*
X176401Y475385D01*
X176484Y475135D01*
X176442Y474885D01*
X176276Y474677D01*
X175442Y474260D01*
X175067Y473969D01*
X174817Y473552D01*
X174734Y473177D01*
X176484D01*
G01X177459Y475677D02*
X178042Y473177D01*
X178709Y475677D01*
X179376Y473177D01*
X179959Y475677D01*
G01X180892Y473677D02*
X181142Y473385D01*
X181476Y473219D01*
X181851Y473177D01*
X182184Y473219D01*
X182517Y473427D01*
X182726Y473677D01*
X182767Y473927D01*
X182684Y474219D01*
X182392Y474427D01*
X182101Y474510D01*
X181726D01*
G01X182101D02*
X182351Y474635D01*
X182559Y474844D01*
X182642Y475094D01*
X182559Y475344D01*
X182351Y475552D01*
X181976Y475677D01*
X181601Y475635D01*
X181226Y475469D01*
G01X183992Y473552D02*
X184242Y473344D01*
X184534Y473219D01*
X184909Y473177D01*
X185284Y473260D01*
X185576Y473427D01*
X185784Y473719D01*
X185826Y474052D01*
X185742Y474385D01*
X185534Y474594D01*
X185242Y474760D01*
X184951Y474802D01*
X184659Y474760D01*
X184284Y474594D01*
X184409Y475677D01*
X185534D01*
G01X167682Y497485D02*
Y499985D01*
X168723D01*
X169057Y499860D01*
X169265Y499693D01*
X169348Y499360D01*
X169265Y499027D01*
X169015Y498818D01*
X168723Y498693D01*
X167682D01*
G01X168723D02*
X169348Y497485D01*
G01X171615Y499985D02*
Y497485D01*
G01X170657Y499985D02*
X172573D01*
G01X173798Y497860D02*
X174048Y497652D01*
X174340Y497527D01*
X174715Y497485D01*
X175090Y497568D01*
X175382Y497735D01*
X175590Y498027D01*
X175632Y498360D01*
X175548Y498693D01*
X175340Y498902D01*
X175048Y499068D01*
X174757Y499110D01*
X174465Y499068D01*
X174090Y498902D01*
X174215Y499985D01*
X175340D01*
G01X127955Y508007D02*
X127705Y508132D01*
X127413Y508215D01*
X127080D01*
X126705Y508090D01*
X126413Y507882D01*
X126205Y507632D01*
X126038Y507215D01*
X125996Y506840D01*
X126080Y506465D01*
X126205Y506215D01*
X126455Y505965D01*
X126746Y505798D01*
X127038Y505715D01*
X127330D01*
X127621Y505798D01*
X127871Y505923D01*
X128080Y506090D01*
G01X130138Y505715D02*
Y508215D01*
X129638Y507715D01*
G01Y505715D02*
X130638D01*
G01X133571Y507048D02*
X133738Y507173D01*
X133863Y507382D01*
X133946Y507673D01*
X133863Y507923D01*
X133696Y508090D01*
X133405Y508215D01*
X132280D01*
Y505715D01*
X133655D01*
X133946Y505882D01*
X134113Y506132D01*
X134196Y506423D01*
X134113Y506715D01*
X133863Y506965D01*
X133571Y507048D01*
X132280D01*
G01X135630Y506007D02*
X135921Y505798D01*
X136255Y505715D01*
X136588Y505798D01*
X136880Y506048D01*
X137088Y506423D01*
X137171Y506798D01*
Y507257D01*
X137088Y507632D01*
X136880Y507965D01*
X136630Y508132D01*
X136338Y508215D01*
X136005Y508132D01*
X135755Y507965D01*
X135588Y507715D01*
X135505Y507382D01*
X135588Y507090D01*
X135796Y506798D01*
X136046Y506632D01*
X136338Y506590D01*
X136671Y506673D01*
X136921Y506882D01*
X137171Y507257D01*
G01X169432Y503577D02*
X169182Y503702D01*
X168890Y503785D01*
X168557D01*
X168182Y503660D01*
X167890Y503452D01*
X167682Y503202D01*
X167515Y502785D01*
X167473Y502410D01*
X167557Y502035D01*
X167682Y501785D01*
X167932Y501535D01*
X168223Y501368D01*
X168515Y501285D01*
X168807D01*
X169098Y501368D01*
X169348Y501493D01*
X169557Y501660D01*
G01X171615Y501285D02*
Y503785D01*
X171115Y503285D01*
G01Y501285D02*
X172115D01*
G01X173673D02*
X174715Y503785D01*
X175757Y501285D01*
G01X175382Y502160D02*
X174048D01*
G01X177815Y501285D02*
Y503785D01*
X177315Y503285D01*
G01Y501285D02*
X178315D01*
G01X180915D02*
X181207Y501327D01*
X181540Y501452D01*
X181748Y501660D01*
X181832Y501952D01*
X181748Y502243D01*
X181498Y502493D01*
X181123Y502618D01*
X180707D01*
X180457Y502702D01*
X180248Y502910D01*
X180165Y503202D01*
X180290Y503493D01*
X180582Y503702D01*
X180915Y503785D01*
X181248Y503702D01*
X181540Y503493D01*
X181665Y503202D01*
X181582Y502910D01*
X181373Y502702D01*
X181123Y502618D01*
X180707D01*
X180332Y502493D01*
X180082Y502243D01*
X179998Y501952D01*
X180082Y501660D01*
X180290Y501452D01*
X180623Y501327D01*
X180915Y501285D01*
G01X169232Y507277D02*
X168982Y507402D01*
X168690Y507485D01*
X168357D01*
X167982Y507360D01*
X167690Y507152D01*
X167482Y506902D01*
X167315Y506485D01*
X167273Y506110D01*
X167357Y505735D01*
X167482Y505485D01*
X167732Y505235D01*
X168023Y505068D01*
X168315Y504985D01*
X168607D01*
X168898Y505068D01*
X169148Y505193D01*
X169357Y505360D01*
G01X171415Y504985D02*
Y507485D01*
X170915Y506985D01*
G01Y504985D02*
X171915D01*
G01X173473D02*
X174515Y507485D01*
X175557Y504985D01*
G01X175182Y505860D02*
X173848D01*
G01X177615Y504985D02*
Y507485D01*
X177115Y506985D01*
G01Y504985D02*
X178115D01*
G01X180007Y505277D02*
X180298Y505068D01*
X180632Y504985D01*
X180965Y505068D01*
X181257Y505318D01*
X181465Y505693D01*
X181548Y506068D01*
Y506527D01*
X181465Y506902D01*
X181257Y507235D01*
X181007Y507402D01*
X180715Y507485D01*
X180382Y507402D01*
X180132Y507235D01*
X179965Y506985D01*
X179882Y506652D01*
X179965Y506360D01*
X180173Y506068D01*
X180423Y505902D01*
X180715Y505860D01*
X181048Y505943D01*
X181298Y506152D01*
X181548Y506527D01*
G01X133698Y492549D02*
X133448Y492674D01*
X133156Y492757D01*
X132823D01*
X132448Y492632D01*
X132156Y492424D01*
X131948Y492174D01*
X131781Y491757D01*
X131739Y491382D01*
X131823Y491007D01*
X131948Y490757D01*
X132198Y490507D01*
X132489Y490340D01*
X132781Y490257D01*
X133073D01*
X133364Y490340D01*
X133614Y490465D01*
X133823Y490632D01*
G01X135881Y490257D02*
Y492757D01*
X135381Y492257D01*
G01Y490257D02*
X136381D01*
G01X139314Y491590D02*
X139481Y491715D01*
X139606Y491924D01*
X139689Y492215D01*
X139606Y492465D01*
X139439Y492632D01*
X139148Y492757D01*
X138023D01*
Y490257D01*
X139398D01*
X139689Y490424D01*
X139856Y490674D01*
X139939Y490965D01*
X139856Y491257D01*
X139606Y491507D01*
X139314Y491590D01*
X138023D01*
G01X142081Y490257D02*
Y492757D01*
X141581Y492257D01*
G01Y490257D02*
X142581D01*
G01X145681D02*
Y492757D01*
X144139Y490965D01*
X146223D01*
G01X117657Y479215D02*
X120657Y482715D01*
X130657D01*
G01X132357Y486965D02*
X130657D01*
Y470465D01*
X132357D01*
G01X143457Y486965D02*
X145157D01*
Y470465D01*
X143457D01*
G01X129775Y551760D02*
X129525Y551885D01*
X129233Y551968D01*
X128900D01*
X128525Y551843D01*
X128233Y551635D01*
X128025Y551385D01*
X127858Y550968D01*
X127816Y550593D01*
X127900Y550218D01*
X128025Y549968D01*
X128275Y549718D01*
X128566Y549551D01*
X128858Y549468D01*
X129150D01*
X129441Y549551D01*
X129691Y549676D01*
X129900Y549843D01*
G01X131958Y549468D02*
Y551968D01*
X131458Y551468D01*
G01Y549468D02*
X132458D01*
G01X134016D02*
X135058Y551968D01*
X136100Y549468D01*
G01X135725Y550343D02*
X134391D01*
G01X138158Y549468D02*
Y551968D01*
X137658Y551468D01*
G01Y549468D02*
X138658D01*
G01X141175D02*
X141258Y550010D01*
X141383Y550468D01*
X141550Y550885D01*
X141758Y551343D01*
X142091Y551968D01*
X140425D01*
G01X115030Y546387D02*
Y549487D01*
X114570Y548867D01*
G01Y546387D02*
X115490D01*
G01X118590D02*
Y549487D01*
X117172Y547265D01*
X119088D01*
G01X120387Y546852D02*
X120617Y546594D01*
X120885Y546439D01*
X121230Y546387D01*
X121575Y546490D01*
X121843Y546697D01*
X122035Y547059D01*
X122073Y547472D01*
X121997Y547885D01*
X121805Y548144D01*
X121537Y548350D01*
X121268Y548402D01*
X121000Y548350D01*
X120655Y548144D01*
X120770Y549487D01*
X121805D01*
G01X118830Y584107D02*
Y587207D01*
X118370Y586587D01*
G01Y584107D02*
X119290D01*
G01X122390D02*
Y587207D01*
X120972Y584985D01*
X122888D01*
G01X124187Y584572D02*
X124417Y584314D01*
X124685Y584159D01*
X125030Y584107D01*
X125375Y584210D01*
X125643Y584417D01*
X125835Y584779D01*
X125873Y585192D01*
X125797Y585605D01*
X125605Y585864D01*
X125337Y586070D01*
X125068Y586122D01*
X124800Y586070D01*
X124455Y585864D01*
X124570Y587207D01*
X125605D01*
G01X121267Y593959D02*
X121017Y594084D01*
X120725Y594167D01*
X120392D01*
X120017Y594042D01*
X119725Y593834D01*
X119517Y593584D01*
X119350Y593167D01*
X119308Y592792D01*
X119392Y592417D01*
X119517Y592167D01*
X119767Y591917D01*
X120058Y591750D01*
X120350Y591667D01*
X120642D01*
X120933Y591750D01*
X121183Y591875D01*
X121392Y592042D01*
G01X123450Y591667D02*
Y594167D01*
X122950Y593667D01*
G01Y591667D02*
X123950D01*
G01X125508D02*
X126550Y594167D01*
X127592Y591667D01*
G01X127217Y592542D02*
X125883D01*
G01X128733Y592042D02*
X128983Y591834D01*
X129275Y591709D01*
X129650Y591667D01*
X130025Y591750D01*
X130317Y591917D01*
X130525Y592209D01*
X130567Y592542D01*
X130483Y592875D01*
X130275Y593084D01*
X129983Y593250D01*
X129692Y593292D01*
X129400Y593250D01*
X129025Y593084D01*
X129150Y594167D01*
X130275D01*
G01X113570Y622297D02*
Y625397D01*
X113110Y624777D01*
G01Y622297D02*
X114030D01*
G01X117130D02*
Y625397D01*
X115712Y623175D01*
X117628D01*
G01X118927Y622762D02*
X119157Y622504D01*
X119425Y622349D01*
X119770Y622297D01*
X120115Y622400D01*
X120383Y622607D01*
X120575Y622969D01*
X120613Y623382D01*
X120537Y623795D01*
X120345Y624054D01*
X120077Y624260D01*
X119808Y624312D01*
X119540Y624260D01*
X119195Y624054D01*
X119310Y625397D01*
X120345D01*
G01X110200Y657600D02*
Y660600D01*
X111200D01*
X111600Y660450D01*
X111900Y660250D01*
X112150Y659950D01*
X112350Y659600D01*
X112400Y659100D01*
X112350Y658600D01*
X112150Y658250D01*
X111900Y657950D01*
X111600Y657750D01*
X111200Y657600D01*
X110200D01*
G01X114150Y658950D02*
X115750D01*
X115600Y659300D01*
X115350Y659500D01*
X115000Y659600D01*
X114650Y659550D01*
X114350Y659400D01*
X114150Y659050D01*
X114050Y658750D01*
Y658450D01*
X114150Y658150D01*
X114400Y657850D01*
X114700Y657650D01*
X115050Y657600D01*
X115400Y657700D01*
X115750Y658000D01*
G01X118500Y657600D02*
Y660600D01*
G01X122100D02*
Y657600D01*
G01X121400Y659600D02*
X122800D01*
G01X126600Y657600D02*
Y659600D01*
G01Y659250D02*
X126400Y659450D01*
X126100Y659550D01*
X125750Y659600D01*
X125400Y659500D01*
X125100Y659300D01*
X124900Y659000D01*
X124800Y658600D01*
X124900Y658200D01*
X125100Y657900D01*
X125400Y657700D01*
X125750Y657600D01*
X126100Y657650D01*
X126400Y657800D01*
X126600Y658000D01*
G01X127800Y656600D02*
X130800D01*
G01X131900Y660600D02*
Y657600D01*
X133900D01*
G01X136500D02*
Y660600D01*
X135900Y660000D01*
G01Y657600D02*
X137100D01*
G01X138600Y656600D02*
X141600D01*
G01X142600Y658050D02*
X142900Y657800D01*
X143250Y657650D01*
X143700Y657600D01*
X144150Y657700D01*
X144500Y657900D01*
X144750Y658250D01*
X144800Y658650D01*
X144700Y659050D01*
X144450Y659300D01*
X144100Y659500D01*
X143750Y659550D01*
X143400Y659500D01*
X142950Y659300D01*
X143100Y660600D01*
X144450D01*
G01X147300Y659600D02*
Y657600D01*
G01Y660400D02*
X147200Y660450D01*
Y660550D01*
X147300Y660600D01*
X147400Y660550D01*
Y660450D01*
X147300Y660400D01*
G01X150050Y657600D02*
Y659600D01*
G01Y659100D02*
X150250Y659350D01*
X150550Y659550D01*
X150950Y659600D01*
X151300Y659550D01*
X151600Y659350D01*
X151750Y659000D01*
Y657600D01*
G01X155300Y659350D02*
X154950Y659550D01*
X154650Y659600D01*
X154250Y659500D01*
X153950Y659300D01*
X153750Y658950D01*
X153700Y658600D01*
X153750Y658250D01*
X153950Y657950D01*
X154250Y657700D01*
X154650Y657600D01*
X155000Y657700D01*
X155300Y657900D01*
G01X157250Y657600D02*
Y660600D01*
G01Y659150D02*
X157500Y659400D01*
X157750Y659550D01*
X158150Y659600D01*
X158450Y659550D01*
X158800Y659350D01*
X158950Y659050D01*
Y657600D01*
G01X207700Y-37500D02*
Y-40500D01*
X209700D01*
G01X212300D02*
Y-37500D01*
X211700Y-38100D01*
G01Y-40500D02*
X212900D01*
G01X218500Y-37500D02*
Y-40500D01*
X220500D01*
G01X222000Y-39900D02*
X222300Y-40250D01*
X222700Y-40450D01*
X223150Y-40500D01*
X223550Y-40450D01*
X223950Y-40200D01*
X224200Y-39900D01*
X224250Y-39600D01*
X224150Y-39250D01*
X223800Y-39000D01*
X223450Y-38900D01*
X223000D01*
G01X223450D02*
X223750Y-38750D01*
X224000Y-38500D01*
X224100Y-38200D01*
X224000Y-37900D01*
X223750Y-37650D01*
X223300Y-37500D01*
X222850Y-37550D01*
X222400Y-37750D01*
G01X229300Y-37500D02*
Y-40500D01*
X231300D01*
G01X232800Y-40050D02*
X233100Y-40300D01*
X233450Y-40450D01*
X233900Y-40500D01*
X234350Y-40400D01*
X234700Y-40200D01*
X234950Y-39850D01*
X235000Y-39450D01*
X234900Y-39050D01*
X234650Y-38800D01*
X234300Y-38600D01*
X233950Y-38550D01*
X233600Y-38600D01*
X233150Y-38800D01*
X233300Y-37500D01*
X234650D01*
G01X240100D02*
Y-40500D01*
X242100D01*
G01X244700D02*
Y-37500D01*
X244100Y-38100D01*
G01Y-40500D02*
X245300D01*
G01X248300Y-37500D02*
X247900Y-37600D01*
X247600Y-37850D01*
X247400Y-38150D01*
X247250Y-38550D01*
X247200Y-39000D01*
X247250Y-39450D01*
X247400Y-39850D01*
X247600Y-40150D01*
X247900Y-40400D01*
X248300Y-40500D01*
X248700Y-40400D01*
X249000Y-40150D01*
X249200Y-39850D01*
X249350Y-39450D01*
X249400Y-39000D01*
X249350Y-38550D01*
X249200Y-38150D01*
X249000Y-37850D01*
X248700Y-37600D01*
X248300Y-37500D01*
G01X254500D02*
Y-40500D01*
X256500D01*
G01X259100D02*
Y-37500D01*
X258500Y-38100D01*
G01Y-40500D02*
X259700D01*
G01X261750Y-38000D02*
X262050Y-37700D01*
X262400Y-37550D01*
X262800Y-37500D01*
X263300Y-37600D01*
X263650Y-37850D01*
X263750Y-38150D01*
X263700Y-38450D01*
X263500Y-38700D01*
X262500Y-39200D01*
X262050Y-39550D01*
X261750Y-40050D01*
X261650Y-40500D01*
X263750D01*
G01X268900Y-37500D02*
Y-40500D01*
X270900D01*
G01X273500D02*
Y-37500D01*
X272900Y-38100D01*
G01Y-40500D02*
X274100D01*
G01X277700D02*
Y-37500D01*
X275850Y-39650D01*
X278350D01*
G01X279200Y-41500D02*
X282200D01*
G01X284900Y-40500D02*
Y-37500D01*
X283050Y-39650D01*
X285550D01*
G01X287900Y-37500D02*
X287500Y-37600D01*
X287200Y-37850D01*
X287000Y-38150D01*
X286850Y-38550D01*
X286800Y-39000D01*
X286850Y-39450D01*
X287000Y-39850D01*
X287200Y-40150D01*
X287500Y-40400D01*
X287900Y-40500D01*
X288300Y-40400D01*
X288600Y-40150D01*
X288800Y-39850D01*
X288950Y-39450D01*
X289000Y-39000D01*
X288950Y-38550D01*
X288800Y-38150D01*
X288600Y-37850D01*
X288300Y-37600D01*
X287900Y-37500D01*
G01X291500Y-40500D02*
X291100Y-40450D01*
X290750Y-40250D01*
X290450Y-39950D01*
X290250Y-39600D01*
X290150Y-39200D01*
Y-38800D01*
X290250Y-38400D01*
X290450Y-38050D01*
X290750Y-37750D01*
X291100Y-37550D01*
X291500Y-37500D01*
X291900Y-37550D01*
X292250Y-37750D01*
X292550Y-38050D01*
X292750Y-38400D01*
X292850Y-38800D01*
Y-39200D01*
X292750Y-39600D01*
X292550Y-39950D01*
X292250Y-40250D01*
X291900Y-40450D01*
X291500Y-40500D01*
G01X294250D02*
Y-37500D01*
G01Y-38950D02*
X294500Y-38700D01*
X294750Y-38550D01*
X295150Y-38500D01*
X295450Y-38550D01*
X295800Y-38750D01*
X295950Y-39050D01*
Y-40500D01*
G01X297200D02*
Y-38500D01*
G01Y-39050D02*
X297350Y-38800D01*
X297600Y-38600D01*
X297950Y-38500D01*
X298300Y-38600D01*
X298550Y-38800D01*
X298700Y-39050D01*
Y-40500D01*
G01Y-39050D02*
X298850Y-38800D01*
X299100Y-38600D01*
X299450Y-38500D01*
X299800Y-38600D01*
X300050Y-38800D01*
X300200Y-39100D01*
Y-40500D01*
G01X300800Y-41500D02*
X303800D01*
G01X304850Y-40100D02*
X305250Y-40350D01*
X305700Y-40500D01*
X306100D01*
X306500Y-40350D01*
X306800Y-40100D01*
X306950Y-39750D01*
X306850Y-39400D01*
X306600Y-39100D01*
X306150Y-38900D01*
X305550Y-38800D01*
X305200Y-38600D01*
X305050Y-38250D01*
X305150Y-37900D01*
X305400Y-37650D01*
X305750Y-37500D01*
X306100D01*
X306450Y-37600D01*
X306750Y-37850D01*
G01X208030Y-55100D02*
Y-58100D01*
X210030D01*
G01X212630D02*
Y-55100D01*
X212030Y-55700D01*
G01Y-58100D02*
X213230D01*
G01X218830Y-55100D02*
Y-58100D01*
X220830D01*
G01X222330Y-57500D02*
X222630Y-57850D01*
X223030Y-58050D01*
X223480Y-58100D01*
X223880Y-58050D01*
X224280Y-57800D01*
X224530Y-57500D01*
X224580Y-57200D01*
X224480Y-56850D01*
X224130Y-56600D01*
X223780Y-56500D01*
X223330D01*
G01X223780D02*
X224080Y-56350D01*
X224330Y-56100D01*
X224430Y-55800D01*
X224330Y-55500D01*
X224080Y-55250D01*
X223630Y-55100D01*
X223180Y-55150D01*
X222730Y-55350D01*
G01X229630Y-55100D02*
Y-58100D01*
X231630D01*
G01X233130Y-57650D02*
X233430Y-57900D01*
X233780Y-58050D01*
X234230Y-58100D01*
X234680Y-58000D01*
X235030Y-57800D01*
X235280Y-57450D01*
X235330Y-57050D01*
X235230Y-56650D01*
X234980Y-56400D01*
X234630Y-56200D01*
X234280Y-56150D01*
X233930Y-56200D01*
X233480Y-56400D01*
X233630Y-55100D01*
X234980D01*
G01X240430D02*
Y-58100D01*
X242430D01*
G01X245030D02*
Y-55100D01*
X244430Y-55700D01*
G01Y-58100D02*
X245630D01*
G01X248630Y-55100D02*
X248230Y-55200D01*
X247930Y-55450D01*
X247730Y-55750D01*
X247580Y-56150D01*
X247530Y-56600D01*
X247580Y-57050D01*
X247730Y-57450D01*
X247930Y-57750D01*
X248230Y-58000D01*
X248630Y-58100D01*
X249030Y-58000D01*
X249330Y-57750D01*
X249530Y-57450D01*
X249680Y-57050D01*
X249730Y-56600D01*
X249680Y-56150D01*
X249530Y-55750D01*
X249330Y-55450D01*
X249030Y-55200D01*
X248630Y-55100D01*
G01X254830D02*
Y-58100D01*
X256830D01*
G01X259430D02*
Y-55100D01*
X258830Y-55700D01*
G01Y-58100D02*
X260030D01*
G01X262080Y-55600D02*
X262380Y-55300D01*
X262730Y-55150D01*
X263130Y-55100D01*
X263630Y-55200D01*
X263980Y-55450D01*
X264080Y-55750D01*
X264030Y-56050D01*
X263830Y-56300D01*
X262830Y-56800D01*
X262380Y-57150D01*
X262080Y-57650D01*
X261980Y-58100D01*
X264080D01*
G01X269230Y-55100D02*
Y-58100D01*
X271230D01*
G01X273830D02*
Y-55100D01*
X273230Y-55700D01*
G01Y-58100D02*
X274430D01*
G01X278030D02*
Y-55100D01*
X276180Y-57250D01*
X278680D01*
G01X279530Y-59100D02*
X282530D01*
G01X283530Y-57650D02*
X283830Y-57900D01*
X284180Y-58050D01*
X284630Y-58100D01*
X285080Y-58000D01*
X285430Y-57800D01*
X285680Y-57450D01*
X285730Y-57050D01*
X285630Y-56650D01*
X285380Y-56400D01*
X285030Y-56200D01*
X284680Y-56150D01*
X284330Y-56200D01*
X283880Y-56400D01*
X284030Y-55100D01*
X285380D01*
G01X288230D02*
X287830Y-55200D01*
X287530Y-55450D01*
X287330Y-55750D01*
X287180Y-56150D01*
X287130Y-56600D01*
X287180Y-57050D01*
X287330Y-57450D01*
X287530Y-57750D01*
X287830Y-58000D01*
X288230Y-58100D01*
X288630Y-58000D01*
X288930Y-57750D01*
X289130Y-57450D01*
X289280Y-57050D01*
X289330Y-56600D01*
X289280Y-56150D01*
X289130Y-55750D01*
X288930Y-55450D01*
X288630Y-55200D01*
X288230Y-55100D01*
G01X291830Y-58100D02*
X291430Y-58050D01*
X291080Y-57850D01*
X290780Y-57550D01*
X290580Y-57200D01*
X290480Y-56800D01*
Y-56400D01*
X290580Y-56000D01*
X290780Y-55650D01*
X291080Y-55350D01*
X291430Y-55150D01*
X291830Y-55100D01*
X292230Y-55150D01*
X292580Y-55350D01*
X292880Y-55650D01*
X293080Y-56000D01*
X293180Y-56400D01*
Y-56800D01*
X293080Y-57200D01*
X292880Y-57550D01*
X292580Y-57850D01*
X292230Y-58050D01*
X291830Y-58100D01*
G01X294580D02*
Y-55100D01*
G01Y-56550D02*
X294830Y-56300D01*
X295080Y-56150D01*
X295480Y-56100D01*
X295780Y-56150D01*
X296130Y-56350D01*
X296280Y-56650D01*
Y-58100D01*
G01X297530D02*
Y-56100D01*
G01Y-56650D02*
X297680Y-56400D01*
X297930Y-56200D01*
X298280Y-56100D01*
X298630Y-56200D01*
X298880Y-56400D01*
X299030Y-56650D01*
Y-58100D01*
G01Y-56650D02*
X299180Y-56400D01*
X299430Y-56200D01*
X299780Y-56100D01*
X300130Y-56200D01*
X300380Y-56400D01*
X300530Y-56700D01*
Y-58100D01*
G01X301130Y-59100D02*
X304130D01*
G01X305180Y-57700D02*
X305580Y-57950D01*
X306030Y-58100D01*
X306430D01*
X306830Y-57950D01*
X307130Y-57700D01*
X307280Y-57350D01*
X307180Y-57000D01*
X306930Y-56700D01*
X306480Y-56500D01*
X305880Y-56400D01*
X305530Y-56200D01*
X305380Y-55850D01*
X305480Y-55500D01*
X305730Y-55250D01*
X306080Y-55100D01*
X306430D01*
X306780Y-55200D01*
X307080Y-55450D01*
G01X266500Y107000D02*
X265300D01*
X265299Y107001D01*
Y116299D01*
X265298Y116300D01*
X178701D01*
X178700Y116301D01*
Y142100D01*
X191900D01*
Y191100D01*
X189501D01*
X189500Y191101D01*
Y205299D01*
X189501Y205300D01*
X210200D01*
G01X227867Y117600D02*
Y120100D01*
X228908D01*
X229242Y119975D01*
X229450Y119808D01*
X229533Y119475D01*
X229450Y119142D01*
X229200Y118933D01*
X228908Y118808D01*
X227867D01*
G01X228908D02*
X229533Y117600D01*
G01X230883Y118100D02*
X231133Y117808D01*
X231467Y117642D01*
X231842Y117600D01*
X232175Y117642D01*
X232508Y117850D01*
X232717Y118100D01*
X232758Y118350D01*
X232675Y118642D01*
X232383Y118850D01*
X232092Y118933D01*
X231717D01*
G01X232092D02*
X232342Y119058D01*
X232550Y119267D01*
X232633Y119517D01*
X232550Y119767D01*
X232342Y119975D01*
X231967Y120100D01*
X231592Y120058D01*
X231217Y119892D01*
G01X233983Y117600D02*
Y120100D01*
X234817D01*
X235150Y119975D01*
X235400Y119808D01*
X235608Y119558D01*
X235775Y119267D01*
X235817Y118850D01*
X235775Y118433D01*
X235608Y118142D01*
X235400Y117892D01*
X235150Y117725D01*
X234817Y117600D01*
X233983D01*
G01X237208Y119683D02*
X237458Y119933D01*
X237750Y120058D01*
X238083Y120100D01*
X238500Y120017D01*
X238792Y119808D01*
X238875Y119558D01*
X238833Y119308D01*
X238667Y119100D01*
X237833Y118683D01*
X237458Y118392D01*
X237208Y117975D01*
X237125Y117600D01*
X238875D01*
G01X241017D02*
X241100Y118142D01*
X241225Y118600D01*
X241392Y119017D01*
X241600Y119475D01*
X241933Y120100D01*
X240267D01*
G01X223500Y122867D02*
X221000D01*
Y123908D01*
X221125Y124242D01*
X221292Y124450D01*
X221625Y124533D01*
X221958Y124450D01*
X222167Y124200D01*
X222292Y123908D01*
Y122867D01*
G01Y123908D02*
X223500Y124533D01*
G01X223000Y125883D02*
X223292Y126133D01*
X223458Y126467D01*
X223500Y126842D01*
X223458Y127175D01*
X223250Y127508D01*
X223000Y127717D01*
X222750Y127758D01*
X222458Y127675D01*
X222250Y127383D01*
X222167Y127092D01*
Y126717D01*
G01Y127092D02*
X222042Y127342D01*
X221833Y127550D01*
X221583Y127633D01*
X221333Y127550D01*
X221125Y127342D01*
X221000Y126967D01*
X221042Y126592D01*
X221208Y126217D01*
G01X223500Y128983D02*
X221000D01*
Y129817D01*
X221125Y130150D01*
X221292Y130400D01*
X221542Y130608D01*
X221833Y130775D01*
X222250Y130817D01*
X222667Y130775D01*
X222958Y130608D01*
X223208Y130400D01*
X223375Y130150D01*
X223500Y129817D01*
Y128983D01*
G01X223000Y132083D02*
X223292Y132333D01*
X223458Y132667D01*
X223500Y133042D01*
X223458Y133375D01*
X223250Y133708D01*
X223000Y133917D01*
X222750Y133958D01*
X222458Y133875D01*
X222250Y133583D01*
X222167Y133292D01*
Y132917D01*
G01Y133292D02*
X222042Y133542D01*
X221833Y133750D01*
X221583Y133833D01*
X221333Y133750D01*
X221125Y133542D01*
X221000Y133167D01*
X221042Y132792D01*
X221208Y132417D01*
G01X221417Y135308D02*
X221167Y135558D01*
X221042Y135850D01*
X221000Y136183D01*
X221083Y136600D01*
X221292Y136892D01*
X221542Y136975D01*
X221792Y136933D01*
X222000Y136767D01*
X222417Y135933D01*
X222708Y135558D01*
X223125Y135308D01*
X223500Y135225D01*
Y136975D01*
G01X233200Y123067D02*
X230700D01*
Y124108D01*
X230825Y124442D01*
X230992Y124650D01*
X231325Y124733D01*
X231658Y124650D01*
X231867Y124400D01*
X231992Y124108D01*
Y123067D01*
G01Y124108D02*
X233200Y124733D01*
G01X232700Y126083D02*
X232992Y126333D01*
X233158Y126667D01*
X233200Y127042D01*
X233158Y127375D01*
X232950Y127708D01*
X232700Y127917D01*
X232450Y127958D01*
X232158Y127875D01*
X231950Y127583D01*
X231867Y127292D01*
Y126917D01*
G01Y127292D02*
X231742Y127542D01*
X231533Y127750D01*
X231283Y127833D01*
X231033Y127750D01*
X230825Y127542D01*
X230700Y127167D01*
X230742Y126792D01*
X230908Y126417D01*
G01X233200Y129183D02*
X230700D01*
Y130017D01*
X230825Y130350D01*
X230992Y130600D01*
X231242Y130808D01*
X231533Y130975D01*
X231950Y131017D01*
X232367Y130975D01*
X232658Y130808D01*
X232908Y130600D01*
X233075Y130350D01*
X233200Y130017D01*
Y129183D01*
G01X231117Y132408D02*
X230867Y132658D01*
X230742Y132950D01*
X230700Y133283D01*
X230783Y133700D01*
X230992Y133992D01*
X231242Y134075D01*
X231492Y134033D01*
X231700Y133867D01*
X232117Y133033D01*
X232408Y132658D01*
X232825Y132408D01*
X233200Y132325D01*
Y134075D01*
G01X232700Y135383D02*
X232992Y135633D01*
X233158Y135967D01*
X233200Y136342D01*
X233158Y136675D01*
X232950Y137008D01*
X232700Y137217D01*
X232450Y137258D01*
X232158Y137175D01*
X231950Y136883D01*
X231867Y136592D01*
Y136217D01*
G01Y136592D02*
X231742Y136842D01*
X231533Y137050D01*
X231283Y137133D01*
X231033Y137050D01*
X230825Y136842D01*
X230700Y136467D01*
X230742Y136092D01*
X230908Y135717D01*
G01X229300Y123167D02*
X226800D01*
Y124208D01*
X226925Y124542D01*
X227092Y124750D01*
X227425Y124833D01*
X227758Y124750D01*
X227967Y124500D01*
X228092Y124208D01*
Y123167D01*
G01Y124208D02*
X229300Y124833D01*
G01X228800Y126183D02*
X229092Y126433D01*
X229258Y126767D01*
X229300Y127142D01*
X229258Y127475D01*
X229050Y127808D01*
X228800Y128017D01*
X228550Y128058D01*
X228258Y127975D01*
X228050Y127683D01*
X227967Y127392D01*
Y127017D01*
G01Y127392D02*
X227842Y127642D01*
X227633Y127850D01*
X227383Y127933D01*
X227133Y127850D01*
X226925Y127642D01*
X226800Y127267D01*
X226842Y126892D01*
X227008Y126517D01*
G01X229300Y129283D02*
X226800D01*
Y130117D01*
X226925Y130450D01*
X227092Y130700D01*
X227342Y130908D01*
X227633Y131075D01*
X228050Y131117D01*
X228467Y131075D01*
X228758Y130908D01*
X229008Y130700D01*
X229175Y130450D01*
X229300Y130117D01*
Y129283D01*
G01X227217Y132508D02*
X226967Y132758D01*
X226842Y133050D01*
X226800Y133383D01*
X226883Y133800D01*
X227092Y134092D01*
X227342Y134175D01*
X227592Y134133D01*
X227800Y133967D01*
X228217Y133133D01*
X228508Y132758D01*
X228925Y132508D01*
X229300Y132425D01*
Y134175D01*
G01X227217Y135608D02*
X226967Y135858D01*
X226842Y136150D01*
X226800Y136483D01*
X226883Y136900D01*
X227092Y137192D01*
X227342Y137275D01*
X227592Y137233D01*
X227800Y137067D01*
X228217Y136233D01*
X228508Y135858D01*
X228925Y135608D01*
X229300Y135525D01*
Y137275D01*
G01X230782Y145317D02*
X230657Y145067D01*
X230574Y144775D01*
Y144442D01*
X230699Y144067D01*
X230907Y143775D01*
X231157Y143567D01*
X231574Y143400D01*
X231949Y143358D01*
X232324Y143442D01*
X232574Y143567D01*
X232824Y143817D01*
X232991Y144108D01*
X233074Y144400D01*
Y144692D01*
X232991Y144983D01*
X232866Y145233D01*
X232699Y145442D01*
G01X232574Y146583D02*
X232866Y146833D01*
X233032Y147167D01*
X233074Y147542D01*
X233032Y147875D01*
X232824Y148208D01*
X232574Y148417D01*
X232324Y148458D01*
X232032Y148375D01*
X231824Y148083D01*
X231741Y147792D01*
Y147417D01*
G01Y147792D02*
X231616Y148042D01*
X231407Y148250D01*
X231157Y148333D01*
X230907Y148250D01*
X230699Y148042D01*
X230574Y147667D01*
X230616Y147292D01*
X230782Y146917D01*
G01X233074Y149683D02*
X230574D01*
Y150517D01*
X230699Y150850D01*
X230866Y151100D01*
X231116Y151308D01*
X231407Y151475D01*
X231824Y151517D01*
X232241Y151475D01*
X232532Y151308D01*
X232782Y151100D01*
X232949Y150850D01*
X233074Y150517D01*
Y149683D01*
G01X230991Y152908D02*
X230741Y153158D01*
X230616Y153450D01*
X230574Y153783D01*
X230657Y154200D01*
X230866Y154492D01*
X231116Y154575D01*
X231366Y154533D01*
X231574Y154367D01*
X231991Y153533D01*
X232282Y153158D01*
X232699Y152908D01*
X233074Y152825D01*
Y154575D01*
G01Y156800D02*
X230574D01*
X231074Y156300D01*
G01X233074D02*
Y157300D01*
G01X216408Y124717D02*
X216283Y124467D01*
X216200Y124175D01*
Y123842D01*
X216325Y123467D01*
X216533Y123175D01*
X216783Y122967D01*
X217200Y122800D01*
X217575Y122758D01*
X217950Y122842D01*
X218200Y122967D01*
X218450Y123217D01*
X218617Y123508D01*
X218700Y123800D01*
Y124092D01*
X218617Y124383D01*
X218492Y124633D01*
X218325Y124842D01*
G01X218200Y125983D02*
X218492Y126233D01*
X218658Y126567D01*
X218700Y126942D01*
X218658Y127275D01*
X218450Y127608D01*
X218200Y127817D01*
X217950Y127858D01*
X217658Y127775D01*
X217450Y127483D01*
X217367Y127192D01*
Y126817D01*
G01Y127192D02*
X217242Y127442D01*
X217033Y127650D01*
X216783Y127733D01*
X216533Y127650D01*
X216325Y127442D01*
X216200Y127067D01*
X216242Y126692D01*
X216408Y126317D01*
G01X218700Y129083D02*
X216200D01*
Y129917D01*
X216325Y130250D01*
X216492Y130500D01*
X216742Y130708D01*
X217033Y130875D01*
X217450Y130917D01*
X217867Y130875D01*
X218158Y130708D01*
X218408Y130500D01*
X218575Y130250D01*
X218700Y129917D01*
Y129083D01*
G01X216617Y132308D02*
X216367Y132558D01*
X216242Y132850D01*
X216200Y133183D01*
X216283Y133600D01*
X216492Y133892D01*
X216742Y133975D01*
X216992Y133933D01*
X217200Y133767D01*
X217617Y132933D01*
X217908Y132558D01*
X218325Y132308D01*
X218700Y132225D01*
Y133975D01*
G01X218325Y135283D02*
X218533Y135533D01*
X218658Y135825D01*
X218700Y136200D01*
X218617Y136575D01*
X218450Y136867D01*
X218158Y137075D01*
X217825Y137117D01*
X217492Y137033D01*
X217283Y136825D01*
X217117Y136533D01*
X217075Y136242D01*
X217117Y135950D01*
X217283Y135575D01*
X216200Y135700D01*
Y136825D01*
G01X223982Y145317D02*
X223857Y145067D01*
X223774Y144775D01*
Y144442D01*
X223899Y144067D01*
X224107Y143775D01*
X224357Y143567D01*
X224774Y143400D01*
X225149Y143358D01*
X225524Y143442D01*
X225774Y143567D01*
X226024Y143817D01*
X226191Y144108D01*
X226274Y144400D01*
Y144692D01*
X226191Y144983D01*
X226066Y145233D01*
X225899Y145442D01*
G01X224191Y146708D02*
X223941Y146958D01*
X223816Y147250D01*
X223774Y147583D01*
X223857Y148000D01*
X224066Y148292D01*
X224316Y148375D01*
X224566Y148333D01*
X224774Y148167D01*
X225191Y147333D01*
X225482Y146958D01*
X225899Y146708D01*
X226274Y146625D01*
Y148375D01*
G01Y149683D02*
X223774D01*
Y150517D01*
X223899Y150850D01*
X224066Y151100D01*
X224316Y151308D01*
X224607Y151475D01*
X225024Y151517D01*
X225441Y151475D01*
X225732Y151308D01*
X225982Y151100D01*
X226149Y150850D01*
X226274Y150517D01*
Y149683D01*
G01X225774Y152783D02*
X226066Y153033D01*
X226232Y153367D01*
X226274Y153742D01*
X226232Y154075D01*
X226024Y154408D01*
X225774Y154617D01*
X225524Y154658D01*
X225232Y154575D01*
X225024Y154283D01*
X224941Y153992D01*
Y153617D01*
G01Y153992D02*
X224816Y154242D01*
X224607Y154450D01*
X224357Y154533D01*
X224107Y154450D01*
X223899Y154242D01*
X223774Y153867D01*
X223816Y153492D01*
X223982Y153117D01*
G01X225982Y156092D02*
X226191Y156383D01*
X226274Y156717D01*
X226191Y157050D01*
X225941Y157342D01*
X225566Y157550D01*
X225191Y157633D01*
X224732D01*
X224357Y157550D01*
X224024Y157342D01*
X223857Y157092D01*
X223774Y156800D01*
X223857Y156467D01*
X224024Y156217D01*
X224274Y156050D01*
X224607Y155967D01*
X224899Y156050D01*
X225191Y156258D01*
X225357Y156508D01*
X225399Y156800D01*
X225316Y157133D01*
X225107Y157383D01*
X224732Y157633D01*
G01X227382Y145317D02*
X227257Y145067D01*
X227174Y144775D01*
Y144442D01*
X227299Y144067D01*
X227507Y143775D01*
X227757Y143567D01*
X228174Y143400D01*
X228549Y143358D01*
X228924Y143442D01*
X229174Y143567D01*
X229424Y143817D01*
X229591Y144108D01*
X229674Y144400D01*
Y144692D01*
X229591Y144983D01*
X229466Y145233D01*
X229299Y145442D01*
G01X227591Y146708D02*
X227341Y146958D01*
X227216Y147250D01*
X227174Y147583D01*
X227257Y148000D01*
X227466Y148292D01*
X227716Y148375D01*
X227966Y148333D01*
X228174Y148167D01*
X228591Y147333D01*
X228882Y146958D01*
X229299Y146708D01*
X229674Y146625D01*
Y148375D01*
G01Y149683D02*
X227174D01*
Y150517D01*
X227299Y150850D01*
X227466Y151100D01*
X227716Y151308D01*
X228007Y151475D01*
X228424Y151517D01*
X228841Y151475D01*
X229132Y151308D01*
X229382Y151100D01*
X229549Y150850D01*
X229674Y150517D01*
Y149683D01*
G01Y154200D02*
X227174D01*
X228966Y152658D01*
Y154742D01*
G01X227174Y156800D02*
X227257Y156467D01*
X227466Y156217D01*
X227716Y156050D01*
X228049Y155925D01*
X228424Y155883D01*
X228799Y155925D01*
X229132Y156050D01*
X229382Y156217D01*
X229591Y156467D01*
X229674Y156800D01*
X229591Y157133D01*
X229382Y157383D01*
X229132Y157550D01*
X228799Y157675D01*
X228424Y157717D01*
X228049Y157675D01*
X227716Y157550D01*
X227466Y157383D01*
X227257Y157133D01*
X227174Y156800D01*
G01X207008Y125217D02*
X206883Y124967D01*
X206800Y124675D01*
Y124342D01*
X206925Y123967D01*
X207133Y123675D01*
X207383Y123467D01*
X207800Y123300D01*
X208175Y123258D01*
X208550Y123342D01*
X208800Y123467D01*
X209050Y123717D01*
X209217Y124008D01*
X209300Y124300D01*
Y124592D01*
X209217Y124883D01*
X209092Y125133D01*
X208925Y125342D01*
G01X207217Y126608D02*
X206967Y126858D01*
X206842Y127150D01*
X206800Y127483D01*
X206883Y127900D01*
X207092Y128192D01*
X207342Y128275D01*
X207592Y128233D01*
X207800Y128067D01*
X208217Y127233D01*
X208508Y126858D01*
X208925Y126608D01*
X209300Y126525D01*
Y128275D01*
G01Y129583D02*
X206800D01*
Y130417D01*
X206925Y130750D01*
X207092Y131000D01*
X207342Y131208D01*
X207633Y131375D01*
X208050Y131417D01*
X208467Y131375D01*
X208758Y131208D01*
X209008Y131000D01*
X209175Y130750D01*
X209300Y130417D01*
Y129583D01*
G01Y134100D02*
X206800D01*
X208592Y132558D01*
Y134642D01*
G01X208258Y135908D02*
X207967Y136200D01*
X207800Y136450D01*
X207717Y136783D01*
X207800Y137075D01*
X207967Y137283D01*
X208217Y137450D01*
X208508Y137492D01*
X208758Y137450D01*
X209008Y137283D01*
X209217Y137033D01*
X209300Y136742D01*
X209217Y136408D01*
X208967Y136117D01*
X208592Y135950D01*
X208175Y135908D01*
X207633Y135992D01*
X207342Y136117D01*
X207050Y136325D01*
X206842Y136617D01*
X206800Y136908D01*
X206883Y137200D01*
X207092Y137408D01*
G01X210608Y125217D02*
X210483Y124967D01*
X210400Y124675D01*
Y124342D01*
X210525Y123967D01*
X210733Y123675D01*
X210983Y123467D01*
X211400Y123300D01*
X211775Y123258D01*
X212150Y123342D01*
X212400Y123467D01*
X212650Y123717D01*
X212817Y124008D01*
X212900Y124300D01*
Y124592D01*
X212817Y124883D01*
X212692Y125133D01*
X212525Y125342D01*
G01X210817Y126608D02*
X210567Y126858D01*
X210442Y127150D01*
X210400Y127483D01*
X210483Y127900D01*
X210692Y128192D01*
X210942Y128275D01*
X211192Y128233D01*
X211400Y128067D01*
X211817Y127233D01*
X212108Y126858D01*
X212525Y126608D01*
X212900Y126525D01*
Y128275D01*
G01Y129583D02*
X210400D01*
Y130417D01*
X210525Y130750D01*
X210692Y131000D01*
X210942Y131208D01*
X211233Y131375D01*
X211650Y131417D01*
X212067Y131375D01*
X212358Y131208D01*
X212608Y131000D01*
X212775Y130750D01*
X212900Y130417D01*
Y129583D01*
G01Y134100D02*
X210400D01*
X212192Y132558D01*
Y134642D01*
G01X212900Y136617D02*
X212358Y136700D01*
X211900Y136825D01*
X211483Y136992D01*
X211025Y137200D01*
X210400Y137533D01*
Y135867D01*
G01X203608Y125117D02*
X203483Y124867D01*
X203400Y124575D01*
Y124242D01*
X203525Y123867D01*
X203733Y123575D01*
X203983Y123367D01*
X204400Y123200D01*
X204775Y123158D01*
X205150Y123242D01*
X205400Y123367D01*
X205650Y123617D01*
X205817Y123908D01*
X205900Y124200D01*
Y124492D01*
X205817Y124783D01*
X205692Y125033D01*
X205525Y125242D01*
G01X203817Y126508D02*
X203567Y126758D01*
X203442Y127050D01*
X203400Y127383D01*
X203483Y127800D01*
X203692Y128092D01*
X203942Y128175D01*
X204192Y128133D01*
X204400Y127967D01*
X204817Y127133D01*
X205108Y126758D01*
X205525Y126508D01*
X205900Y126425D01*
Y128175D01*
G01Y129483D02*
X203400D01*
Y130317D01*
X203525Y130650D01*
X203692Y130900D01*
X203942Y131108D01*
X204233Y131275D01*
X204650Y131317D01*
X205067Y131275D01*
X205358Y131108D01*
X205608Y130900D01*
X205775Y130650D01*
X205900Y130317D01*
Y129483D01*
G01Y134000D02*
X203400D01*
X205192Y132458D01*
Y134542D01*
G01X205525Y135683D02*
X205733Y135933D01*
X205858Y136225D01*
X205900Y136600D01*
X205817Y136975D01*
X205650Y137267D01*
X205358Y137475D01*
X205025Y137517D01*
X204692Y137433D01*
X204483Y137225D01*
X204317Y136933D01*
X204275Y136642D01*
X204317Y136350D01*
X204483Y135975D01*
X203400Y136100D01*
Y137225D01*
G01X220582Y145317D02*
X220457Y145067D01*
X220374Y144775D01*
Y144442D01*
X220499Y144067D01*
X220707Y143775D01*
X220957Y143567D01*
X221374Y143400D01*
X221749Y143358D01*
X222124Y143442D01*
X222374Y143567D01*
X222624Y143817D01*
X222791Y144108D01*
X222874Y144400D01*
Y144692D01*
X222791Y144983D01*
X222666Y145233D01*
X222499Y145442D01*
G01X220791Y146708D02*
X220541Y146958D01*
X220416Y147250D01*
X220374Y147583D01*
X220457Y148000D01*
X220666Y148292D01*
X220916Y148375D01*
X221166Y148333D01*
X221374Y148167D01*
X221791Y147333D01*
X222082Y146958D01*
X222499Y146708D01*
X222874Y146625D01*
Y148375D01*
G01Y149683D02*
X220374D01*
Y150517D01*
X220499Y150850D01*
X220666Y151100D01*
X220916Y151308D01*
X221207Y151475D01*
X221624Y151517D01*
X222041Y151475D01*
X222332Y151308D01*
X222582Y151100D01*
X222749Y150850D01*
X222874Y150517D01*
Y149683D01*
G01X222374Y152783D02*
X222666Y153033D01*
X222832Y153367D01*
X222874Y153742D01*
X222832Y154075D01*
X222624Y154408D01*
X222374Y154617D01*
X222124Y154658D01*
X221832Y154575D01*
X221624Y154283D01*
X221541Y153992D01*
Y153617D01*
G01Y153992D02*
X221416Y154242D01*
X221207Y154450D01*
X220957Y154533D01*
X220707Y154450D01*
X220499Y154242D01*
X220374Y153867D01*
X220416Y153492D01*
X220582Y153117D01*
G01X222874Y156800D02*
X222832Y157092D01*
X222707Y157425D01*
X222499Y157633D01*
X222207Y157717D01*
X221916Y157633D01*
X221666Y157383D01*
X221541Y157008D01*
Y156592D01*
X221457Y156342D01*
X221249Y156133D01*
X220957Y156050D01*
X220666Y156175D01*
X220457Y156467D01*
X220374Y156800D01*
X220457Y157133D01*
X220666Y157425D01*
X220957Y157550D01*
X221249Y157467D01*
X221457Y157258D01*
X221541Y157008D01*
Y156592D01*
X221666Y156217D01*
X221916Y155967D01*
X222207Y155883D01*
X222499Y155967D01*
X222707Y156175D01*
X222832Y156508D01*
X222874Y156800D01*
G01X181817Y133492D02*
X181567Y133617D01*
X181275Y133700D01*
X180942D01*
X180567Y133575D01*
X180275Y133367D01*
X180067Y133117D01*
X179900Y132700D01*
X179858Y132325D01*
X179942Y131950D01*
X180067Y131700D01*
X180317Y131450D01*
X180608Y131283D01*
X180900Y131200D01*
X181192D01*
X181483Y131283D01*
X181733Y131408D01*
X181942Y131575D01*
G01X183208Y133283D02*
X183458Y133533D01*
X183750Y133658D01*
X184083Y133700D01*
X184500Y133617D01*
X184792Y133408D01*
X184875Y133158D01*
X184833Y132908D01*
X184667Y132700D01*
X183833Y132283D01*
X183458Y131992D01*
X183208Y131575D01*
X183125Y131200D01*
X184875D01*
G01X186183D02*
Y133700D01*
X187017D01*
X187350Y133575D01*
X187600Y133408D01*
X187808Y133158D01*
X187975Y132867D01*
X188017Y132450D01*
X187975Y132033D01*
X187808Y131742D01*
X187600Y131492D01*
X187350Y131325D01*
X187017Y131200D01*
X186183D01*
G01X190700D02*
Y133700D01*
X189158Y131908D01*
X191242D01*
G01X193300Y131200D02*
Y133700D01*
X192800Y133200D01*
G01Y131200D02*
X193800D01*
G01X206982Y145317D02*
X206857Y145067D01*
X206774Y144775D01*
Y144442D01*
X206899Y144067D01*
X207107Y143775D01*
X207357Y143567D01*
X207774Y143400D01*
X208149Y143358D01*
X208524Y143442D01*
X208774Y143567D01*
X209024Y143817D01*
X209191Y144108D01*
X209274Y144400D01*
Y144692D01*
X209191Y144983D01*
X209066Y145233D01*
X208899Y145442D01*
G01X207191Y146708D02*
X206941Y146958D01*
X206816Y147250D01*
X206774Y147583D01*
X206857Y148000D01*
X207066Y148292D01*
X207316Y148375D01*
X207566Y148333D01*
X207774Y148167D01*
X208191Y147333D01*
X208482Y146958D01*
X208899Y146708D01*
X209274Y146625D01*
Y148375D01*
G01Y149683D02*
X206774D01*
Y150517D01*
X206899Y150850D01*
X207066Y151100D01*
X207316Y151308D01*
X207607Y151475D01*
X208024Y151517D01*
X208441Y151475D01*
X208732Y151308D01*
X208982Y151100D01*
X209149Y150850D01*
X209274Y150517D01*
Y149683D01*
G01X208774Y152783D02*
X209066Y153033D01*
X209232Y153367D01*
X209274Y153742D01*
X209232Y154075D01*
X209024Y154408D01*
X208774Y154617D01*
X208524Y154658D01*
X208232Y154575D01*
X208024Y154283D01*
X207941Y153992D01*
Y153617D01*
G01Y153992D02*
X207816Y154242D01*
X207607Y154450D01*
X207357Y154533D01*
X207107Y154450D01*
X206899Y154242D01*
X206774Y153867D01*
X206816Y153492D01*
X206982Y153117D01*
G01X209274Y157300D02*
X206774D01*
X208566Y155758D01*
Y157842D01*
G01X203582Y145317D02*
X203457Y145067D01*
X203374Y144775D01*
Y144442D01*
X203499Y144067D01*
X203707Y143775D01*
X203957Y143567D01*
X204374Y143400D01*
X204749Y143358D01*
X205124Y143442D01*
X205374Y143567D01*
X205624Y143817D01*
X205791Y144108D01*
X205874Y144400D01*
Y144692D01*
X205791Y144983D01*
X205666Y145233D01*
X205499Y145442D01*
G01X203791Y146708D02*
X203541Y146958D01*
X203416Y147250D01*
X203374Y147583D01*
X203457Y148000D01*
X203666Y148292D01*
X203916Y148375D01*
X204166Y148333D01*
X204374Y148167D01*
X204791Y147333D01*
X205082Y146958D01*
X205499Y146708D01*
X205874Y146625D01*
Y148375D01*
G01Y149683D02*
X203374D01*
Y150517D01*
X203499Y150850D01*
X203666Y151100D01*
X203916Y151308D01*
X204207Y151475D01*
X204624Y151517D01*
X205041Y151475D01*
X205332Y151308D01*
X205582Y151100D01*
X205749Y150850D01*
X205874Y150517D01*
Y149683D01*
G01X205374Y152783D02*
X205666Y153033D01*
X205832Y153367D01*
X205874Y153742D01*
X205832Y154075D01*
X205624Y154408D01*
X205374Y154617D01*
X205124Y154658D01*
X204832Y154575D01*
X204624Y154283D01*
X204541Y153992D01*
Y153617D01*
G01Y153992D02*
X204416Y154242D01*
X204207Y154450D01*
X203957Y154533D01*
X203707Y154450D01*
X203499Y154242D01*
X203374Y153867D01*
X203416Y153492D01*
X203582Y153117D01*
G01X205374Y155883D02*
X205666Y156133D01*
X205832Y156467D01*
X205874Y156842D01*
X205832Y157175D01*
X205624Y157508D01*
X205374Y157717D01*
X205124Y157758D01*
X204832Y157675D01*
X204624Y157383D01*
X204541Y157092D01*
Y156717D01*
G01Y157092D02*
X204416Y157342D01*
X204207Y157550D01*
X203957Y157633D01*
X203707Y157550D01*
X203499Y157342D01*
X203374Y156967D01*
X203416Y156592D01*
X203582Y156217D01*
G01X196782Y145317D02*
X196657Y145067D01*
X196574Y144775D01*
Y144442D01*
X196699Y144067D01*
X196907Y143775D01*
X197157Y143567D01*
X197574Y143400D01*
X197949Y143358D01*
X198324Y143442D01*
X198574Y143567D01*
X198824Y143817D01*
X198991Y144108D01*
X199074Y144400D01*
Y144692D01*
X198991Y144983D01*
X198866Y145233D01*
X198699Y145442D01*
G01X196991Y146708D02*
X196741Y146958D01*
X196616Y147250D01*
X196574Y147583D01*
X196657Y148000D01*
X196866Y148292D01*
X197116Y148375D01*
X197366Y148333D01*
X197574Y148167D01*
X197991Y147333D01*
X198282Y146958D01*
X198699Y146708D01*
X199074Y146625D01*
Y148375D01*
G01Y149683D02*
X196574D01*
Y150517D01*
X196699Y150850D01*
X196866Y151100D01*
X197116Y151308D01*
X197407Y151475D01*
X197824Y151517D01*
X198241Y151475D01*
X198532Y151308D01*
X198782Y151100D01*
X198949Y150850D01*
X199074Y150517D01*
Y149683D01*
G01X198574Y152783D02*
X198866Y153033D01*
X199032Y153367D01*
X199074Y153742D01*
X199032Y154075D01*
X198824Y154408D01*
X198574Y154617D01*
X198324Y154658D01*
X198032Y154575D01*
X197824Y154283D01*
X197741Y153992D01*
Y153617D01*
G01Y153992D02*
X197616Y154242D01*
X197407Y154450D01*
X197157Y154533D01*
X196907Y154450D01*
X196699Y154242D01*
X196574Y153867D01*
X196616Y153492D01*
X196782Y153117D01*
G01X199074Y156800D02*
X196574D01*
X197074Y156300D01*
G01X199074D02*
Y157300D01*
G01X193382Y145317D02*
X193257Y145067D01*
X193174Y144775D01*
Y144442D01*
X193299Y144067D01*
X193507Y143775D01*
X193757Y143567D01*
X194174Y143400D01*
X194549Y143358D01*
X194924Y143442D01*
X195174Y143567D01*
X195424Y143817D01*
X195591Y144108D01*
X195674Y144400D01*
Y144692D01*
X195591Y144983D01*
X195466Y145233D01*
X195299Y145442D01*
G01X193591Y146708D02*
X193341Y146958D01*
X193216Y147250D01*
X193174Y147583D01*
X193257Y148000D01*
X193466Y148292D01*
X193716Y148375D01*
X193966Y148333D01*
X194174Y148167D01*
X194591Y147333D01*
X194882Y146958D01*
X195299Y146708D01*
X195674Y146625D01*
Y148375D01*
G01Y149683D02*
X193174D01*
Y150517D01*
X193299Y150850D01*
X193466Y151100D01*
X193716Y151308D01*
X194007Y151475D01*
X194424Y151517D01*
X194841Y151475D01*
X195132Y151308D01*
X195382Y151100D01*
X195549Y150850D01*
X195674Y150517D01*
Y149683D01*
G01X195174Y152783D02*
X195466Y153033D01*
X195632Y153367D01*
X195674Y153742D01*
X195632Y154075D01*
X195424Y154408D01*
X195174Y154617D01*
X194924Y154658D01*
X194632Y154575D01*
X194424Y154283D01*
X194341Y153992D01*
Y153617D01*
G01Y153992D02*
X194216Y154242D01*
X194007Y154450D01*
X193757Y154533D01*
X193507Y154450D01*
X193299Y154242D01*
X193174Y153867D01*
X193216Y153492D01*
X193382Y153117D01*
G01X193174Y156800D02*
X193257Y156467D01*
X193466Y156217D01*
X193716Y156050D01*
X194049Y155925D01*
X194424Y155883D01*
X194799Y155925D01*
X195132Y156050D01*
X195382Y156217D01*
X195591Y156467D01*
X195674Y156800D01*
X195591Y157133D01*
X195382Y157383D01*
X195132Y157550D01*
X194799Y157675D01*
X194424Y157717D01*
X194049Y157675D01*
X193716Y157550D01*
X193466Y157383D01*
X193257Y157133D01*
X193174Y156800D01*
G01X200182Y145317D02*
X200057Y145067D01*
X199974Y144775D01*
Y144442D01*
X200099Y144067D01*
X200307Y143775D01*
X200557Y143567D01*
X200974Y143400D01*
X201349Y143358D01*
X201724Y143442D01*
X201974Y143567D01*
X202224Y143817D01*
X202391Y144108D01*
X202474Y144400D01*
Y144692D01*
X202391Y144983D01*
X202266Y145233D01*
X202099Y145442D01*
G01X200391Y146708D02*
X200141Y146958D01*
X200016Y147250D01*
X199974Y147583D01*
X200057Y148000D01*
X200266Y148292D01*
X200516Y148375D01*
X200766Y148333D01*
X200974Y148167D01*
X201391Y147333D01*
X201682Y146958D01*
X202099Y146708D01*
X202474Y146625D01*
Y148375D01*
G01Y149683D02*
X199974D01*
Y150517D01*
X200099Y150850D01*
X200266Y151100D01*
X200516Y151308D01*
X200807Y151475D01*
X201224Y151517D01*
X201641Y151475D01*
X201932Y151308D01*
X202182Y151100D01*
X202349Y150850D01*
X202474Y150517D01*
Y149683D01*
G01X201974Y152783D02*
X202266Y153033D01*
X202432Y153367D01*
X202474Y153742D01*
X202432Y154075D01*
X202224Y154408D01*
X201974Y154617D01*
X201724Y154658D01*
X201432Y154575D01*
X201224Y154283D01*
X201141Y153992D01*
Y153617D01*
G01Y153992D02*
X201016Y154242D01*
X200807Y154450D01*
X200557Y154533D01*
X200307Y154450D01*
X200099Y154242D01*
X199974Y153867D01*
X200016Y153492D01*
X200182Y153117D01*
G01X200391Y156008D02*
X200141Y156258D01*
X200016Y156550D01*
X199974Y156883D01*
X200057Y157300D01*
X200266Y157592D01*
X200516Y157675D01*
X200766Y157633D01*
X200974Y157467D01*
X201391Y156633D01*
X201682Y156258D01*
X202099Y156008D01*
X202474Y155925D01*
Y157675D01*
G01X213782Y145317D02*
X213657Y145067D01*
X213574Y144775D01*
Y144442D01*
X213699Y144067D01*
X213907Y143775D01*
X214157Y143567D01*
X214574Y143400D01*
X214949Y143358D01*
X215324Y143442D01*
X215574Y143567D01*
X215824Y143817D01*
X215991Y144108D01*
X216074Y144400D01*
Y144692D01*
X215991Y144983D01*
X215866Y145233D01*
X215699Y145442D01*
G01X213991Y146708D02*
X213741Y146958D01*
X213616Y147250D01*
X213574Y147583D01*
X213657Y148000D01*
X213866Y148292D01*
X214116Y148375D01*
X214366Y148333D01*
X214574Y148167D01*
X214991Y147333D01*
X215282Y146958D01*
X215699Y146708D01*
X216074Y146625D01*
Y148375D01*
G01Y149683D02*
X213574D01*
Y150517D01*
X213699Y150850D01*
X213866Y151100D01*
X214116Y151308D01*
X214407Y151475D01*
X214824Y151517D01*
X215241Y151475D01*
X215532Y151308D01*
X215782Y151100D01*
X215949Y150850D01*
X216074Y150517D01*
Y149683D01*
G01X215574Y152783D02*
X215866Y153033D01*
X216032Y153367D01*
X216074Y153742D01*
X216032Y154075D01*
X215824Y154408D01*
X215574Y154617D01*
X215324Y154658D01*
X215032Y154575D01*
X214824Y154283D01*
X214741Y153992D01*
Y153617D01*
G01Y153992D02*
X214616Y154242D01*
X214407Y154450D01*
X214157Y154533D01*
X213907Y154450D01*
X213699Y154242D01*
X213574Y153867D01*
X213616Y153492D01*
X213782Y153117D01*
G01X215032Y156008D02*
X214741Y156300D01*
X214574Y156550D01*
X214491Y156883D01*
X214574Y157175D01*
X214741Y157383D01*
X214991Y157550D01*
X215282Y157592D01*
X215532Y157550D01*
X215782Y157383D01*
X215991Y157133D01*
X216074Y156842D01*
X215991Y156508D01*
X215741Y156217D01*
X215366Y156050D01*
X214949Y156008D01*
X214407Y156092D01*
X214116Y156217D01*
X213824Y156425D01*
X213616Y156717D01*
X213574Y157008D01*
X213657Y157300D01*
X213866Y157508D01*
G01X217182Y145317D02*
X217057Y145067D01*
X216974Y144775D01*
Y144442D01*
X217099Y144067D01*
X217307Y143775D01*
X217557Y143567D01*
X217974Y143400D01*
X218349Y143358D01*
X218724Y143442D01*
X218974Y143567D01*
X219224Y143817D01*
X219391Y144108D01*
X219474Y144400D01*
Y144692D01*
X219391Y144983D01*
X219266Y145233D01*
X219099Y145442D01*
G01X217391Y146708D02*
X217141Y146958D01*
X217016Y147250D01*
X216974Y147583D01*
X217057Y148000D01*
X217266Y148292D01*
X217516Y148375D01*
X217766Y148333D01*
X217974Y148167D01*
X218391Y147333D01*
X218682Y146958D01*
X219099Y146708D01*
X219474Y146625D01*
Y148375D01*
G01Y149683D02*
X216974D01*
Y150517D01*
X217099Y150850D01*
X217266Y151100D01*
X217516Y151308D01*
X217807Y151475D01*
X218224Y151517D01*
X218641Y151475D01*
X218932Y151308D01*
X219182Y151100D01*
X219349Y150850D01*
X219474Y150517D01*
Y149683D01*
G01X218974Y152783D02*
X219266Y153033D01*
X219432Y153367D01*
X219474Y153742D01*
X219432Y154075D01*
X219224Y154408D01*
X218974Y154617D01*
X218724Y154658D01*
X218432Y154575D01*
X218224Y154283D01*
X218141Y153992D01*
Y153617D01*
G01Y153992D02*
X218016Y154242D01*
X217807Y154450D01*
X217557Y154533D01*
X217307Y154450D01*
X217099Y154242D01*
X216974Y153867D01*
X217016Y153492D01*
X217182Y153117D01*
G01X219474Y156717D02*
X218932Y156800D01*
X218474Y156925D01*
X218057Y157092D01*
X217599Y157300D01*
X216974Y157633D01*
Y155967D01*
G01X200208Y125117D02*
X200083Y124867D01*
X200000Y124575D01*
Y124242D01*
X200125Y123867D01*
X200333Y123575D01*
X200583Y123367D01*
X201000Y123200D01*
X201375Y123158D01*
X201750Y123242D01*
X202000Y123367D01*
X202250Y123617D01*
X202417Y123908D01*
X202500Y124200D01*
Y124492D01*
X202417Y124783D01*
X202292Y125033D01*
X202125Y125242D01*
G01X200417Y126508D02*
X200167Y126758D01*
X200042Y127050D01*
X200000Y127383D01*
X200083Y127800D01*
X200292Y128092D01*
X200542Y128175D01*
X200792Y128133D01*
X201000Y127967D01*
X201417Y127133D01*
X201708Y126758D01*
X202125Y126508D01*
X202500Y126425D01*
Y128175D01*
G01Y129483D02*
X200000D01*
Y130317D01*
X200125Y130650D01*
X200292Y130900D01*
X200542Y131108D01*
X200833Y131275D01*
X201250Y131317D01*
X201667Y131275D01*
X201958Y131108D01*
X202208Y130900D01*
X202375Y130650D01*
X202500Y130317D01*
Y129483D01*
G01Y134000D02*
X200000D01*
X201792Y132458D01*
Y134542D01*
G01X202500Y137100D02*
X200000D01*
X201792Y135558D01*
Y137642D01*
G01X196808Y125117D02*
X196683Y124867D01*
X196600Y124575D01*
Y124242D01*
X196725Y123867D01*
X196933Y123575D01*
X197183Y123367D01*
X197600Y123200D01*
X197975Y123158D01*
X198350Y123242D01*
X198600Y123367D01*
X198850Y123617D01*
X199017Y123908D01*
X199100Y124200D01*
Y124492D01*
X199017Y124783D01*
X198892Y125033D01*
X198725Y125242D01*
G01X197017Y126508D02*
X196767Y126758D01*
X196642Y127050D01*
X196600Y127383D01*
X196683Y127800D01*
X196892Y128092D01*
X197142Y128175D01*
X197392Y128133D01*
X197600Y127967D01*
X198017Y127133D01*
X198308Y126758D01*
X198725Y126508D01*
X199100Y126425D01*
Y128175D01*
G01Y129483D02*
X196600D01*
Y130317D01*
X196725Y130650D01*
X196892Y130900D01*
X197142Y131108D01*
X197433Y131275D01*
X197850Y131317D01*
X198267Y131275D01*
X198558Y131108D01*
X198808Y130900D01*
X198975Y130650D01*
X199100Y130317D01*
Y129483D01*
G01Y134000D02*
X196600D01*
X198392Y132458D01*
Y134542D01*
G01X198600Y135683D02*
X198892Y135933D01*
X199058Y136267D01*
X199100Y136642D01*
X199058Y136975D01*
X198850Y137308D01*
X198600Y137517D01*
X198350Y137558D01*
X198058Y137475D01*
X197850Y137183D01*
X197767Y136892D01*
Y136517D01*
G01Y136892D02*
X197642Y137142D01*
X197433Y137350D01*
X197183Y137433D01*
X196933Y137350D01*
X196725Y137142D01*
X196600Y136767D01*
X196642Y136392D01*
X196808Y136017D01*
G01X181817Y130092D02*
X181567Y130217D01*
X181275Y130300D01*
X180942D01*
X180567Y130175D01*
X180275Y129967D01*
X180067Y129717D01*
X179900Y129300D01*
X179858Y128925D01*
X179942Y128550D01*
X180067Y128300D01*
X180317Y128050D01*
X180608Y127883D01*
X180900Y127800D01*
X181192D01*
X181483Y127883D01*
X181733Y128008D01*
X181942Y128175D01*
G01X183208Y129883D02*
X183458Y130133D01*
X183750Y130258D01*
X184083Y130300D01*
X184500Y130217D01*
X184792Y130008D01*
X184875Y129758D01*
X184833Y129508D01*
X184667Y129300D01*
X183833Y128883D01*
X183458Y128592D01*
X183208Y128175D01*
X183125Y127800D01*
X184875D01*
G01X186183D02*
Y130300D01*
X187017D01*
X187350Y130175D01*
X187600Y130008D01*
X187808Y129758D01*
X187975Y129467D01*
X188017Y129050D01*
X187975Y128633D01*
X187808Y128342D01*
X187600Y128092D01*
X187350Y127925D01*
X187017Y127800D01*
X186183D01*
G01X190700D02*
Y130300D01*
X189158Y128508D01*
X191242D01*
G01X192508Y129883D02*
X192758Y130133D01*
X193050Y130258D01*
X193383Y130300D01*
X193800Y130217D01*
X194092Y130008D01*
X194175Y129758D01*
X194133Y129508D01*
X193967Y129300D01*
X193133Y128883D01*
X192758Y128592D01*
X192508Y128175D01*
X192425Y127800D01*
X194175D01*
G01X210382Y145317D02*
X210257Y145067D01*
X210174Y144775D01*
Y144442D01*
X210299Y144067D01*
X210507Y143775D01*
X210757Y143567D01*
X211174Y143400D01*
X211549Y143358D01*
X211924Y143442D01*
X212174Y143567D01*
X212424Y143817D01*
X212591Y144108D01*
X212674Y144400D01*
Y144692D01*
X212591Y144983D01*
X212466Y145233D01*
X212299Y145442D01*
G01X210591Y146708D02*
X210341Y146958D01*
X210216Y147250D01*
X210174Y147583D01*
X210257Y148000D01*
X210466Y148292D01*
X210716Y148375D01*
X210966Y148333D01*
X211174Y148167D01*
X211591Y147333D01*
X211882Y146958D01*
X212299Y146708D01*
X212674Y146625D01*
Y148375D01*
G01Y149683D02*
X210174D01*
Y150517D01*
X210299Y150850D01*
X210466Y151100D01*
X210716Y151308D01*
X211007Y151475D01*
X211424Y151517D01*
X211841Y151475D01*
X212132Y151308D01*
X212382Y151100D01*
X212549Y150850D01*
X212674Y150517D01*
Y149683D01*
G01X212174Y152783D02*
X212466Y153033D01*
X212632Y153367D01*
X212674Y153742D01*
X212632Y154075D01*
X212424Y154408D01*
X212174Y154617D01*
X211924Y154658D01*
X211632Y154575D01*
X211424Y154283D01*
X211341Y153992D01*
Y153617D01*
G01Y153992D02*
X211216Y154242D01*
X211007Y154450D01*
X210757Y154533D01*
X210507Y154450D01*
X210299Y154242D01*
X210174Y153867D01*
X210216Y153492D01*
X210382Y153117D01*
G01X212299Y155883D02*
X212507Y156133D01*
X212632Y156425D01*
X212674Y156800D01*
X212591Y157175D01*
X212424Y157467D01*
X212132Y157675D01*
X211799Y157717D01*
X211466Y157633D01*
X211257Y157425D01*
X211091Y157133D01*
X211049Y156842D01*
X211091Y156550D01*
X211257Y156175D01*
X210174Y156300D01*
Y157425D01*
G01X190766Y149139D02*
X187766Y145639D01*
X177766D01*
G01X176066Y186139D02*
X190766D01*
Y149139D01*
G01X176066Y141389D02*
X177766D01*
Y157889D01*
X176066D01*
G01X210200Y214995D02*
Y205301D01*
X210201Y205300D01*
X238999D01*
X239000Y205299D01*
Y192400D01*
X250899D01*
X250900Y192399D01*
Y178100D01*
X270299D01*
X270300Y178099D01*
Y141600D01*
X268400D01*
G01X230200Y192517D02*
X227700D01*
Y193558D01*
X227825Y193892D01*
X227992Y194100D01*
X228325Y194183D01*
X228658Y194100D01*
X228867Y193850D01*
X228992Y193558D01*
Y192517D01*
G01Y193558D02*
X230200Y194183D01*
G01X229700Y195533D02*
X229992Y195783D01*
X230158Y196117D01*
X230200Y196492D01*
X230158Y196825D01*
X229950Y197158D01*
X229700Y197367D01*
X229450Y197408D01*
X229158Y197325D01*
X228950Y197033D01*
X228867Y196742D01*
Y196367D01*
G01Y196742D02*
X228742Y196992D01*
X228533Y197200D01*
X228283Y197283D01*
X228033Y197200D01*
X227825Y196992D01*
X227700Y196617D01*
X227742Y196242D01*
X227908Y195867D01*
G01X230200Y198633D02*
X227700D01*
Y199467D01*
X227825Y199800D01*
X227992Y200050D01*
X228242Y200258D01*
X228533Y200425D01*
X228950Y200467D01*
X229367Y200425D01*
X229658Y200258D01*
X229908Y200050D01*
X230075Y199800D01*
X230200Y199467D01*
Y198633D01*
G01X228117Y201858D02*
X227867Y202108D01*
X227742Y202400D01*
X227700Y202733D01*
X227783Y203150D01*
X227992Y203442D01*
X228242Y203525D01*
X228492Y203483D01*
X228700Y203317D01*
X229117Y202483D01*
X229408Y202108D01*
X229825Y201858D01*
X230200Y201775D01*
Y203525D01*
G01X226800Y192517D02*
X224300D01*
Y193558D01*
X224425Y193892D01*
X224592Y194100D01*
X224925Y194183D01*
X225258Y194100D01*
X225467Y193850D01*
X225592Y193558D01*
Y192517D01*
G01Y193558D02*
X226800Y194183D01*
G01X226300Y195533D02*
X226592Y195783D01*
X226758Y196117D01*
X226800Y196492D01*
X226758Y196825D01*
X226550Y197158D01*
X226300Y197367D01*
X226050Y197408D01*
X225758Y197325D01*
X225550Y197033D01*
X225467Y196742D01*
Y196367D01*
G01Y196742D02*
X225342Y196992D01*
X225133Y197200D01*
X224883Y197283D01*
X224633Y197200D01*
X224425Y196992D01*
X224300Y196617D01*
X224342Y196242D01*
X224508Y195867D01*
G01X226800Y198633D02*
X224300D01*
Y199467D01*
X224425Y199800D01*
X224592Y200050D01*
X224842Y200258D01*
X225133Y200425D01*
X225550Y200467D01*
X225967Y200425D01*
X226258Y200258D01*
X226508Y200050D01*
X226675Y199800D01*
X226800Y199467D01*
Y198633D01*
G01Y202650D02*
X224300D01*
X224800Y202150D01*
G01X226800D02*
Y203150D01*
G01X233600Y192517D02*
X231100D01*
Y193558D01*
X231225Y193892D01*
X231392Y194100D01*
X231725Y194183D01*
X232058Y194100D01*
X232267Y193850D01*
X232392Y193558D01*
Y192517D01*
G01Y193558D02*
X233600Y194183D01*
G01X233100Y195533D02*
X233392Y195783D01*
X233558Y196117D01*
X233600Y196492D01*
X233558Y196825D01*
X233350Y197158D01*
X233100Y197367D01*
X232850Y197408D01*
X232558Y197325D01*
X232350Y197033D01*
X232267Y196742D01*
Y196367D01*
G01Y196742D02*
X232142Y196992D01*
X231933Y197200D01*
X231683Y197283D01*
X231433Y197200D01*
X231225Y196992D01*
X231100Y196617D01*
X231142Y196242D01*
X231308Y195867D01*
G01X233600Y198633D02*
X231100D01*
Y199467D01*
X231225Y199800D01*
X231392Y200050D01*
X231642Y200258D01*
X231933Y200425D01*
X232350Y200467D01*
X232767Y200425D01*
X233058Y200258D01*
X233308Y200050D01*
X233475Y199800D01*
X233600Y199467D01*
Y198633D01*
G01X233100Y201733D02*
X233392Y201983D01*
X233558Y202317D01*
X233600Y202692D01*
X233558Y203025D01*
X233350Y203358D01*
X233100Y203567D01*
X232850Y203608D01*
X232558Y203525D01*
X232350Y203233D01*
X232267Y202942D01*
Y202567D01*
G01Y202942D02*
X232142Y203192D01*
X231933Y203400D01*
X231683Y203483D01*
X231433Y203400D01*
X231225Y203192D01*
X231100Y202817D01*
X231142Y202442D01*
X231308Y202067D01*
G01X214750Y212247D02*
X212250D01*
Y213288D01*
X212375Y213622D01*
X212542Y213830D01*
X212875Y213913D01*
X213208Y213830D01*
X213417Y213580D01*
X213542Y213288D01*
Y212247D01*
G01Y213288D02*
X214750Y213913D01*
G01Y216180D02*
X212250D01*
X212750Y215680D01*
G01X214750D02*
Y216680D01*
G01Y218363D02*
X212250D01*
Y219197D01*
X212375Y219530D01*
X212542Y219780D01*
X212792Y219988D01*
X213083Y220155D01*
X213500Y220197D01*
X213917Y220155D01*
X214208Y219988D01*
X214458Y219780D01*
X214625Y219530D01*
X214750Y219197D01*
Y218363D01*
G01X214375Y221463D02*
X214583Y221713D01*
X214708Y222005D01*
X214750Y222380D01*
X214667Y222755D01*
X214500Y223047D01*
X214208Y223255D01*
X213875Y223297D01*
X213542Y223213D01*
X213333Y223005D01*
X213167Y222713D01*
X213125Y222422D01*
X213167Y222130D01*
X213333Y221755D01*
X212250Y221880D01*
Y223005D01*
G01X214750Y225480D02*
X212250D01*
X212750Y224980D01*
G01X214750D02*
Y225980D01*
G01X216167Y211300D02*
Y213800D01*
X217208D01*
X217542Y213675D01*
X217750Y213508D01*
X217833Y213175D01*
X217750Y212842D01*
X217500Y212633D01*
X217208Y212508D01*
X216167D01*
G01X217208D02*
X217833Y211300D01*
G01X220100D02*
Y213800D01*
X219600Y213300D01*
G01Y211300D02*
X220600D01*
G01X224033D02*
X222367D01*
Y213800D01*
X224033D01*
G01X223367Y212592D02*
X222367D01*
G01X226300Y211300D02*
Y213800D01*
X225800Y213300D01*
G01Y211300D02*
X226800D01*
G01X228483Y211800D02*
X228733Y211508D01*
X229067Y211342D01*
X229442Y211300D01*
X229775Y211342D01*
X230108Y211550D01*
X230317Y211800D01*
X230358Y212050D01*
X230275Y212342D01*
X229983Y212550D01*
X229692Y212633D01*
X229317D01*
G01X229692D02*
X229942Y212758D01*
X230150Y212967D01*
X230233Y213217D01*
X230150Y213467D01*
X229942Y213675D01*
X229567Y213800D01*
X229192Y213758D01*
X228817Y213592D01*
G01X176594Y206576D02*
Y209076D01*
X177635D01*
X177969Y208951D01*
X178177Y208784D01*
X178260Y208451D01*
X178177Y208118D01*
X177927Y207909D01*
X177635Y207784D01*
X176594D01*
G01X177635D02*
X178260Y206576D01*
G01X180527D02*
Y209076D01*
X180027Y208576D01*
G01Y206576D02*
X181027D01*
G01X184460D02*
X182794D01*
Y209076D01*
X184460D01*
G01X183794Y207868D02*
X182794D01*
G01X185810Y207076D02*
X186060Y206784D01*
X186394Y206618D01*
X186769Y206576D01*
X187102Y206618D01*
X187435Y206826D01*
X187644Y207076D01*
X187685Y207326D01*
X187602Y207618D01*
X187310Y207826D01*
X187019Y207909D01*
X186644D01*
G01X187019D02*
X187269Y208034D01*
X187477Y208243D01*
X187560Y208493D01*
X187477Y208743D01*
X187269Y208951D01*
X186894Y209076D01*
X186519Y209034D01*
X186144Y208868D01*
G01X174130Y194559D02*
Y197059D01*
X175171D01*
X175505Y196934D01*
X175713Y196767D01*
X175796Y196434D01*
X175713Y196101D01*
X175463Y195892D01*
X175171Y195767D01*
X174130D01*
G01X175171D02*
X175796Y194559D01*
G01X178063Y197059D02*
Y194559D01*
G01X177105Y197059D02*
X179021D01*
G01X181163Y194559D02*
X181455Y194601D01*
X181788Y194726D01*
X181996Y194934D01*
X182080Y195226D01*
X181996Y195517D01*
X181746Y195767D01*
X181371Y195892D01*
X180955D01*
X180705Y195976D01*
X180496Y196184D01*
X180413Y196476D01*
X180538Y196767D01*
X180830Y196976D01*
X181163Y197059D01*
X181496Y196976D01*
X181788Y196767D01*
X181913Y196476D01*
X181830Y196184D01*
X181621Y195976D01*
X181371Y195892D01*
X180955D01*
X180580Y195767D01*
X180330Y195517D01*
X180246Y195226D01*
X180330Y194934D01*
X180538Y194726D01*
X180871Y194601D01*
X181163Y194559D01*
G01X183430D02*
Y197059D01*
X184430D01*
X184763Y196934D01*
X185013Y196642D01*
X185096Y196309D01*
X185013Y195976D01*
X184805Y195726D01*
X184430Y195601D01*
X183430D01*
G01X187363Y194559D02*
Y197059D01*
X186863Y196559D01*
G01Y194559D02*
X187863D01*
G01X216167Y214700D02*
Y217200D01*
X217208D01*
X217542Y217075D01*
X217750Y216908D01*
X217833Y216575D01*
X217750Y216242D01*
X217500Y216033D01*
X217208Y215908D01*
X216167D01*
G01X217208D02*
X217833Y214700D01*
G01X220100Y217200D02*
Y214700D01*
G01X219142Y217200D02*
X221058D01*
G01X223200Y214700D02*
Y217200D01*
X222700Y216700D01*
G01Y214700D02*
X223700D01*
G01X226217D02*
X226300Y215242D01*
X226425Y215700D01*
X226592Y216117D01*
X226800Y216575D01*
X227133Y217200D01*
X225467D01*
G01X230481Y161293D02*
X230356Y161043D01*
X230273Y160751D01*
Y160418D01*
X230398Y160043D01*
X230606Y159751D01*
X230856Y159543D01*
X231273Y159376D01*
X231648Y159334D01*
X232023Y159418D01*
X232273Y159543D01*
X232523Y159793D01*
X232690Y160084D01*
X232773Y160376D01*
Y160668D01*
X232690Y160959D01*
X232565Y161209D01*
X232398Y161418D01*
G01X232273Y162559D02*
X232565Y162809D01*
X232731Y163143D01*
X232773Y163518D01*
X232731Y163851D01*
X232523Y164184D01*
X232273Y164393D01*
X232023Y164434D01*
X231731Y164351D01*
X231523Y164059D01*
X231440Y163768D01*
Y163393D01*
G01Y163768D02*
X231315Y164018D01*
X231106Y164226D01*
X230856Y164309D01*
X230606Y164226D01*
X230398Y164018D01*
X230273Y163643D01*
X230315Y163268D01*
X230481Y162893D01*
G01X232773Y165659D02*
X230273D01*
Y166493D01*
X230398Y166826D01*
X230565Y167076D01*
X230815Y167284D01*
X231106Y167451D01*
X231523Y167493D01*
X231940Y167451D01*
X232231Y167284D01*
X232481Y167076D01*
X232648Y166826D01*
X232773Y166493D01*
Y165659D01*
G01Y169676D02*
X230273D01*
X230773Y169176D01*
G01X232773D02*
Y170176D01*
G01X230273Y172776D02*
X230356Y172443D01*
X230565Y172193D01*
X230815Y172026D01*
X231148Y171901D01*
X231523Y171859D01*
X231898Y171901D01*
X232231Y172026D01*
X232481Y172193D01*
X232690Y172443D01*
X232773Y172776D01*
X232690Y173109D01*
X232481Y173359D01*
X232231Y173526D01*
X231898Y173651D01*
X231523Y173693D01*
X231148Y173651D01*
X230815Y173526D01*
X230565Y173359D01*
X230356Y173109D01*
X230273Y172776D01*
G01X223681Y161293D02*
X223556Y161043D01*
X223473Y160751D01*
Y160418D01*
X223598Y160043D01*
X223806Y159751D01*
X224056Y159543D01*
X224473Y159376D01*
X224848Y159334D01*
X225223Y159418D01*
X225473Y159543D01*
X225723Y159793D01*
X225890Y160084D01*
X225973Y160376D01*
Y160668D01*
X225890Y160959D01*
X225765Y161209D01*
X225598Y161418D01*
G01X223890Y162684D02*
X223640Y162934D01*
X223515Y163226D01*
X223473Y163559D01*
X223556Y163976D01*
X223765Y164268D01*
X224015Y164351D01*
X224265Y164309D01*
X224473Y164143D01*
X224890Y163309D01*
X225181Y162934D01*
X225598Y162684D01*
X225973Y162601D01*
Y164351D01*
G01Y165659D02*
X223473D01*
Y166493D01*
X223598Y166826D01*
X223765Y167076D01*
X224015Y167284D01*
X224306Y167451D01*
X224723Y167493D01*
X225140Y167451D01*
X225431Y167284D01*
X225681Y167076D01*
X225848Y166826D01*
X225973Y166493D01*
Y165659D01*
G01X223890Y168884D02*
X223640Y169134D01*
X223515Y169426D01*
X223473Y169759D01*
X223556Y170176D01*
X223765Y170468D01*
X224015Y170551D01*
X224265Y170509D01*
X224473Y170343D01*
X224890Y169509D01*
X225181Y169134D01*
X225598Y168884D01*
X225973Y168801D01*
Y170551D01*
G01Y172776D02*
X225931Y173068D01*
X225806Y173401D01*
X225598Y173609D01*
X225306Y173693D01*
X225015Y173609D01*
X224765Y173359D01*
X224640Y172984D01*
Y172568D01*
X224556Y172318D01*
X224348Y172109D01*
X224056Y172026D01*
X223765Y172151D01*
X223556Y172443D01*
X223473Y172776D01*
X223556Y173109D01*
X223765Y173401D01*
X224056Y173526D01*
X224348Y173443D01*
X224556Y173234D01*
X224640Y172984D01*
Y172568D01*
X224765Y172193D01*
X225015Y171943D01*
X225306Y171859D01*
X225598Y171943D01*
X225806Y172151D01*
X225931Y172484D01*
X225973Y172776D01*
G01X227081Y161293D02*
X226956Y161043D01*
X226873Y160751D01*
Y160418D01*
X226998Y160043D01*
X227206Y159751D01*
X227456Y159543D01*
X227873Y159376D01*
X228248Y159334D01*
X228623Y159418D01*
X228873Y159543D01*
X229123Y159793D01*
X229290Y160084D01*
X229373Y160376D01*
Y160668D01*
X229290Y160959D01*
X229165Y161209D01*
X228998Y161418D01*
G01X227290Y162684D02*
X227040Y162934D01*
X226915Y163226D01*
X226873Y163559D01*
X226956Y163976D01*
X227165Y164268D01*
X227415Y164351D01*
X227665Y164309D01*
X227873Y164143D01*
X228290Y163309D01*
X228581Y162934D01*
X228998Y162684D01*
X229373Y162601D01*
Y164351D01*
G01Y165659D02*
X226873D01*
Y166493D01*
X226998Y166826D01*
X227165Y167076D01*
X227415Y167284D01*
X227706Y167451D01*
X228123Y167493D01*
X228540Y167451D01*
X228831Y167284D01*
X229081Y167076D01*
X229248Y166826D01*
X229373Y166493D01*
Y165659D01*
G01X227290Y168884D02*
X227040Y169134D01*
X226915Y169426D01*
X226873Y169759D01*
X226956Y170176D01*
X227165Y170468D01*
X227415Y170551D01*
X227665Y170509D01*
X227873Y170343D01*
X228290Y169509D01*
X228581Y169134D01*
X228998Y168884D01*
X229373Y168801D01*
Y170551D01*
G01X229081Y172068D02*
X229290Y172359D01*
X229373Y172693D01*
X229290Y173026D01*
X229040Y173318D01*
X228665Y173526D01*
X228290Y173609D01*
X227831D01*
X227456Y173526D01*
X227123Y173318D01*
X226956Y173068D01*
X226873Y172776D01*
X226956Y172443D01*
X227123Y172193D01*
X227373Y172026D01*
X227706Y171943D01*
X227998Y172026D01*
X228290Y172234D01*
X228456Y172484D01*
X228498Y172776D01*
X228415Y173109D01*
X228206Y173359D01*
X227831Y173609D01*
G01X220281Y161293D02*
X220156Y161043D01*
X220073Y160751D01*
Y160418D01*
X220198Y160043D01*
X220406Y159751D01*
X220656Y159543D01*
X221073Y159376D01*
X221448Y159334D01*
X221823Y159418D01*
X222073Y159543D01*
X222323Y159793D01*
X222490Y160084D01*
X222573Y160376D01*
Y160668D01*
X222490Y160959D01*
X222365Y161209D01*
X222198Y161418D01*
G01X220490Y162684D02*
X220240Y162934D01*
X220115Y163226D01*
X220073Y163559D01*
X220156Y163976D01*
X220365Y164268D01*
X220615Y164351D01*
X220865Y164309D01*
X221073Y164143D01*
X221490Y163309D01*
X221781Y162934D01*
X222198Y162684D01*
X222573Y162601D01*
Y164351D01*
G01Y165659D02*
X220073D01*
Y166493D01*
X220198Y166826D01*
X220365Y167076D01*
X220615Y167284D01*
X220906Y167451D01*
X221323Y167493D01*
X221740Y167451D01*
X222031Y167284D01*
X222281Y167076D01*
X222448Y166826D01*
X222573Y166493D01*
Y165659D01*
G01X220490Y168884D02*
X220240Y169134D01*
X220115Y169426D01*
X220073Y169759D01*
X220156Y170176D01*
X220365Y170468D01*
X220615Y170551D01*
X220865Y170509D01*
X221073Y170343D01*
X221490Y169509D01*
X221781Y169134D01*
X222198Y168884D01*
X222573Y168801D01*
Y170551D01*
G01Y172693D02*
X222031Y172776D01*
X221573Y172901D01*
X221156Y173068D01*
X220698Y173276D01*
X220073Y173609D01*
Y171943D01*
G01X227108Y177117D02*
X226983Y176867D01*
X226900Y176575D01*
Y176242D01*
X227025Y175867D01*
X227233Y175575D01*
X227483Y175367D01*
X227900Y175200D01*
X228275Y175158D01*
X228650Y175242D01*
X228900Y175367D01*
X229150Y175617D01*
X229317Y175908D01*
X229400Y176200D01*
Y176492D01*
X229317Y176783D01*
X229192Y177033D01*
X229025Y177242D01*
G01X227317Y178508D02*
X227067Y178758D01*
X226942Y179050D01*
X226900Y179383D01*
X226983Y179800D01*
X227192Y180092D01*
X227442Y180175D01*
X227692Y180133D01*
X227900Y179967D01*
X228317Y179133D01*
X228608Y178758D01*
X229025Y178508D01*
X229400Y178425D01*
Y180175D01*
G01Y181483D02*
X226900D01*
Y182317D01*
X227025Y182650D01*
X227192Y182900D01*
X227442Y183108D01*
X227733Y183275D01*
X228150Y183317D01*
X228567Y183275D01*
X228858Y183108D01*
X229108Y182900D01*
X229275Y182650D01*
X229400Y182317D01*
Y181483D01*
G01Y185500D02*
X226900D01*
X227400Y185000D01*
G01X229400D02*
Y186000D01*
G01Y188600D02*
X229358Y188892D01*
X229233Y189225D01*
X229025Y189433D01*
X228733Y189517D01*
X228442Y189433D01*
X228192Y189183D01*
X228067Y188808D01*
Y188392D01*
X227983Y188142D01*
X227775Y187933D01*
X227483Y187850D01*
X227192Y187975D01*
X226983Y188267D01*
X226900Y188600D01*
X226983Y188933D01*
X227192Y189225D01*
X227483Y189350D01*
X227775Y189267D01*
X227983Y189058D01*
X228067Y188808D01*
Y188392D01*
X228192Y188017D01*
X228442Y187767D01*
X228733Y187683D01*
X229025Y187767D01*
X229233Y187975D01*
X229358Y188308D01*
X229400Y188600D01*
G01X221108Y194267D02*
X220983Y194017D01*
X220900Y193725D01*
Y193392D01*
X221025Y193017D01*
X221233Y192725D01*
X221483Y192517D01*
X221900Y192350D01*
X222275Y192308D01*
X222650Y192392D01*
X222900Y192517D01*
X223150Y192767D01*
X223317Y193058D01*
X223400Y193350D01*
Y193642D01*
X223317Y193933D01*
X223192Y194183D01*
X223025Y194392D01*
G01X222900Y195533D02*
X223192Y195783D01*
X223358Y196117D01*
X223400Y196492D01*
X223358Y196825D01*
X223150Y197158D01*
X222900Y197367D01*
X222650Y197408D01*
X222358Y197325D01*
X222150Y197033D01*
X222067Y196742D01*
Y196367D01*
G01Y196742D02*
X221942Y196992D01*
X221733Y197200D01*
X221483Y197283D01*
X221233Y197200D01*
X221025Y196992D01*
X220900Y196617D01*
X220942Y196242D01*
X221108Y195867D01*
G01X223400Y198633D02*
X220900D01*
Y199467D01*
X221025Y199800D01*
X221192Y200050D01*
X221442Y200258D01*
X221733Y200425D01*
X222150Y200467D01*
X222567Y200425D01*
X222858Y200258D01*
X223108Y200050D01*
X223275Y199800D01*
X223400Y199467D01*
Y198633D01*
G01X221317Y201858D02*
X221067Y202108D01*
X220942Y202400D01*
X220900Y202733D01*
X220983Y203150D01*
X221192Y203442D01*
X221442Y203525D01*
X221692Y203483D01*
X221900Y203317D01*
X222317Y202483D01*
X222608Y202108D01*
X223025Y201858D01*
X223400Y201775D01*
Y203525D01*
G01X217708Y194267D02*
X217583Y194017D01*
X217500Y193725D01*
Y193392D01*
X217625Y193017D01*
X217833Y192725D01*
X218083Y192517D01*
X218500Y192350D01*
X218875Y192308D01*
X219250Y192392D01*
X219500Y192517D01*
X219750Y192767D01*
X219917Y193058D01*
X220000Y193350D01*
Y193642D01*
X219917Y193933D01*
X219792Y194183D01*
X219625Y194392D01*
G01X219500Y195533D02*
X219792Y195783D01*
X219958Y196117D01*
X220000Y196492D01*
X219958Y196825D01*
X219750Y197158D01*
X219500Y197367D01*
X219250Y197408D01*
X218958Y197325D01*
X218750Y197033D01*
X218667Y196742D01*
Y196367D01*
G01Y196742D02*
X218542Y196992D01*
X218333Y197200D01*
X218083Y197283D01*
X217833Y197200D01*
X217625Y196992D01*
X217500Y196617D01*
X217542Y196242D01*
X217708Y195867D01*
G01X220000Y198633D02*
X217500D01*
Y199467D01*
X217625Y199800D01*
X217792Y200050D01*
X218042Y200258D01*
X218333Y200425D01*
X218750Y200467D01*
X219167Y200425D01*
X219458Y200258D01*
X219708Y200050D01*
X219875Y199800D01*
X220000Y199467D01*
Y198633D01*
G01Y202650D02*
X217500D01*
X218000Y202150D01*
G01X220000D02*
Y203150D01*
G01X210908Y194267D02*
X210783Y194017D01*
X210700Y193725D01*
Y193392D01*
X210825Y193017D01*
X211033Y192725D01*
X211283Y192517D01*
X211700Y192350D01*
X212075Y192308D01*
X212450Y192392D01*
X212700Y192517D01*
X212950Y192767D01*
X213117Y193058D01*
X213200Y193350D01*
Y193642D01*
X213117Y193933D01*
X212992Y194183D01*
X212825Y194392D01*
G01X211117Y195658D02*
X210867Y195908D01*
X210742Y196200D01*
X210700Y196533D01*
X210783Y196950D01*
X210992Y197242D01*
X211242Y197325D01*
X211492Y197283D01*
X211700Y197117D01*
X212117Y196283D01*
X212408Y195908D01*
X212825Y195658D01*
X213200Y195575D01*
Y197325D01*
G01Y198633D02*
X210700D01*
Y199467D01*
X210825Y199800D01*
X210992Y200050D01*
X211242Y200258D01*
X211533Y200425D01*
X211950Y200467D01*
X212367Y200425D01*
X212658Y200258D01*
X212908Y200050D01*
X213075Y199800D01*
X213200Y199467D01*
Y198633D01*
G01X211117Y201858D02*
X210867Y202108D01*
X210742Y202400D01*
X210700Y202733D01*
X210783Y203150D01*
X210992Y203442D01*
X211242Y203525D01*
X211492Y203483D01*
X211700Y203317D01*
X212117Y202483D01*
X212408Y202108D01*
X212825Y201858D01*
X213200Y201775D01*
Y203525D01*
G01X214308Y194267D02*
X214183Y194017D01*
X214100Y193725D01*
Y193392D01*
X214225Y193017D01*
X214433Y192725D01*
X214683Y192517D01*
X215100Y192350D01*
X215475Y192308D01*
X215850Y192392D01*
X216100Y192517D01*
X216350Y192767D01*
X216517Y193058D01*
X216600Y193350D01*
Y193642D01*
X216517Y193933D01*
X216392Y194183D01*
X216225Y194392D01*
G01X214517Y195658D02*
X214267Y195908D01*
X214142Y196200D01*
X214100Y196533D01*
X214183Y196950D01*
X214392Y197242D01*
X214642Y197325D01*
X214892Y197283D01*
X215100Y197117D01*
X215517Y196283D01*
X215808Y195908D01*
X216225Y195658D01*
X216600Y195575D01*
Y197325D01*
G01Y198633D02*
X214100D01*
Y199467D01*
X214225Y199800D01*
X214392Y200050D01*
X214642Y200258D01*
X214933Y200425D01*
X215350Y200467D01*
X215767Y200425D01*
X216058Y200258D01*
X216308Y200050D01*
X216475Y199800D01*
X216600Y199467D01*
Y198633D01*
G01X216100Y201733D02*
X216392Y201983D01*
X216558Y202317D01*
X216600Y202692D01*
X216558Y203025D01*
X216350Y203358D01*
X216100Y203567D01*
X215850Y203608D01*
X215558Y203525D01*
X215350Y203233D01*
X215267Y202942D01*
Y202567D01*
G01Y202942D02*
X215142Y203192D01*
X214933Y203400D01*
X214683Y203483D01*
X214433Y203400D01*
X214225Y203192D01*
X214100Y202817D01*
X214142Y202442D01*
X214308Y202067D01*
G01X207508Y194267D02*
X207383Y194017D01*
X207300Y193725D01*
Y193392D01*
X207425Y193017D01*
X207633Y192725D01*
X207883Y192517D01*
X208300Y192350D01*
X208675Y192308D01*
X209050Y192392D01*
X209300Y192517D01*
X209550Y192767D01*
X209717Y193058D01*
X209800Y193350D01*
Y193642D01*
X209717Y193933D01*
X209592Y194183D01*
X209425Y194392D01*
G01X207717Y195658D02*
X207467Y195908D01*
X207342Y196200D01*
X207300Y196533D01*
X207383Y196950D01*
X207592Y197242D01*
X207842Y197325D01*
X208092Y197283D01*
X208300Y197117D01*
X208717Y196283D01*
X209008Y195908D01*
X209425Y195658D01*
X209800Y195575D01*
Y197325D01*
G01Y198633D02*
X207300D01*
Y199467D01*
X207425Y199800D01*
X207592Y200050D01*
X207842Y200258D01*
X208133Y200425D01*
X208550Y200467D01*
X208967Y200425D01*
X209258Y200258D01*
X209508Y200050D01*
X209675Y199800D01*
X209800Y199467D01*
Y198633D01*
G01Y202650D02*
X207300D01*
X207800Y202150D01*
G01X209800D02*
Y203150D01*
G01X220408Y177217D02*
X220283Y176967D01*
X220200Y176675D01*
Y176342D01*
X220325Y175967D01*
X220533Y175675D01*
X220783Y175467D01*
X221200Y175300D01*
X221575Y175258D01*
X221950Y175342D01*
X222200Y175467D01*
X222450Y175717D01*
X222617Y176008D01*
X222700Y176300D01*
Y176592D01*
X222617Y176883D01*
X222492Y177133D01*
X222325Y177342D01*
G01X220617Y178608D02*
X220367Y178858D01*
X220242Y179150D01*
X220200Y179483D01*
X220283Y179900D01*
X220492Y180192D01*
X220742Y180275D01*
X220992Y180233D01*
X221200Y180067D01*
X221617Y179233D01*
X221908Y178858D01*
X222325Y178608D01*
X222700Y178525D01*
Y180275D01*
G01Y181583D02*
X220200D01*
Y182417D01*
X220325Y182750D01*
X220492Y183000D01*
X220742Y183208D01*
X221033Y183375D01*
X221450Y183417D01*
X221867Y183375D01*
X222158Y183208D01*
X222408Y183000D01*
X222575Y182750D01*
X222700Y182417D01*
Y181583D01*
G01Y185600D02*
X220200D01*
X220700Y185100D01*
G01X222700D02*
Y186100D01*
G01Y188617D02*
X222158Y188700D01*
X221700Y188825D01*
X221283Y188992D01*
X220825Y189200D01*
X220200Y189533D01*
Y187867D01*
G01X193081Y177543D02*
X192956Y177293D01*
X192873Y177001D01*
Y176668D01*
X192998Y176293D01*
X193206Y176001D01*
X193456Y175793D01*
X193873Y175626D01*
X194248Y175584D01*
X194623Y175668D01*
X194873Y175793D01*
X195123Y176043D01*
X195290Y176334D01*
X195373Y176626D01*
Y176918D01*
X195290Y177209D01*
X195165Y177459D01*
X194998Y177668D01*
G01X193290Y178934D02*
X193040Y179184D01*
X192915Y179476D01*
X192873Y179809D01*
X192956Y180226D01*
X193165Y180518D01*
X193415Y180601D01*
X193665Y180559D01*
X193873Y180393D01*
X194290Y179559D01*
X194581Y179184D01*
X194998Y178934D01*
X195373Y178851D01*
Y180601D01*
G01Y181909D02*
X192873D01*
Y182743D01*
X192998Y183076D01*
X193165Y183326D01*
X193415Y183534D01*
X193706Y183701D01*
X194123Y183743D01*
X194540Y183701D01*
X194831Y183534D01*
X195081Y183326D01*
X195248Y183076D01*
X195373Y182743D01*
Y181909D01*
G01X195081Y185218D02*
X195290Y185509D01*
X195373Y185843D01*
X195290Y186176D01*
X195040Y186468D01*
X194665Y186676D01*
X194290Y186759D01*
X193831D01*
X193456Y186676D01*
X193123Y186468D01*
X192956Y186218D01*
X192873Y185926D01*
X192956Y185593D01*
X193123Y185343D01*
X193373Y185176D01*
X193706Y185093D01*
X193998Y185176D01*
X194290Y185384D01*
X194456Y185634D01*
X194498Y185926D01*
X194415Y186259D01*
X194206Y186509D01*
X193831Y186759D01*
G01X196481Y177543D02*
X196356Y177293D01*
X196273Y177001D01*
Y176668D01*
X196398Y176293D01*
X196606Y176001D01*
X196856Y175793D01*
X197273Y175626D01*
X197648Y175584D01*
X198023Y175668D01*
X198273Y175793D01*
X198523Y176043D01*
X198690Y176334D01*
X198773Y176626D01*
Y176918D01*
X198690Y177209D01*
X198565Y177459D01*
X198398Y177668D01*
G01X196690Y178934D02*
X196440Y179184D01*
X196315Y179476D01*
X196273Y179809D01*
X196356Y180226D01*
X196565Y180518D01*
X196815Y180601D01*
X197065Y180559D01*
X197273Y180393D01*
X197690Y179559D01*
X197981Y179184D01*
X198398Y178934D01*
X198773Y178851D01*
Y180601D01*
G01Y181909D02*
X196273D01*
Y182743D01*
X196398Y183076D01*
X196565Y183326D01*
X196815Y183534D01*
X197106Y183701D01*
X197523Y183743D01*
X197940Y183701D01*
X198231Y183534D01*
X198481Y183326D01*
X198648Y183076D01*
X198773Y182743D01*
Y181909D01*
G01Y185926D02*
X196273D01*
X196773Y185426D01*
G01X198773D02*
Y186426D01*
G01X196273Y189026D02*
X196356Y188693D01*
X196565Y188443D01*
X196815Y188276D01*
X197148Y188151D01*
X197523Y188109D01*
X197898Y188151D01*
X198231Y188276D01*
X198481Y188443D01*
X198690Y188693D01*
X198773Y189026D01*
X198690Y189359D01*
X198481Y189609D01*
X198231Y189776D01*
X197898Y189901D01*
X197523Y189943D01*
X197148Y189901D01*
X196815Y189776D01*
X196565Y189609D01*
X196356Y189359D01*
X196273Y189026D01*
G01X199881Y177543D02*
X199756Y177293D01*
X199673Y177001D01*
Y176668D01*
X199798Y176293D01*
X200006Y176001D01*
X200256Y175793D01*
X200673Y175626D01*
X201048Y175584D01*
X201423Y175668D01*
X201673Y175793D01*
X201923Y176043D01*
X202090Y176334D01*
X202173Y176626D01*
Y176918D01*
X202090Y177209D01*
X201965Y177459D01*
X201798Y177668D01*
G01X200090Y178934D02*
X199840Y179184D01*
X199715Y179476D01*
X199673Y179809D01*
X199756Y180226D01*
X199965Y180518D01*
X200215Y180601D01*
X200465Y180559D01*
X200673Y180393D01*
X201090Y179559D01*
X201381Y179184D01*
X201798Y178934D01*
X202173Y178851D01*
Y180601D01*
G01Y181909D02*
X199673D01*
Y182743D01*
X199798Y183076D01*
X199965Y183326D01*
X200215Y183534D01*
X200506Y183701D01*
X200923Y183743D01*
X201340Y183701D01*
X201631Y183534D01*
X201881Y183326D01*
X202048Y183076D01*
X202173Y182743D01*
Y181909D01*
G01Y185926D02*
X199673D01*
X200173Y185426D01*
G01X202173D02*
Y186426D01*
G01Y189026D02*
X199673D01*
X200173Y188526D01*
G01X202173D02*
Y189526D01*
G01X190508Y194267D02*
X190383Y194017D01*
X190300Y193725D01*
Y193392D01*
X190425Y193017D01*
X190633Y192725D01*
X190883Y192517D01*
X191300Y192350D01*
X191675Y192308D01*
X192050Y192392D01*
X192300Y192517D01*
X192550Y192767D01*
X192717Y193058D01*
X192800Y193350D01*
Y193642D01*
X192717Y193933D01*
X192592Y194183D01*
X192425Y194392D01*
G01X190717Y195658D02*
X190467Y195908D01*
X190342Y196200D01*
X190300Y196533D01*
X190383Y196950D01*
X190592Y197242D01*
X190842Y197325D01*
X191092Y197283D01*
X191300Y197117D01*
X191717Y196283D01*
X192008Y195908D01*
X192425Y195658D01*
X192800Y195575D01*
Y197325D01*
G01Y198633D02*
X190300D01*
Y199467D01*
X190425Y199800D01*
X190592Y200050D01*
X190842Y200258D01*
X191133Y200425D01*
X191550Y200467D01*
X191967Y200425D01*
X192258Y200258D01*
X192508Y200050D01*
X192675Y199800D01*
X192800Y199467D01*
Y198633D01*
G01Y202650D02*
X192758Y202942D01*
X192633Y203275D01*
X192425Y203483D01*
X192133Y203567D01*
X191842Y203483D01*
X191592Y203233D01*
X191467Y202858D01*
Y202442D01*
X191383Y202192D01*
X191175Y201983D01*
X190883Y201900D01*
X190592Y202025D01*
X190383Y202317D01*
X190300Y202650D01*
X190383Y202983D01*
X190592Y203275D01*
X190883Y203400D01*
X191175Y203317D01*
X191383Y203108D01*
X191467Y202858D01*
Y202442D01*
X191592Y202067D01*
X191842Y201817D01*
X192133Y201733D01*
X192425Y201817D01*
X192633Y202025D01*
X192758Y202358D01*
X192800Y202650D01*
G01X193908Y194267D02*
X193783Y194017D01*
X193700Y193725D01*
Y193392D01*
X193825Y193017D01*
X194033Y192725D01*
X194283Y192517D01*
X194700Y192350D01*
X195075Y192308D01*
X195450Y192392D01*
X195700Y192517D01*
X195950Y192767D01*
X196117Y193058D01*
X196200Y193350D01*
Y193642D01*
X196117Y193933D01*
X195992Y194183D01*
X195825Y194392D01*
G01X194117Y195658D02*
X193867Y195908D01*
X193742Y196200D01*
X193700Y196533D01*
X193783Y196950D01*
X193992Y197242D01*
X194242Y197325D01*
X194492Y197283D01*
X194700Y197117D01*
X195117Y196283D01*
X195408Y195908D01*
X195825Y195658D01*
X196200Y195575D01*
Y197325D01*
G01Y198633D02*
X193700D01*
Y199467D01*
X193825Y199800D01*
X193992Y200050D01*
X194242Y200258D01*
X194533Y200425D01*
X194950Y200467D01*
X195367Y200425D01*
X195658Y200258D01*
X195908Y200050D01*
X196075Y199800D01*
X196200Y199467D01*
Y198633D01*
G01Y202567D02*
X195658Y202650D01*
X195200Y202775D01*
X194783Y202942D01*
X194325Y203150D01*
X193700Y203483D01*
Y201817D01*
G01X204108Y194267D02*
X203983Y194017D01*
X203900Y193725D01*
Y193392D01*
X204025Y193017D01*
X204233Y192725D01*
X204483Y192517D01*
X204900Y192350D01*
X205275Y192308D01*
X205650Y192392D01*
X205900Y192517D01*
X206150Y192767D01*
X206317Y193058D01*
X206400Y193350D01*
Y193642D01*
X206317Y193933D01*
X206192Y194183D01*
X206025Y194392D01*
G01X204317Y195658D02*
X204067Y195908D01*
X203942Y196200D01*
X203900Y196533D01*
X203983Y196950D01*
X204192Y197242D01*
X204442Y197325D01*
X204692Y197283D01*
X204900Y197117D01*
X205317Y196283D01*
X205608Y195908D01*
X206025Y195658D01*
X206400Y195575D01*
Y197325D01*
G01Y198633D02*
X203900D01*
Y199467D01*
X204025Y199800D01*
X204192Y200050D01*
X204442Y200258D01*
X204733Y200425D01*
X205150Y200467D01*
X205567Y200425D01*
X205858Y200258D01*
X206108Y200050D01*
X206275Y199800D01*
X206400Y199467D01*
Y198633D01*
G01X205358Y201858D02*
X205067Y202150D01*
X204900Y202400D01*
X204817Y202733D01*
X204900Y203025D01*
X205067Y203233D01*
X205317Y203400D01*
X205608Y203442D01*
X205858Y203400D01*
X206108Y203233D01*
X206317Y202983D01*
X206400Y202692D01*
X206317Y202358D01*
X206067Y202067D01*
X205692Y201900D01*
X205275Y201858D01*
X204733Y201942D01*
X204442Y202067D01*
X204150Y202275D01*
X203942Y202567D01*
X203900Y202858D01*
X203983Y203150D01*
X204192Y203358D01*
G01X200708Y194267D02*
X200583Y194017D01*
X200500Y193725D01*
Y193392D01*
X200625Y193017D01*
X200833Y192725D01*
X201083Y192517D01*
X201500Y192350D01*
X201875Y192308D01*
X202250Y192392D01*
X202500Y192517D01*
X202750Y192767D01*
X202917Y193058D01*
X203000Y193350D01*
Y193642D01*
X202917Y193933D01*
X202792Y194183D01*
X202625Y194392D01*
G01X200917Y195658D02*
X200667Y195908D01*
X200542Y196200D01*
X200500Y196533D01*
X200583Y196950D01*
X200792Y197242D01*
X201042Y197325D01*
X201292Y197283D01*
X201500Y197117D01*
X201917Y196283D01*
X202208Y195908D01*
X202625Y195658D01*
X203000Y195575D01*
Y197325D01*
G01Y198633D02*
X200500D01*
Y199467D01*
X200625Y199800D01*
X200792Y200050D01*
X201042Y200258D01*
X201333Y200425D01*
X201750Y200467D01*
X202167Y200425D01*
X202458Y200258D01*
X202708Y200050D01*
X202875Y199800D01*
X203000Y199467D01*
Y198633D01*
G01X202625Y201733D02*
X202833Y201983D01*
X202958Y202275D01*
X203000Y202650D01*
X202917Y203025D01*
X202750Y203317D01*
X202458Y203525D01*
X202125Y203567D01*
X201792Y203483D01*
X201583Y203275D01*
X201417Y202983D01*
X201375Y202692D01*
X201417Y202400D01*
X201583Y202025D01*
X200500Y202150D01*
Y203275D01*
G01X197308Y194267D02*
X197183Y194017D01*
X197100Y193725D01*
Y193392D01*
X197225Y193017D01*
X197433Y192725D01*
X197683Y192517D01*
X198100Y192350D01*
X198475Y192308D01*
X198850Y192392D01*
X199100Y192517D01*
X199350Y192767D01*
X199517Y193058D01*
X199600Y193350D01*
Y193642D01*
X199517Y193933D01*
X199392Y194183D01*
X199225Y194392D01*
G01X197517Y195658D02*
X197267Y195908D01*
X197142Y196200D01*
X197100Y196533D01*
X197183Y196950D01*
X197392Y197242D01*
X197642Y197325D01*
X197892Y197283D01*
X198100Y197117D01*
X198517Y196283D01*
X198808Y195908D01*
X199225Y195658D01*
X199600Y195575D01*
Y197325D01*
G01Y198633D02*
X197100D01*
Y199467D01*
X197225Y199800D01*
X197392Y200050D01*
X197642Y200258D01*
X197933Y200425D01*
X198350Y200467D01*
X198767Y200425D01*
X199058Y200258D01*
X199308Y200050D01*
X199475Y199800D01*
X199600Y199467D01*
Y198633D01*
G01Y203150D02*
X197100D01*
X198892Y201608D01*
Y203692D01*
G01X210008Y177217D02*
X209883Y176967D01*
X209800Y176675D01*
Y176342D01*
X209925Y175967D01*
X210133Y175675D01*
X210383Y175467D01*
X210800Y175300D01*
X211175Y175258D01*
X211550Y175342D01*
X211800Y175467D01*
X212050Y175717D01*
X212217Y176008D01*
X212300Y176300D01*
Y176592D01*
X212217Y176883D01*
X212092Y177133D01*
X211925Y177342D01*
G01X210217Y178608D02*
X209967Y178858D01*
X209842Y179150D01*
X209800Y179483D01*
X209883Y179900D01*
X210092Y180192D01*
X210342Y180275D01*
X210592Y180233D01*
X210800Y180067D01*
X211217Y179233D01*
X211508Y178858D01*
X211925Y178608D01*
X212300Y178525D01*
Y180275D01*
G01Y181583D02*
X209800D01*
Y182417D01*
X209925Y182750D01*
X210092Y183000D01*
X210342Y183208D01*
X210633Y183375D01*
X211050Y183417D01*
X211467Y183375D01*
X211758Y183208D01*
X212008Y183000D01*
X212175Y182750D01*
X212300Y182417D01*
Y181583D01*
G01Y185600D02*
X209800D01*
X210300Y185100D01*
G01X212300D02*
Y186100D01*
G01Y189200D02*
X209800D01*
X211592Y187658D01*
Y189742D01*
G01X206608Y177217D02*
X206483Y176967D01*
X206400Y176675D01*
Y176342D01*
X206525Y175967D01*
X206733Y175675D01*
X206983Y175467D01*
X207400Y175300D01*
X207775Y175258D01*
X208150Y175342D01*
X208400Y175467D01*
X208650Y175717D01*
X208817Y176008D01*
X208900Y176300D01*
Y176592D01*
X208817Y176883D01*
X208692Y177133D01*
X208525Y177342D01*
G01X206817Y178608D02*
X206567Y178858D01*
X206442Y179150D01*
X206400Y179483D01*
X206483Y179900D01*
X206692Y180192D01*
X206942Y180275D01*
X207192Y180233D01*
X207400Y180067D01*
X207817Y179233D01*
X208108Y178858D01*
X208525Y178608D01*
X208900Y178525D01*
Y180275D01*
G01Y181583D02*
X206400D01*
Y182417D01*
X206525Y182750D01*
X206692Y183000D01*
X206942Y183208D01*
X207233Y183375D01*
X207650Y183417D01*
X208067Y183375D01*
X208358Y183208D01*
X208608Y183000D01*
X208775Y182750D01*
X208900Y182417D01*
Y181583D01*
G01Y185600D02*
X206400D01*
X206900Y185100D01*
G01X208900D02*
Y186100D01*
G01X208400Y187783D02*
X208692Y188033D01*
X208858Y188367D01*
X208900Y188742D01*
X208858Y189075D01*
X208650Y189408D01*
X208400Y189617D01*
X208150Y189658D01*
X207858Y189575D01*
X207650Y189283D01*
X207567Y188992D01*
Y188617D01*
G01Y188992D02*
X207442Y189242D01*
X207233Y189450D01*
X206983Y189533D01*
X206733Y189450D01*
X206525Y189242D01*
X206400Y188867D01*
X206442Y188492D01*
X206608Y188117D01*
G01X217008Y177217D02*
X216883Y176967D01*
X216800Y176675D01*
Y176342D01*
X216925Y175967D01*
X217133Y175675D01*
X217383Y175467D01*
X217800Y175300D01*
X218175Y175258D01*
X218550Y175342D01*
X218800Y175467D01*
X219050Y175717D01*
X219217Y176008D01*
X219300Y176300D01*
Y176592D01*
X219217Y176883D01*
X219092Y177133D01*
X218925Y177342D01*
G01X217217Y178608D02*
X216967Y178858D01*
X216842Y179150D01*
X216800Y179483D01*
X216883Y179900D01*
X217092Y180192D01*
X217342Y180275D01*
X217592Y180233D01*
X217800Y180067D01*
X218217Y179233D01*
X218508Y178858D01*
X218925Y178608D01*
X219300Y178525D01*
Y180275D01*
G01Y181583D02*
X216800D01*
Y182417D01*
X216925Y182750D01*
X217092Y183000D01*
X217342Y183208D01*
X217633Y183375D01*
X218050Y183417D01*
X218467Y183375D01*
X218758Y183208D01*
X219008Y183000D01*
X219175Y182750D01*
X219300Y182417D01*
Y181583D01*
G01Y185600D02*
X216800D01*
X217300Y185100D01*
G01X219300D02*
Y186100D01*
G01X218258Y187908D02*
X217967Y188200D01*
X217800Y188450D01*
X217717Y188783D01*
X217800Y189075D01*
X217967Y189283D01*
X218217Y189450D01*
X218508Y189492D01*
X218758Y189450D01*
X219008Y189283D01*
X219217Y189033D01*
X219300Y188742D01*
X219217Y188408D01*
X218967Y188117D01*
X218592Y187950D01*
X218175Y187908D01*
X217633Y187992D01*
X217342Y188117D01*
X217050Y188325D01*
X216842Y188617D01*
X216800Y188908D01*
X216883Y189200D01*
X217092Y189408D01*
G01X213508Y177217D02*
X213383Y176967D01*
X213300Y176675D01*
Y176342D01*
X213425Y175967D01*
X213633Y175675D01*
X213883Y175467D01*
X214300Y175300D01*
X214675Y175258D01*
X215050Y175342D01*
X215300Y175467D01*
X215550Y175717D01*
X215717Y176008D01*
X215800Y176300D01*
Y176592D01*
X215717Y176883D01*
X215592Y177133D01*
X215425Y177342D01*
G01X213717Y178608D02*
X213467Y178858D01*
X213342Y179150D01*
X213300Y179483D01*
X213383Y179900D01*
X213592Y180192D01*
X213842Y180275D01*
X214092Y180233D01*
X214300Y180067D01*
X214717Y179233D01*
X215008Y178858D01*
X215425Y178608D01*
X215800Y178525D01*
Y180275D01*
G01Y181583D02*
X213300D01*
Y182417D01*
X213425Y182750D01*
X213592Y183000D01*
X213842Y183208D01*
X214133Y183375D01*
X214550Y183417D01*
X214967Y183375D01*
X215258Y183208D01*
X215508Y183000D01*
X215675Y182750D01*
X215800Y182417D01*
Y181583D01*
G01Y185600D02*
X213300D01*
X213800Y185100D01*
G01X215800D02*
Y186100D01*
G01X215425Y187783D02*
X215633Y188033D01*
X215758Y188325D01*
X215800Y188700D01*
X215717Y189075D01*
X215550Y189367D01*
X215258Y189575D01*
X214925Y189617D01*
X214592Y189533D01*
X214383Y189325D01*
X214217Y189033D01*
X214175Y188742D01*
X214217Y188450D01*
X214383Y188075D01*
X213300Y188200D01*
Y189325D01*
G01X203308Y177317D02*
X203183Y177067D01*
X203100Y176775D01*
Y176442D01*
X203225Y176067D01*
X203433Y175775D01*
X203683Y175567D01*
X204100Y175400D01*
X204475Y175358D01*
X204850Y175442D01*
X205100Y175567D01*
X205350Y175817D01*
X205517Y176108D01*
X205600Y176400D01*
Y176692D01*
X205517Y176983D01*
X205392Y177233D01*
X205225Y177442D01*
G01X203517Y178708D02*
X203267Y178958D01*
X203142Y179250D01*
X203100Y179583D01*
X203183Y180000D01*
X203392Y180292D01*
X203642Y180375D01*
X203892Y180333D01*
X204100Y180167D01*
X204517Y179333D01*
X204808Y178958D01*
X205225Y178708D01*
X205600Y178625D01*
Y180375D01*
G01Y181683D02*
X203100D01*
Y182517D01*
X203225Y182850D01*
X203392Y183100D01*
X203642Y183308D01*
X203933Y183475D01*
X204350Y183517D01*
X204767Y183475D01*
X205058Y183308D01*
X205308Y183100D01*
X205475Y182850D01*
X205600Y182517D01*
Y181683D01*
G01Y185700D02*
X203100D01*
X203600Y185200D01*
G01X205600D02*
Y186200D01*
G01X203517Y188008D02*
X203267Y188258D01*
X203142Y188550D01*
X203100Y188883D01*
X203183Y189300D01*
X203392Y189592D01*
X203642Y189675D01*
X203892Y189633D01*
X204100Y189467D01*
X204517Y188633D01*
X204808Y188258D01*
X205225Y188008D01*
X205600Y187925D01*
Y189675D01*
G01X210081Y161293D02*
X209956Y161043D01*
X209873Y160751D01*
Y160418D01*
X209998Y160043D01*
X210206Y159751D01*
X210456Y159543D01*
X210873Y159376D01*
X211248Y159334D01*
X211623Y159418D01*
X211873Y159543D01*
X212123Y159793D01*
X212290Y160084D01*
X212373Y160376D01*
Y160668D01*
X212290Y160959D01*
X212165Y161209D01*
X211998Y161418D01*
G01X210290Y162684D02*
X210040Y162934D01*
X209915Y163226D01*
X209873Y163559D01*
X209956Y163976D01*
X210165Y164268D01*
X210415Y164351D01*
X210665Y164309D01*
X210873Y164143D01*
X211290Y163309D01*
X211581Y162934D01*
X211998Y162684D01*
X212373Y162601D01*
Y164351D01*
G01Y165659D02*
X209873D01*
Y166493D01*
X209998Y166826D01*
X210165Y167076D01*
X210415Y167284D01*
X210706Y167451D01*
X211123Y167493D01*
X211540Y167451D01*
X211831Y167284D01*
X212081Y167076D01*
X212248Y166826D01*
X212373Y166493D01*
Y165659D01*
G01X210290Y168884D02*
X210040Y169134D01*
X209915Y169426D01*
X209873Y169759D01*
X209956Y170176D01*
X210165Y170468D01*
X210415Y170551D01*
X210665Y170509D01*
X210873Y170343D01*
X211290Y169509D01*
X211581Y169134D01*
X211998Y168884D01*
X212373Y168801D01*
Y170551D01*
G01Y173276D02*
X209873D01*
X211665Y171734D01*
Y173818D01*
G01X199881Y161293D02*
X199756Y161043D01*
X199673Y160751D01*
Y160418D01*
X199798Y160043D01*
X200006Y159751D01*
X200256Y159543D01*
X200673Y159376D01*
X201048Y159334D01*
X201423Y159418D01*
X201673Y159543D01*
X201923Y159793D01*
X202090Y160084D01*
X202173Y160376D01*
Y160668D01*
X202090Y160959D01*
X201965Y161209D01*
X201798Y161418D01*
G01X200090Y162684D02*
X199840Y162934D01*
X199715Y163226D01*
X199673Y163559D01*
X199756Y163976D01*
X199965Y164268D01*
X200215Y164351D01*
X200465Y164309D01*
X200673Y164143D01*
X201090Y163309D01*
X201381Y162934D01*
X201798Y162684D01*
X202173Y162601D01*
Y164351D01*
G01Y165659D02*
X199673D01*
Y166493D01*
X199798Y166826D01*
X199965Y167076D01*
X200215Y167284D01*
X200506Y167451D01*
X200923Y167493D01*
X201340Y167451D01*
X201631Y167284D01*
X201881Y167076D01*
X202048Y166826D01*
X202173Y166493D01*
Y165659D01*
G01X200090Y168884D02*
X199840Y169134D01*
X199715Y169426D01*
X199673Y169759D01*
X199756Y170176D01*
X199965Y170468D01*
X200215Y170551D01*
X200465Y170509D01*
X200673Y170343D01*
X201090Y169509D01*
X201381Y169134D01*
X201798Y168884D01*
X202173Y168801D01*
Y170551D01*
G01Y172776D02*
X199673D01*
X200173Y172276D01*
G01X202173D02*
Y173276D01*
G01X203281Y161293D02*
X203156Y161043D01*
X203073Y160751D01*
Y160418D01*
X203198Y160043D01*
X203406Y159751D01*
X203656Y159543D01*
X204073Y159376D01*
X204448Y159334D01*
X204823Y159418D01*
X205073Y159543D01*
X205323Y159793D01*
X205490Y160084D01*
X205573Y160376D01*
Y160668D01*
X205490Y160959D01*
X205365Y161209D01*
X205198Y161418D01*
G01X203490Y162684D02*
X203240Y162934D01*
X203115Y163226D01*
X203073Y163559D01*
X203156Y163976D01*
X203365Y164268D01*
X203615Y164351D01*
X203865Y164309D01*
X204073Y164143D01*
X204490Y163309D01*
X204781Y162934D01*
X205198Y162684D01*
X205573Y162601D01*
Y164351D01*
G01Y165659D02*
X203073D01*
Y166493D01*
X203198Y166826D01*
X203365Y167076D01*
X203615Y167284D01*
X203906Y167451D01*
X204323Y167493D01*
X204740Y167451D01*
X205031Y167284D01*
X205281Y167076D01*
X205448Y166826D01*
X205573Y166493D01*
Y165659D01*
G01X203490Y168884D02*
X203240Y169134D01*
X203115Y169426D01*
X203073Y169759D01*
X203156Y170176D01*
X203365Y170468D01*
X203615Y170551D01*
X203865Y170509D01*
X204073Y170343D01*
X204490Y169509D01*
X204781Y169134D01*
X205198Y168884D01*
X205573Y168801D01*
Y170551D01*
G01X203490Y171984D02*
X203240Y172234D01*
X203115Y172526D01*
X203073Y172859D01*
X203156Y173276D01*
X203365Y173568D01*
X203615Y173651D01*
X203865Y173609D01*
X204073Y173443D01*
X204490Y172609D01*
X204781Y172234D01*
X205198Y171984D01*
X205573Y171901D01*
Y173651D01*
G01X193081Y161293D02*
X192956Y161043D01*
X192873Y160751D01*
Y160418D01*
X192998Y160043D01*
X193206Y159751D01*
X193456Y159543D01*
X193873Y159376D01*
X194248Y159334D01*
X194623Y159418D01*
X194873Y159543D01*
X195123Y159793D01*
X195290Y160084D01*
X195373Y160376D01*
Y160668D01*
X195290Y160959D01*
X195165Y161209D01*
X194998Y161418D01*
G01X193290Y162684D02*
X193040Y162934D01*
X192915Y163226D01*
X192873Y163559D01*
X192956Y163976D01*
X193165Y164268D01*
X193415Y164351D01*
X193665Y164309D01*
X193873Y164143D01*
X194290Y163309D01*
X194581Y162934D01*
X194998Y162684D01*
X195373Y162601D01*
Y164351D01*
G01Y165659D02*
X192873D01*
Y166493D01*
X192998Y166826D01*
X193165Y167076D01*
X193415Y167284D01*
X193706Y167451D01*
X194123Y167493D01*
X194540Y167451D01*
X194831Y167284D01*
X195081Y167076D01*
X195248Y166826D01*
X195373Y166493D01*
Y165659D01*
G01Y169676D02*
X192873D01*
X193373Y169176D01*
G01X195373D02*
Y170176D01*
G01X195081Y172068D02*
X195290Y172359D01*
X195373Y172693D01*
X195290Y173026D01*
X195040Y173318D01*
X194665Y173526D01*
X194290Y173609D01*
X193831D01*
X193456Y173526D01*
X193123Y173318D01*
X192956Y173068D01*
X192873Y172776D01*
X192956Y172443D01*
X193123Y172193D01*
X193373Y172026D01*
X193706Y171943D01*
X193998Y172026D01*
X194290Y172234D01*
X194456Y172484D01*
X194498Y172776D01*
X194415Y173109D01*
X194206Y173359D01*
X193831Y173609D01*
G01X196481Y161293D02*
X196356Y161043D01*
X196273Y160751D01*
Y160418D01*
X196398Y160043D01*
X196606Y159751D01*
X196856Y159543D01*
X197273Y159376D01*
X197648Y159334D01*
X198023Y159418D01*
X198273Y159543D01*
X198523Y159793D01*
X198690Y160084D01*
X198773Y160376D01*
Y160668D01*
X198690Y160959D01*
X198565Y161209D01*
X198398Y161418D01*
G01X196690Y162684D02*
X196440Y162934D01*
X196315Y163226D01*
X196273Y163559D01*
X196356Y163976D01*
X196565Y164268D01*
X196815Y164351D01*
X197065Y164309D01*
X197273Y164143D01*
X197690Y163309D01*
X197981Y162934D01*
X198398Y162684D01*
X198773Y162601D01*
Y164351D01*
G01Y165659D02*
X196273D01*
Y166493D01*
X196398Y166826D01*
X196565Y167076D01*
X196815Y167284D01*
X197106Y167451D01*
X197523Y167493D01*
X197940Y167451D01*
X198231Y167284D01*
X198481Y167076D01*
X198648Y166826D01*
X198773Y166493D01*
Y165659D01*
G01X196690Y168884D02*
X196440Y169134D01*
X196315Y169426D01*
X196273Y169759D01*
X196356Y170176D01*
X196565Y170468D01*
X196815Y170551D01*
X197065Y170509D01*
X197273Y170343D01*
X197690Y169509D01*
X197981Y169134D01*
X198398Y168884D01*
X198773Y168801D01*
Y170551D01*
G01X196273Y172776D02*
X196356Y172443D01*
X196565Y172193D01*
X196815Y172026D01*
X197148Y171901D01*
X197523Y171859D01*
X197898Y171901D01*
X198231Y172026D01*
X198481Y172193D01*
X198690Y172443D01*
X198773Y172776D01*
X198690Y173109D01*
X198481Y173359D01*
X198231Y173526D01*
X197898Y173651D01*
X197523Y173693D01*
X197148Y173651D01*
X196815Y173526D01*
X196565Y173359D01*
X196356Y173109D01*
X196273Y172776D01*
G01X206681Y161293D02*
X206556Y161043D01*
X206473Y160751D01*
Y160418D01*
X206598Y160043D01*
X206806Y159751D01*
X207056Y159543D01*
X207473Y159376D01*
X207848Y159334D01*
X208223Y159418D01*
X208473Y159543D01*
X208723Y159793D01*
X208890Y160084D01*
X208973Y160376D01*
Y160668D01*
X208890Y160959D01*
X208765Y161209D01*
X208598Y161418D01*
G01X206890Y162684D02*
X206640Y162934D01*
X206515Y163226D01*
X206473Y163559D01*
X206556Y163976D01*
X206765Y164268D01*
X207015Y164351D01*
X207265Y164309D01*
X207473Y164143D01*
X207890Y163309D01*
X208181Y162934D01*
X208598Y162684D01*
X208973Y162601D01*
Y164351D01*
G01Y165659D02*
X206473D01*
Y166493D01*
X206598Y166826D01*
X206765Y167076D01*
X207015Y167284D01*
X207306Y167451D01*
X207723Y167493D01*
X208140Y167451D01*
X208431Y167284D01*
X208681Y167076D01*
X208848Y166826D01*
X208973Y166493D01*
Y165659D01*
G01X206890Y168884D02*
X206640Y169134D01*
X206515Y169426D01*
X206473Y169759D01*
X206556Y170176D01*
X206765Y170468D01*
X207015Y170551D01*
X207265Y170509D01*
X207473Y170343D01*
X207890Y169509D01*
X208181Y169134D01*
X208598Y168884D01*
X208973Y168801D01*
Y170551D01*
G01X208473Y171859D02*
X208765Y172109D01*
X208931Y172443D01*
X208973Y172818D01*
X208931Y173151D01*
X208723Y173484D01*
X208473Y173693D01*
X208223Y173734D01*
X207931Y173651D01*
X207723Y173359D01*
X207640Y173068D01*
Y172693D01*
G01Y173068D02*
X207515Y173318D01*
X207306Y173526D01*
X207056Y173609D01*
X206806Y173526D01*
X206598Y173318D01*
X206473Y172943D01*
X206515Y172568D01*
X206681Y172193D01*
G01X213481Y161293D02*
X213356Y161043D01*
X213273Y160751D01*
Y160418D01*
X213398Y160043D01*
X213606Y159751D01*
X213856Y159543D01*
X214273Y159376D01*
X214648Y159334D01*
X215023Y159418D01*
X215273Y159543D01*
X215523Y159793D01*
X215690Y160084D01*
X215773Y160376D01*
Y160668D01*
X215690Y160959D01*
X215565Y161209D01*
X215398Y161418D01*
G01X213690Y162684D02*
X213440Y162934D01*
X213315Y163226D01*
X213273Y163559D01*
X213356Y163976D01*
X213565Y164268D01*
X213815Y164351D01*
X214065Y164309D01*
X214273Y164143D01*
X214690Y163309D01*
X214981Y162934D01*
X215398Y162684D01*
X215773Y162601D01*
Y164351D01*
G01Y165659D02*
X213273D01*
Y166493D01*
X213398Y166826D01*
X213565Y167076D01*
X213815Y167284D01*
X214106Y167451D01*
X214523Y167493D01*
X214940Y167451D01*
X215231Y167284D01*
X215481Y167076D01*
X215648Y166826D01*
X215773Y166493D01*
Y165659D01*
G01X213690Y168884D02*
X213440Y169134D01*
X213315Y169426D01*
X213273Y169759D01*
X213356Y170176D01*
X213565Y170468D01*
X213815Y170551D01*
X214065Y170509D01*
X214273Y170343D01*
X214690Y169509D01*
X214981Y169134D01*
X215398Y168884D01*
X215773Y168801D01*
Y170551D01*
G01X215398Y171859D02*
X215606Y172109D01*
X215731Y172401D01*
X215773Y172776D01*
X215690Y173151D01*
X215523Y173443D01*
X215231Y173651D01*
X214898Y173693D01*
X214565Y173609D01*
X214356Y173401D01*
X214190Y173109D01*
X214148Y172818D01*
X214190Y172526D01*
X214356Y172151D01*
X213273Y172276D01*
Y173401D01*
G01X216881Y161293D02*
X216756Y161043D01*
X216673Y160751D01*
Y160418D01*
X216798Y160043D01*
X217006Y159751D01*
X217256Y159543D01*
X217673Y159376D01*
X218048Y159334D01*
X218423Y159418D01*
X218673Y159543D01*
X218923Y159793D01*
X219090Y160084D01*
X219173Y160376D01*
Y160668D01*
X219090Y160959D01*
X218965Y161209D01*
X218798Y161418D01*
G01X217090Y162684D02*
X216840Y162934D01*
X216715Y163226D01*
X216673Y163559D01*
X216756Y163976D01*
X216965Y164268D01*
X217215Y164351D01*
X217465Y164309D01*
X217673Y164143D01*
X218090Y163309D01*
X218381Y162934D01*
X218798Y162684D01*
X219173Y162601D01*
Y164351D01*
G01Y165659D02*
X216673D01*
Y166493D01*
X216798Y166826D01*
X216965Y167076D01*
X217215Y167284D01*
X217506Y167451D01*
X217923Y167493D01*
X218340Y167451D01*
X218631Y167284D01*
X218881Y167076D01*
X219048Y166826D01*
X219173Y166493D01*
Y165659D01*
G01X217090Y168884D02*
X216840Y169134D01*
X216715Y169426D01*
X216673Y169759D01*
X216756Y170176D01*
X216965Y170468D01*
X217215Y170551D01*
X217465Y170509D01*
X217673Y170343D01*
X218090Y169509D01*
X218381Y169134D01*
X218798Y168884D01*
X219173Y168801D01*
Y170551D01*
G01X218131Y171984D02*
X217840Y172276D01*
X217673Y172526D01*
X217590Y172859D01*
X217673Y173151D01*
X217840Y173359D01*
X218090Y173526D01*
X218381Y173568D01*
X218631Y173526D01*
X218881Y173359D01*
X219090Y173109D01*
X219173Y172818D01*
X219090Y172484D01*
X218840Y172193D01*
X218465Y172026D01*
X218048Y171984D01*
X217506Y172068D01*
X217215Y172193D01*
X216923Y172401D01*
X216715Y172693D01*
X216673Y172984D01*
X216756Y173276D01*
X216965Y173484D01*
G01X223708Y177117D02*
X223583Y176867D01*
X223500Y176575D01*
Y176242D01*
X223625Y175867D01*
X223833Y175575D01*
X224083Y175367D01*
X224500Y175200D01*
X224875Y175158D01*
X225250Y175242D01*
X225500Y175367D01*
X225750Y175617D01*
X225917Y175908D01*
X226000Y176200D01*
Y176492D01*
X225917Y176783D01*
X225792Y177033D01*
X225625Y177242D01*
G01X225500Y178383D02*
X225792Y178633D01*
X225958Y178967D01*
X226000Y179342D01*
X225958Y179675D01*
X225750Y180008D01*
X225500Y180217D01*
X225250Y180258D01*
X224958Y180175D01*
X224750Y179883D01*
X224667Y179592D01*
Y179217D01*
G01Y179592D02*
X224542Y179842D01*
X224333Y180050D01*
X224083Y180133D01*
X223833Y180050D01*
X223625Y179842D01*
X223500Y179467D01*
X223542Y179092D01*
X223708Y178717D01*
G01X223500Y181150D02*
X226000Y181733D01*
X223500Y182400D01*
X226000Y183067D01*
X223500Y183650D01*
G01X225500Y184583D02*
X225792Y184833D01*
X225958Y185167D01*
X226000Y185542D01*
X225958Y185875D01*
X225750Y186208D01*
X225500Y186417D01*
X225250Y186458D01*
X224958Y186375D01*
X224750Y186083D01*
X224667Y185792D01*
Y185417D01*
G01Y185792D02*
X224542Y186042D01*
X224333Y186250D01*
X224083Y186333D01*
X223833Y186250D01*
X223625Y186042D01*
X223500Y185667D01*
X223542Y185292D01*
X223708Y184917D01*
G01X230608Y177067D02*
X230483Y176817D01*
X230400Y176525D01*
Y176192D01*
X230525Y175817D01*
X230733Y175525D01*
X230983Y175317D01*
X231400Y175150D01*
X231775Y175108D01*
X232150Y175192D01*
X232400Y175317D01*
X232650Y175567D01*
X232817Y175858D01*
X232900Y176150D01*
Y176442D01*
X232817Y176733D01*
X232692Y176983D01*
X232525Y177192D01*
G01X232400Y178333D02*
X232692Y178583D01*
X232858Y178917D01*
X232900Y179292D01*
X232858Y179625D01*
X232650Y179958D01*
X232400Y180167D01*
X232150Y180208D01*
X231858Y180125D01*
X231650Y179833D01*
X231567Y179542D01*
Y179167D01*
G01Y179542D02*
X231442Y179792D01*
X231233Y180000D01*
X230983Y180083D01*
X230733Y180000D01*
X230525Y179792D01*
X230400Y179417D01*
X230442Y179042D01*
X230608Y178667D01*
G01X230400Y181100D02*
X232900Y181683D01*
X230400Y182350D01*
X232900Y183017D01*
X230400Y183600D01*
G01X232900Y185950D02*
X230400D01*
X232192Y184408D01*
Y186492D01*
G01X213067Y209292D02*
X212817Y209417D01*
X212525Y209500D01*
X212192D01*
X211817Y209375D01*
X211525Y209167D01*
X211317Y208917D01*
X211150Y208500D01*
X211108Y208125D01*
X211192Y207750D01*
X211317Y207500D01*
X211567Y207250D01*
X211858Y207083D01*
X212150Y207000D01*
X212442D01*
X212733Y207083D01*
X212983Y207208D01*
X213192Y207375D01*
G01X215250Y207000D02*
Y209500D01*
X214750Y209000D01*
G01Y207000D02*
X215750D01*
G01X219183D02*
X217517D01*
Y209500D01*
X219183D01*
G01X218517Y208292D02*
X217517D01*
G01X220658Y209083D02*
X220908Y209333D01*
X221200Y209458D01*
X221533Y209500D01*
X221950Y209417D01*
X222242Y209208D01*
X222325Y208958D01*
X222283Y208708D01*
X222117Y208500D01*
X221283Y208083D01*
X220908Y207792D01*
X220658Y207375D01*
X220575Y207000D01*
X222325D01*
G01X191896Y218466D02*
Y215966D01*
X193562D01*
G01X195829D02*
Y218466D01*
X195329Y217966D01*
G01Y215966D02*
X196329D01*
G01X199762D02*
X198096D01*
Y218466D01*
X199762D01*
G01X199096Y217258D02*
X198096D01*
G01X202029Y215966D02*
Y218466D01*
X201529Y217966D01*
G01Y215966D02*
X202529D01*
G01X210199Y318200D02*
X210200Y318199D01*
Y219379D01*
G01X215887Y242780D02*
Y245280D01*
X216928D01*
X217262Y245155D01*
X217470Y244988D01*
X217553Y244655D01*
X217470Y244322D01*
X217220Y244113D01*
X216928Y243988D01*
X215887D01*
G01X216928D02*
X217553Y242780D01*
G01X219820D02*
Y245280D01*
X219320Y244780D01*
G01Y242780D02*
X220320D01*
G01X222003D02*
Y245280D01*
X222837D01*
X223170Y245155D01*
X223420Y244988D01*
X223628Y244738D01*
X223795Y244447D01*
X223837Y244030D01*
X223795Y243613D01*
X223628Y243322D01*
X223420Y243072D01*
X223170Y242905D01*
X222837Y242780D01*
X222003D01*
G01X225103Y243155D02*
X225353Y242947D01*
X225645Y242822D01*
X226020Y242780D01*
X226395Y242863D01*
X226687Y243030D01*
X226895Y243322D01*
X226937Y243655D01*
X226853Y243988D01*
X226645Y244197D01*
X226353Y244363D01*
X226062Y244405D01*
X225770Y244363D01*
X225395Y244197D01*
X225520Y245280D01*
X226645D01*
G01X228203Y243155D02*
X228453Y242947D01*
X228745Y242822D01*
X229120Y242780D01*
X229495Y242863D01*
X229787Y243030D01*
X229995Y243322D01*
X230037Y243655D01*
X229953Y243988D01*
X229745Y244197D01*
X229453Y244363D01*
X229162Y244405D01*
X228870Y244363D01*
X228495Y244197D01*
X228620Y245280D01*
X229745D01*
G01X213382Y277414D02*
Y279914D01*
X214423D01*
X214757Y279789D01*
X214965Y279622D01*
X215048Y279289D01*
X214965Y278956D01*
X214715Y278747D01*
X214423Y278622D01*
X213382D01*
G01X214423D02*
X215048Y277414D01*
G01X217315D02*
Y279914D01*
X216815Y279414D01*
G01Y277414D02*
X217815D01*
G01X219498D02*
Y279914D01*
X220332D01*
X220665Y279789D01*
X220915Y279622D01*
X221123Y279372D01*
X221290Y279081D01*
X221332Y278664D01*
X221290Y278247D01*
X221123Y277956D01*
X220915Y277706D01*
X220665Y277539D01*
X220332Y277414D01*
X219498D01*
G01X222598Y277789D02*
X222848Y277581D01*
X223140Y277456D01*
X223515Y277414D01*
X223890Y277497D01*
X224182Y277664D01*
X224390Y277956D01*
X224432Y278289D01*
X224348Y278622D01*
X224140Y278831D01*
X223848Y278997D01*
X223557Y279039D01*
X223265Y278997D01*
X222890Y278831D01*
X223015Y279914D01*
X224140D01*
G01X225823Y279497D02*
X226073Y279747D01*
X226365Y279872D01*
X226698Y279914D01*
X227115Y279831D01*
X227407Y279622D01*
X227490Y279372D01*
X227448Y279122D01*
X227282Y278914D01*
X226448Y278497D01*
X226073Y278206D01*
X225823Y277789D01*
X225740Y277414D01*
X227490D01*
G01X212867Y263527D02*
Y266027D01*
X213908D01*
X214242Y265902D01*
X214450Y265735D01*
X214533Y265402D01*
X214450Y265069D01*
X214200Y264860D01*
X213908Y264735D01*
X212867D01*
G01X213908D02*
X214533Y263527D01*
G01X216800D02*
Y266027D01*
X216300Y265527D01*
G01Y263527D02*
X217300D01*
G01X218983D02*
Y266027D01*
X219817D01*
X220150Y265902D01*
X220400Y265735D01*
X220608Y265485D01*
X220775Y265194D01*
X220817Y264777D01*
X220775Y264360D01*
X220608Y264069D01*
X220400Y263819D01*
X220150Y263652D01*
X219817Y263527D01*
X218983D01*
G01X222083Y263902D02*
X222333Y263694D01*
X222625Y263569D01*
X223000Y263527D01*
X223375Y263610D01*
X223667Y263777D01*
X223875Y264069D01*
X223917Y264402D01*
X223833Y264735D01*
X223625Y264944D01*
X223333Y265110D01*
X223042Y265152D01*
X222750Y265110D01*
X222375Y264944D01*
X222500Y266027D01*
X223625D01*
G01X226600Y263527D02*
Y266027D01*
X225058Y264235D01*
X227142D01*
G01X216876Y248409D02*
X214376D01*
Y249450D01*
X214501Y249784D01*
X214668Y249992D01*
X215001Y250075D01*
X215334Y249992D01*
X215543Y249742D01*
X215668Y249450D01*
Y248409D01*
G01Y249450D02*
X216876Y250075D01*
G01Y252342D02*
X214376D01*
X214876Y251842D01*
G01X216876D02*
Y252842D01*
G01Y254525D02*
X214376D01*
Y255359D01*
X214501Y255692D01*
X214668Y255942D01*
X214918Y256150D01*
X215209Y256317D01*
X215626Y256359D01*
X216043Y256317D01*
X216334Y256150D01*
X216584Y255942D01*
X216751Y255692D01*
X216876Y255359D01*
Y254525D01*
G01X216376Y257625D02*
X216668Y257875D01*
X216834Y258209D01*
X216876Y258584D01*
X216834Y258917D01*
X216626Y259250D01*
X216376Y259459D01*
X216126Y259500D01*
X215834Y259417D01*
X215626Y259125D01*
X215543Y258834D01*
Y258459D01*
G01Y258834D02*
X215418Y259084D01*
X215209Y259292D01*
X214959Y259375D01*
X214709Y259292D01*
X214501Y259084D01*
X214376Y258709D01*
X214418Y258334D01*
X214584Y257959D01*
G01X216501Y260725D02*
X216709Y260975D01*
X216834Y261267D01*
X216876Y261642D01*
X216793Y262017D01*
X216626Y262309D01*
X216334Y262517D01*
X216001Y262559D01*
X215668Y262475D01*
X215459Y262267D01*
X215293Y261975D01*
X215251Y261684D01*
X215293Y261392D01*
X215459Y261017D01*
X214376Y261142D01*
Y262267D01*
G01X213737Y231080D02*
Y233580D01*
X214778D01*
X215112Y233455D01*
X215320Y233288D01*
X215403Y232955D01*
X215320Y232622D01*
X215070Y232413D01*
X214778Y232288D01*
X213737D01*
G01X214778D02*
X215403Y231080D01*
G01X217670D02*
Y233580D01*
X217170Y233080D01*
G01Y231080D02*
X218170D01*
G01X219520Y233580D02*
X220103Y231080D01*
X220770Y233580D01*
X221437Y231080D01*
X222020Y233580D01*
G01X223078Y233163D02*
X223328Y233413D01*
X223620Y233538D01*
X223953Y233580D01*
X224370Y233497D01*
X224662Y233288D01*
X224745Y233038D01*
X224703Y232788D01*
X224537Y232580D01*
X223703Y232163D01*
X223328Y231872D01*
X223078Y231455D01*
X222995Y231080D01*
X224745D01*
G01X226970D02*
Y233580D01*
X226470Y233080D01*
G01Y231080D02*
X227470D01*
G01X213737Y234480D02*
Y236980D01*
X214778D01*
X215112Y236855D01*
X215320Y236688D01*
X215403Y236355D01*
X215320Y236022D01*
X215070Y235813D01*
X214778Y235688D01*
X213737D01*
G01X214778D02*
X215403Y234480D01*
G01X217670D02*
Y236980D01*
X217170Y236480D01*
G01Y234480D02*
X218170D01*
G01X219520Y236980D02*
X220103Y234480D01*
X220770Y236980D01*
X221437Y234480D01*
X222020Y236980D01*
G01X223078Y236563D02*
X223328Y236813D01*
X223620Y236938D01*
X223953Y236980D01*
X224370Y236897D01*
X224662Y236688D01*
X224745Y236438D01*
X224703Y236188D01*
X224537Y235980D01*
X223703Y235563D01*
X223328Y235272D01*
X223078Y234855D01*
X222995Y234480D01*
X224745D01*
G01X226970Y236980D02*
X226637Y236897D01*
X226387Y236688D01*
X226220Y236438D01*
X226095Y236105D01*
X226053Y235730D01*
X226095Y235355D01*
X226220Y235022D01*
X226387Y234772D01*
X226637Y234563D01*
X226970Y234480D01*
X227303Y234563D01*
X227553Y234772D01*
X227720Y235022D01*
X227845Y235355D01*
X227887Y235730D01*
X227845Y236105D01*
X227720Y236438D01*
X227553Y236688D01*
X227303Y236897D01*
X226970Y236980D01*
G01X213737Y227680D02*
Y230180D01*
X214778D01*
X215112Y230055D01*
X215320Y229888D01*
X215403Y229555D01*
X215320Y229222D01*
X215070Y229013D01*
X214778Y228888D01*
X213737D01*
G01X214778D02*
X215403Y227680D01*
G01X217670D02*
Y230180D01*
X217170Y229680D01*
G01Y227680D02*
X218170D01*
G01X219853D02*
Y230180D01*
X220687D01*
X221020Y230055D01*
X221270Y229888D01*
X221478Y229638D01*
X221645Y229347D01*
X221687Y228930D01*
X221645Y228513D01*
X221478Y228222D01*
X221270Y227972D01*
X221020Y227805D01*
X220687Y227680D01*
X219853D01*
G01X224370D02*
Y230180D01*
X222828Y228388D01*
X224912D01*
G01X226970Y227680D02*
X227262Y227722D01*
X227595Y227847D01*
X227803Y228055D01*
X227887Y228347D01*
X227803Y228638D01*
X227553Y228888D01*
X227178Y229013D01*
X226762D01*
X226512Y229097D01*
X226303Y229305D01*
X226220Y229597D01*
X226345Y229888D01*
X226637Y230097D01*
X226970Y230180D01*
X227303Y230097D01*
X227595Y229888D01*
X227720Y229597D01*
X227637Y229305D01*
X227428Y229097D01*
X227178Y229013D01*
X226762D01*
X226387Y228888D01*
X226137Y228638D01*
X226053Y228347D01*
X226137Y228055D01*
X226345Y227847D01*
X226678Y227722D01*
X226970Y227680D01*
G01X218907Y246557D02*
Y249057D01*
X219948D01*
X220282Y248932D01*
X220490Y248765D01*
X220573Y248432D01*
X220490Y248099D01*
X220240Y247890D01*
X219948Y247765D01*
X218907D01*
G01X219948D02*
X220573Y246557D01*
G01X222840Y249057D02*
Y246557D01*
G01X221882Y249057D02*
X223798D01*
G01X225940Y246557D02*
Y249057D01*
X225440Y248557D01*
G01Y246557D02*
X226440D01*
G01X229040D02*
Y249057D01*
X228540Y248557D01*
G01Y246557D02*
X229540D01*
G01X213382Y266914D02*
Y269414D01*
X214423D01*
X214757Y269289D01*
X214965Y269122D01*
X215048Y268789D01*
X214965Y268456D01*
X214715Y268247D01*
X214423Y268122D01*
X213382D01*
G01X214423D02*
X215048Y266914D01*
G01X217315Y269414D02*
Y266914D01*
G01X216357Y269414D02*
X218273D01*
G01X220415Y266914D02*
Y269414D01*
X219915Y268914D01*
G01Y266914D02*
X220915D01*
G01X224015D02*
Y269414D01*
X222473Y267622D01*
X224557D01*
G01X200032Y235287D02*
X199907Y235037D01*
X199824Y234745D01*
Y234412D01*
X199949Y234037D01*
X200157Y233745D01*
X200407Y233537D01*
X200824Y233370D01*
X201199Y233328D01*
X201574Y233412D01*
X201824Y233537D01*
X202074Y233787D01*
X202241Y234078D01*
X202324Y234370D01*
Y234662D01*
X202241Y234953D01*
X202116Y235203D01*
X201949Y235412D01*
G01X202324Y237470D02*
X199824D01*
X200324Y236970D01*
G01X202324D02*
Y237970D01*
G01Y241403D02*
Y239737D01*
X199824D01*
Y241403D01*
G01X201032Y240737D02*
Y239737D01*
G01X201824Y242753D02*
X202116Y243003D01*
X202282Y243337D01*
X202324Y243712D01*
X202282Y244045D01*
X202074Y244378D01*
X201824Y244587D01*
X201574Y244628D01*
X201282Y244545D01*
X201074Y244253D01*
X200991Y243962D01*
Y243587D01*
G01Y243962D02*
X200866Y244212D01*
X200657Y244420D01*
X200407Y244503D01*
X200157Y244420D01*
X199949Y244212D01*
X199824Y243837D01*
X199866Y243462D01*
X200032Y243087D01*
G01X197831Y222550D02*
X197706Y222300D01*
X197623Y222008D01*
Y221675D01*
X197748Y221300D01*
X197956Y221008D01*
X198206Y220800D01*
X198623Y220633D01*
X198998Y220591D01*
X199373Y220675D01*
X199623Y220800D01*
X199873Y221050D01*
X200040Y221341D01*
X200123Y221633D01*
Y221925D01*
X200040Y222216D01*
X199915Y222466D01*
X199748Y222675D01*
G01X200123Y224733D02*
X197623D01*
X198123Y224233D01*
G01X200123D02*
Y225233D01*
G01Y228666D02*
Y227000D01*
X197623D01*
Y228666D01*
G01X198831Y228000D02*
Y227000D01*
G01X199831Y230225D02*
X200040Y230516D01*
X200123Y230850D01*
X200040Y231183D01*
X199790Y231475D01*
X199415Y231683D01*
X199040Y231766D01*
X198581D01*
X198206Y231683D01*
X197873Y231475D01*
X197706Y231225D01*
X197623Y230933D01*
X197706Y230600D01*
X197873Y230350D01*
X198123Y230183D01*
X198456Y230100D01*
X198748Y230183D01*
X199040Y230391D01*
X199206Y230641D01*
X199248Y230933D01*
X199165Y231266D01*
X198956Y231516D01*
X198581Y231766D01*
G01X205685Y270859D02*
X205560Y270609D01*
X205477Y270317D01*
Y269984D01*
X205602Y269609D01*
X205810Y269317D01*
X206060Y269109D01*
X206477Y268942D01*
X206852Y268900D01*
X207227Y268984D01*
X207477Y269109D01*
X207727Y269359D01*
X207894Y269650D01*
X207977Y269942D01*
Y270234D01*
X207894Y270525D01*
X207769Y270775D01*
X207602Y270984D01*
G01X207977Y273042D02*
X205477D01*
X205977Y272542D01*
G01X207977D02*
Y273542D01*
G01Y275225D02*
X205477D01*
Y276059D01*
X205602Y276392D01*
X205769Y276642D01*
X206019Y276850D01*
X206310Y277017D01*
X206727Y277059D01*
X207144Y277017D01*
X207435Y276850D01*
X207685Y276642D01*
X207852Y276392D01*
X207977Y276059D01*
Y275225D01*
G01X205894Y278450D02*
X205644Y278700D01*
X205519Y278992D01*
X205477Y279325D01*
X205560Y279742D01*
X205769Y280034D01*
X206019Y280117D01*
X206269Y280075D01*
X206477Y279909D01*
X206894Y279075D01*
X207185Y278700D01*
X207602Y278450D01*
X207977Y278367D01*
Y280117D01*
G01Y282842D02*
X205477D01*
X207269Y281300D01*
Y283384D01*
G01X220324Y253009D02*
X220074Y253134D01*
X219782Y253217D01*
X219449D01*
X219074Y253092D01*
X218782Y252884D01*
X218574Y252634D01*
X218407Y252217D01*
X218365Y251842D01*
X218449Y251467D01*
X218574Y251217D01*
X218824Y250967D01*
X219115Y250800D01*
X219407Y250717D01*
X219699D01*
X219990Y250800D01*
X220240Y250925D01*
X220449Y251092D01*
G01X222507Y250717D02*
Y253217D01*
X222007Y252717D01*
G01Y250717D02*
X223007D01*
G01X224690D02*
Y253217D01*
X225524D01*
X225857Y253092D01*
X226107Y252925D01*
X226315Y252675D01*
X226482Y252384D01*
X226524Y251967D01*
X226482Y251550D01*
X226315Y251259D01*
X226107Y251009D01*
X225857Y250842D01*
X225524Y250717D01*
X224690D01*
G01X227915Y252800D02*
X228165Y253050D01*
X228457Y253175D01*
X228790Y253217D01*
X229207Y253134D01*
X229499Y252925D01*
X229582Y252675D01*
X229540Y252425D01*
X229374Y252217D01*
X228540Y251800D01*
X228165Y251509D01*
X227915Y251092D01*
X227832Y250717D01*
X229582D01*
G01X231807Y253217D02*
X231474Y253134D01*
X231224Y252925D01*
X231057Y252675D01*
X230932Y252342D01*
X230890Y251967D01*
X230932Y251592D01*
X231057Y251259D01*
X231224Y251009D01*
X231474Y250800D01*
X231807Y250717D01*
X232140Y250800D01*
X232390Y251009D01*
X232557Y251259D01*
X232682Y251592D01*
X232724Y251967D01*
X232682Y252342D01*
X232557Y252675D01*
X232390Y252925D01*
X232140Y253134D01*
X231807Y253217D01*
G01X220027Y257789D02*
X219777Y257914D01*
X219485Y257997D01*
X219152D01*
X218777Y257872D01*
X218485Y257664D01*
X218277Y257414D01*
X218110Y256997D01*
X218068Y256622D01*
X218152Y256247D01*
X218277Y255997D01*
X218527Y255747D01*
X218818Y255580D01*
X219110Y255497D01*
X219402D01*
X219693Y255580D01*
X219943Y255705D01*
X220152Y255872D01*
G01X222210Y255497D02*
Y257997D01*
X221710Y257497D01*
G01Y255497D02*
X222710D01*
G01X224393D02*
Y257997D01*
X225227D01*
X225560Y257872D01*
X225810Y257705D01*
X226018Y257455D01*
X226185Y257164D01*
X226227Y256747D01*
X226185Y256330D01*
X226018Y256039D01*
X225810Y255789D01*
X225560Y255622D01*
X225227Y255497D01*
X224393D01*
G01X227618Y257580D02*
X227868Y257830D01*
X228160Y257955D01*
X228493Y257997D01*
X228910Y257914D01*
X229202Y257705D01*
X229285Y257455D01*
X229243Y257205D01*
X229077Y256997D01*
X228243Y256580D01*
X227868Y256289D01*
X227618Y255872D01*
X227535Y255497D01*
X229285D01*
G01X230593Y255997D02*
X230843Y255705D01*
X231177Y255539D01*
X231552Y255497D01*
X231885Y255539D01*
X232218Y255747D01*
X232427Y255997D01*
X232468Y256247D01*
X232385Y256539D01*
X232093Y256747D01*
X231802Y256830D01*
X231427D01*
G01X231802D02*
X232052Y256955D01*
X232260Y257164D01*
X232343Y257414D01*
X232260Y257664D01*
X232052Y257872D01*
X231677Y257997D01*
X231302Y257955D01*
X230927Y257789D01*
G01X215132Y276299D02*
X214882Y276424D01*
X214590Y276507D01*
X214257D01*
X213882Y276382D01*
X213590Y276174D01*
X213382Y275924D01*
X213215Y275507D01*
X213173Y275132D01*
X213257Y274757D01*
X213382Y274507D01*
X213632Y274257D01*
X213923Y274090D01*
X214215Y274007D01*
X214507D01*
X214798Y274090D01*
X215048Y274215D01*
X215257Y274382D01*
G01X217315Y274007D02*
Y276507D01*
X216815Y276007D01*
G01Y274007D02*
X217815D01*
G01X219498D02*
Y276507D01*
X220332D01*
X220665Y276382D01*
X220915Y276215D01*
X221123Y275965D01*
X221290Y275674D01*
X221332Y275257D01*
X221290Y274840D01*
X221123Y274549D01*
X220915Y274299D01*
X220665Y274132D01*
X220332Y274007D01*
X219498D01*
G01X223515D02*
Y276507D01*
X223015Y276007D01*
G01Y274007D02*
X224015D01*
G01X225823Y276090D02*
X226073Y276340D01*
X226365Y276465D01*
X226698Y276507D01*
X227115Y276424D01*
X227407Y276215D01*
X227490Y275965D01*
X227448Y275715D01*
X227282Y275507D01*
X226448Y275090D01*
X226073Y274799D01*
X225823Y274382D01*
X225740Y274007D01*
X227490D01*
G01X215132Y272706D02*
X214882Y272831D01*
X214590Y272914D01*
X214257D01*
X213882Y272789D01*
X213590Y272581D01*
X213382Y272331D01*
X213215Y271914D01*
X213173Y271539D01*
X213257Y271164D01*
X213382Y270914D01*
X213632Y270664D01*
X213923Y270497D01*
X214215Y270414D01*
X214507D01*
X214798Y270497D01*
X215048Y270622D01*
X215257Y270789D01*
G01X217315Y270414D02*
Y272914D01*
X216815Y272414D01*
G01Y270414D02*
X217815D01*
G01X219498D02*
Y272914D01*
X220332D01*
X220665Y272789D01*
X220915Y272622D01*
X221123Y272372D01*
X221290Y272081D01*
X221332Y271664D01*
X221290Y271247D01*
X221123Y270956D01*
X220915Y270706D01*
X220665Y270539D01*
X220332Y270414D01*
X219498D01*
G01X223515D02*
Y272914D01*
X223015Y272414D01*
G01Y270414D02*
X224015D01*
G01X226615Y272914D02*
X226282Y272831D01*
X226032Y272622D01*
X225865Y272372D01*
X225740Y272039D01*
X225698Y271664D01*
X225740Y271289D01*
X225865Y270956D01*
X226032Y270706D01*
X226282Y270497D01*
X226615Y270414D01*
X226948Y270497D01*
X227198Y270706D01*
X227365Y270956D01*
X227490Y271289D01*
X227532Y271664D01*
X227490Y272039D01*
X227365Y272372D01*
X227198Y272622D01*
X226948Y272831D01*
X226615Y272914D01*
G01X219417Y222092D02*
X219167Y222217D01*
X218875Y222300D01*
X218542D01*
X218167Y222175D01*
X217875Y221967D01*
X217667Y221717D01*
X217500Y221300D01*
X217458Y220925D01*
X217542Y220550D01*
X217667Y220300D01*
X217917Y220050D01*
X218208Y219883D01*
X218500Y219800D01*
X218792D01*
X219083Y219883D01*
X219333Y220008D01*
X219542Y220175D01*
G01X221600Y219800D02*
Y222300D01*
X221100Y221800D01*
G01Y219800D02*
X222100D01*
G01X223783D02*
Y222300D01*
X224617D01*
X224950Y222175D01*
X225200Y222008D01*
X225408Y221758D01*
X225575Y221467D01*
X225617Y221050D01*
X225575Y220633D01*
X225408Y220342D01*
X225200Y220092D01*
X224950Y219925D01*
X224617Y219800D01*
X223783D01*
G01X226883Y220300D02*
X227133Y220008D01*
X227467Y219842D01*
X227842Y219800D01*
X228175Y219842D01*
X228508Y220050D01*
X228717Y220300D01*
X228758Y220550D01*
X228675Y220842D01*
X228383Y221050D01*
X228092Y221133D01*
X227717D01*
G01X228092D02*
X228342Y221258D01*
X228550Y221467D01*
X228633Y221717D01*
X228550Y221967D01*
X228342Y222175D01*
X227967Y222300D01*
X227592Y222258D01*
X227217Y222092D01*
G01X230108Y220842D02*
X230400Y221133D01*
X230650Y221300D01*
X230983Y221383D01*
X231275Y221300D01*
X231483Y221133D01*
X231650Y220883D01*
X231692Y220592D01*
X231650Y220342D01*
X231483Y220092D01*
X231233Y219883D01*
X230942Y219800D01*
X230608Y219883D01*
X230317Y220133D01*
X230150Y220508D01*
X230108Y220925D01*
X230192Y221467D01*
X230317Y221758D01*
X230525Y222050D01*
X230817Y222258D01*
X231108Y222300D01*
X231400Y222217D01*
X231608Y222008D01*
G01X219417Y225785D02*
X219167Y225910D01*
X218875Y225993D01*
X218542D01*
X218167Y225868D01*
X217875Y225660D01*
X217667Y225410D01*
X217500Y224993D01*
X217458Y224618D01*
X217542Y224243D01*
X217667Y223993D01*
X217917Y223743D01*
X218208Y223576D01*
X218500Y223493D01*
X218792D01*
X219083Y223576D01*
X219333Y223701D01*
X219542Y223868D01*
G01X221600Y223493D02*
Y225993D01*
X221100Y225493D01*
G01Y223493D02*
X222100D01*
G01X223783D02*
Y225993D01*
X224617D01*
X224950Y225868D01*
X225200Y225701D01*
X225408Y225451D01*
X225575Y225160D01*
X225617Y224743D01*
X225575Y224326D01*
X225408Y224035D01*
X225200Y223785D01*
X224950Y223618D01*
X224617Y223493D01*
X223783D01*
G01X226883Y223993D02*
X227133Y223701D01*
X227467Y223535D01*
X227842Y223493D01*
X228175Y223535D01*
X228508Y223743D01*
X228717Y223993D01*
X228758Y224243D01*
X228675Y224535D01*
X228383Y224743D01*
X228092Y224826D01*
X227717D01*
G01X228092D02*
X228342Y224951D01*
X228550Y225160D01*
X228633Y225410D01*
X228550Y225660D01*
X228342Y225868D01*
X227967Y225993D01*
X227592Y225951D01*
X227217Y225785D01*
G01X229983Y223868D02*
X230233Y223660D01*
X230525Y223535D01*
X230900Y223493D01*
X231275Y223576D01*
X231567Y223743D01*
X231775Y224035D01*
X231817Y224368D01*
X231733Y224701D01*
X231525Y224910D01*
X231233Y225076D01*
X230942Y225118D01*
X230650Y225076D01*
X230275Y224910D01*
X230400Y225993D01*
X231525D01*
G01X211142Y245117D02*
X211017Y244867D01*
X210934Y244575D01*
Y244242D01*
X211059Y243867D01*
X211267Y243575D01*
X211517Y243367D01*
X211934Y243200D01*
X212309Y243158D01*
X212684Y243242D01*
X212934Y243367D01*
X213184Y243617D01*
X213351Y243908D01*
X213434Y244200D01*
Y244492D01*
X213351Y244783D01*
X213226Y245033D01*
X213059Y245242D01*
G01X213434Y247300D02*
X210934D01*
X211434Y246800D01*
G01X213434D02*
Y247800D01*
G01Y249483D02*
X210934D01*
Y250317D01*
X211059Y250650D01*
X211226Y250900D01*
X211476Y251108D01*
X211767Y251275D01*
X212184Y251317D01*
X212601Y251275D01*
X212892Y251108D01*
X213142Y250900D01*
X213309Y250650D01*
X213434Y250317D01*
Y249483D01*
G01Y253500D02*
X210934D01*
X211434Y253000D01*
G01X213434D02*
Y254000D01*
G01X213142Y255892D02*
X213351Y256183D01*
X213434Y256517D01*
X213351Y256850D01*
X213101Y257142D01*
X212726Y257350D01*
X212351Y257433D01*
X211892D01*
X211517Y257350D01*
X211184Y257142D01*
X211017Y256892D01*
X210934Y256600D01*
X211017Y256267D01*
X211184Y256017D01*
X211434Y255850D01*
X211767Y255767D01*
X212059Y255850D01*
X212351Y256058D01*
X212517Y256308D01*
X212559Y256600D01*
X212476Y256933D01*
X212267Y257183D01*
X211892Y257433D01*
G01X214570Y237880D02*
X214237Y237922D01*
X213945Y238088D01*
X213695Y238338D01*
X213528Y238630D01*
X213445Y238963D01*
Y239297D01*
X213528Y239630D01*
X213695Y239922D01*
X213945Y240172D01*
X214237Y240338D01*
X214570Y240380D01*
X214903Y240338D01*
X215195Y240172D01*
X215445Y239922D01*
X215612Y239630D01*
X215695Y239297D01*
Y238963D01*
X215612Y238630D01*
X215445Y238338D01*
X215195Y238088D01*
X214903Y237922D01*
X214570Y237880D01*
G01X214903Y238547D02*
X215403Y237880D01*
G01X217670D02*
Y240380D01*
X217170Y239880D01*
G01Y237880D02*
X218170D01*
G01X219853D02*
Y240380D01*
X220687D01*
X221020Y240255D01*
X221270Y240088D01*
X221478Y239838D01*
X221645Y239547D01*
X221687Y239130D01*
X221645Y238713D01*
X221478Y238422D01*
X221270Y238172D01*
X221020Y238005D01*
X220687Y237880D01*
X219853D01*
G01X222953Y238380D02*
X223203Y238088D01*
X223537Y237922D01*
X223912Y237880D01*
X224245Y237922D01*
X224578Y238130D01*
X224787Y238380D01*
X224828Y238630D01*
X224745Y238922D01*
X224453Y239130D01*
X224162Y239213D01*
X223787D01*
G01X224162D02*
X224412Y239338D01*
X224620Y239547D01*
X224703Y239797D01*
X224620Y240047D01*
X224412Y240255D01*
X224037Y240380D01*
X223662Y240338D01*
X223287Y240172D01*
G01X194317Y258667D02*
Y256167D01*
X195983D01*
G01X198250D02*
Y258667D01*
X197750Y258167D01*
G01Y256167D02*
X198750D01*
G01X200433D02*
Y258667D01*
X201267D01*
X201600Y258542D01*
X201850Y258375D01*
X202058Y258125D01*
X202225Y257834D01*
X202267Y257417D01*
X202225Y257000D01*
X202058Y256709D01*
X201850Y256459D01*
X201600Y256292D01*
X201267Y256167D01*
X200433D01*
G01X203533Y256667D02*
X203783Y256375D01*
X204117Y256209D01*
X204492Y256167D01*
X204825Y256209D01*
X205158Y256417D01*
X205367Y256667D01*
X205408Y256917D01*
X205325Y257209D01*
X205033Y257417D01*
X204742Y257500D01*
X204367D01*
G01X204742D02*
X204992Y257625D01*
X205200Y257834D01*
X205283Y258084D01*
X205200Y258334D01*
X204992Y258542D01*
X204617Y258667D01*
X204242Y258625D01*
X203867Y258459D01*
G01X212112Y308904D02*
Y315904D01*
X214778D01*
X215845Y315554D01*
X216645Y315087D01*
X217312Y314387D01*
X217845Y313571D01*
X217978Y312404D01*
X217845Y311237D01*
X217312Y310421D01*
X216645Y309720D01*
X215845Y309254D01*
X214778Y308904D01*
X212112D01*
G01X206700Y370600D02*
Y318200D01*
X251999D01*
X252000Y318201D01*
Y331650D01*
G01X226649Y319110D02*
X224149D01*
Y320151D01*
X224274Y320485D01*
X224441Y320693D01*
X224774Y320776D01*
X225107Y320693D01*
X225316Y320443D01*
X225441Y320151D01*
Y319110D01*
G01Y320151D02*
X226649Y320776D01*
G01Y323043D02*
X224149D01*
X224649Y322543D01*
G01X226649D02*
Y323543D01*
G01Y325226D02*
X224149D01*
Y326060D01*
X224274Y326393D01*
X224441Y326643D01*
X224691Y326851D01*
X224982Y327018D01*
X225399Y327060D01*
X225816Y327018D01*
X226107Y326851D01*
X226357Y326643D01*
X226524Y326393D01*
X226649Y326060D01*
Y325226D01*
G01Y329743D02*
X224149D01*
X225941Y328201D01*
Y330285D01*
G01X226149Y331426D02*
X226441Y331676D01*
X226607Y332010D01*
X226649Y332385D01*
X226607Y332718D01*
X226399Y333051D01*
X226149Y333260D01*
X225899Y333301D01*
X225607Y333218D01*
X225399Y332926D01*
X225316Y332635D01*
Y332260D01*
G01Y332635D02*
X225191Y332885D01*
X224982Y333093D01*
X224732Y333176D01*
X224482Y333093D01*
X224274Y332885D01*
X224149Y332510D01*
X224191Y332135D01*
X224357Y331760D01*
G01X219616Y319181D02*
X217116D01*
Y320222D01*
X217241Y320556D01*
X217408Y320764D01*
X217741Y320847D01*
X218074Y320764D01*
X218283Y320514D01*
X218408Y320222D01*
Y319181D01*
G01Y320222D02*
X219616Y320847D01*
G01Y323114D02*
X217116D01*
X217616Y322614D01*
G01X219616D02*
Y323614D01*
G01Y325297D02*
X217116D01*
Y326131D01*
X217241Y326464D01*
X217408Y326714D01*
X217658Y326922D01*
X217949Y327089D01*
X218366Y327131D01*
X218783Y327089D01*
X219074Y326922D01*
X219324Y326714D01*
X219491Y326464D01*
X219616Y326131D01*
Y325297D01*
G01Y329814D02*
X217116D01*
X218908Y328272D01*
Y330356D01*
G01X217533Y331622D02*
X217283Y331872D01*
X217158Y332164D01*
X217116Y332497D01*
X217199Y332914D01*
X217408Y333206D01*
X217658Y333289D01*
X217908Y333247D01*
X218116Y333081D01*
X218533Y332247D01*
X218824Y331872D01*
X219241Y331622D01*
X219616Y331539D01*
Y333289D01*
G01X213382Y280914D02*
Y283414D01*
X214423D01*
X214757Y283289D01*
X214965Y283122D01*
X215048Y282789D01*
X214965Y282456D01*
X214715Y282247D01*
X214423Y282122D01*
X213382D01*
G01X214423D02*
X215048Y280914D01*
G01X217315Y283414D02*
Y280914D01*
G01X216357Y283414D02*
X218273D01*
G01X219707Y281206D02*
X219998Y280997D01*
X220332Y280914D01*
X220665Y280997D01*
X220957Y281247D01*
X221165Y281622D01*
X221248Y281997D01*
Y282456D01*
X221165Y282831D01*
X220957Y283164D01*
X220707Y283331D01*
X220415Y283414D01*
X220082Y283331D01*
X219832Y283164D01*
X219665Y282914D01*
X219582Y282581D01*
X219665Y282289D01*
X219873Y281997D01*
X220123Y281831D01*
X220415Y281789D01*
X220748Y281872D01*
X220998Y282081D01*
X221248Y282456D01*
G01X202460Y300035D02*
X202335Y299785D01*
X202252Y299493D01*
Y299160D01*
X202377Y298785D01*
X202585Y298493D01*
X202835Y298285D01*
X203252Y298118D01*
X203627Y298076D01*
X204002Y298160D01*
X204252Y298285D01*
X204502Y298535D01*
X204669Y298826D01*
X204752Y299118D01*
Y299410D01*
X204669Y299701D01*
X204544Y299951D01*
X204377Y300160D01*
G01X204752Y302218D02*
X202252D01*
X202752Y301718D01*
G01X204752D02*
Y302718D01*
G01Y304401D02*
X202252D01*
Y305235D01*
X202377Y305568D01*
X202544Y305818D01*
X202794Y306026D01*
X203085Y306193D01*
X203502Y306235D01*
X203919Y306193D01*
X204210Y306026D01*
X204460Y305818D01*
X204627Y305568D01*
X204752Y305235D01*
Y304401D01*
G01Y308418D02*
X202252D01*
X202752Y307918D01*
G01X204752D02*
Y308918D01*
G01Y312018D02*
X202252D01*
X204044Y310476D01*
Y312560D01*
G01X203100Y325492D02*
X202975Y325242D01*
X202892Y324950D01*
Y324617D01*
X203017Y324242D01*
X203225Y323950D01*
X203475Y323742D01*
X203892Y323575D01*
X204267Y323533D01*
X204642Y323617D01*
X204892Y323742D01*
X205142Y323992D01*
X205309Y324283D01*
X205392Y324575D01*
Y324867D01*
X205309Y325158D01*
X205184Y325408D01*
X205017Y325617D01*
G01X205392Y327675D02*
X202892D01*
X203392Y327175D01*
G01X205392D02*
Y328175D01*
G01Y329858D02*
X202892D01*
Y330692D01*
X203017Y331025D01*
X203184Y331275D01*
X203434Y331483D01*
X203725Y331650D01*
X204142Y331692D01*
X204559Y331650D01*
X204850Y331483D01*
X205100Y331275D01*
X205267Y331025D01*
X205392Y330692D01*
Y329858D01*
G01X204892Y332958D02*
X205184Y333208D01*
X205350Y333542D01*
X205392Y333917D01*
X205350Y334250D01*
X205142Y334583D01*
X204892Y334792D01*
X204642Y334833D01*
X204350Y334750D01*
X204142Y334458D01*
X204059Y334167D01*
Y333792D01*
G01Y334167D02*
X203934Y334417D01*
X203725Y334625D01*
X203475Y334708D01*
X203225Y334625D01*
X203017Y334417D01*
X202892Y334042D01*
X202934Y333667D01*
X203100Y333292D01*
G01X215132Y287146D02*
X214882Y287271D01*
X214590Y287354D01*
X214257D01*
X213882Y287229D01*
X213590Y287021D01*
X213382Y286771D01*
X213215Y286354D01*
X213173Y285979D01*
X213257Y285604D01*
X213382Y285354D01*
X213632Y285104D01*
X213923Y284937D01*
X214215Y284854D01*
X214507D01*
X214798Y284937D01*
X215048Y285062D01*
X215257Y285229D01*
G01X217315Y284854D02*
Y287354D01*
X216815Y286854D01*
G01Y284854D02*
X217815D01*
G01X221332Y287146D02*
X221082Y287271D01*
X220790Y287354D01*
X220457D01*
X220082Y287229D01*
X219790Y287021D01*
X219582Y286771D01*
X219415Y286354D01*
X219373Y285979D01*
X219457Y285604D01*
X219582Y285354D01*
X219832Y285104D01*
X220123Y284937D01*
X220415Y284854D01*
X220707D01*
X220998Y284937D01*
X221248Y285062D01*
X221457Y285229D01*
G01X222723Y286937D02*
X222973Y287187D01*
X223265Y287312D01*
X223598Y287354D01*
X224015Y287271D01*
X224307Y287062D01*
X224390Y286812D01*
X224348Y286562D01*
X224182Y286354D01*
X223348Y285937D01*
X222973Y285646D01*
X222723Y285229D01*
X222640Y284854D01*
X224390D01*
G01X227115D02*
Y287354D01*
X225573Y285562D01*
X227657D01*
G01X213839Y291811D02*
X213589Y291936D01*
X213297Y292019D01*
X212964D01*
X212589Y291894D01*
X212297Y291686D01*
X212089Y291436D01*
X211922Y291019D01*
X211880Y290644D01*
X211964Y290269D01*
X212089Y290019D01*
X212339Y289769D01*
X212630Y289602D01*
X212922Y289519D01*
X213214D01*
X213505Y289602D01*
X213755Y289727D01*
X213964Y289894D01*
G01X216022Y289519D02*
Y292019D01*
X215522Y291519D01*
G01Y289519D02*
X216522D01*
G01X220039Y291811D02*
X219789Y291936D01*
X219497Y292019D01*
X219164D01*
X218789Y291894D01*
X218497Y291686D01*
X218289Y291436D01*
X218122Y291019D01*
X218080Y290644D01*
X218164Y290269D01*
X218289Y290019D01*
X218539Y289769D01*
X218830Y289602D01*
X219122Y289519D01*
X219414D01*
X219705Y289602D01*
X219955Y289727D01*
X220164Y289894D01*
G01X221430Y291602D02*
X221680Y291852D01*
X221972Y291977D01*
X222305Y292019D01*
X222722Y291936D01*
X223014Y291727D01*
X223097Y291477D01*
X223055Y291227D01*
X222889Y291019D01*
X222055Y290602D01*
X221680Y290311D01*
X221430Y289894D01*
X221347Y289519D01*
X223097D01*
G01X224530Y290561D02*
X224822Y290852D01*
X225072Y291019D01*
X225405Y291102D01*
X225697Y291019D01*
X225905Y290852D01*
X226072Y290602D01*
X226114Y290311D01*
X226072Y290061D01*
X225905Y289811D01*
X225655Y289602D01*
X225364Y289519D01*
X225030Y289602D01*
X224739Y289852D01*
X224572Y290227D01*
X224530Y290644D01*
X224614Y291186D01*
X224739Y291477D01*
X224947Y291769D01*
X225239Y291977D01*
X225530Y292019D01*
X225822Y291936D01*
X226030Y291727D01*
G01X220802Y321016D02*
X220677Y320766D01*
X220594Y320474D01*
Y320141D01*
X220719Y319766D01*
X220927Y319474D01*
X221177Y319266D01*
X221594Y319099D01*
X221969Y319057D01*
X222344Y319141D01*
X222594Y319266D01*
X222844Y319516D01*
X223011Y319807D01*
X223094Y320099D01*
Y320391D01*
X223011Y320682D01*
X222886Y320932D01*
X222719Y321141D01*
G01X223094Y323199D02*
X220594D01*
X221094Y322699D01*
G01X223094D02*
Y323699D01*
G01Y325382D02*
X220594D01*
Y326216D01*
X220719Y326549D01*
X220886Y326799D01*
X221136Y327007D01*
X221427Y327174D01*
X221844Y327216D01*
X222261Y327174D01*
X222552Y327007D01*
X222802Y326799D01*
X222969Y326549D01*
X223094Y326216D01*
Y325382D01*
G01X221011Y328607D02*
X220761Y328857D01*
X220636Y329149D01*
X220594Y329482D01*
X220677Y329899D01*
X220886Y330191D01*
X221136Y330274D01*
X221386Y330232D01*
X221594Y330066D01*
X222011Y329232D01*
X222302Y328857D01*
X222719Y328607D01*
X223094Y328524D01*
Y330274D01*
G01Y332416D02*
X222552Y332499D01*
X222094Y332624D01*
X221677Y332791D01*
X221219Y332999D01*
X220594Y333332D01*
Y331666D01*
G01X213824Y320931D02*
X213699Y320681D01*
X213616Y320389D01*
Y320056D01*
X213741Y319681D01*
X213949Y319389D01*
X214199Y319181D01*
X214616Y319014D01*
X214991Y318972D01*
X215366Y319056D01*
X215616Y319181D01*
X215866Y319431D01*
X216033Y319722D01*
X216116Y320014D01*
Y320306D01*
X216033Y320597D01*
X215908Y320847D01*
X215741Y321056D01*
G01X216116Y323114D02*
X213616D01*
X214116Y322614D01*
G01X216116D02*
Y323614D01*
G01Y325297D02*
X213616D01*
Y326131D01*
X213741Y326464D01*
X213908Y326714D01*
X214158Y326922D01*
X214449Y327089D01*
X214866Y327131D01*
X215283Y327089D01*
X215574Y326922D01*
X215824Y326714D01*
X215991Y326464D01*
X216116Y326131D01*
Y325297D01*
G01X214033Y328522D02*
X213783Y328772D01*
X213658Y329064D01*
X213616Y329397D01*
X213699Y329814D01*
X213908Y330106D01*
X214158Y330189D01*
X214408Y330147D01*
X214616Y329981D01*
X215033Y329147D01*
X215324Y328772D01*
X215741Y328522D01*
X216116Y328439D01*
Y330189D01*
G01X215074Y331622D02*
X214783Y331914D01*
X214616Y332164D01*
X214533Y332497D01*
X214616Y332789D01*
X214783Y332997D01*
X215033Y333164D01*
X215324Y333206D01*
X215574Y333164D01*
X215824Y332997D01*
X216033Y332747D01*
X216116Y332456D01*
X216033Y332122D01*
X215783Y331831D01*
X215408Y331664D01*
X214991Y331622D01*
X214449Y331706D01*
X214158Y331831D01*
X213866Y332039D01*
X213658Y332331D01*
X213616Y332622D01*
X213699Y332914D01*
X213908Y333122D01*
G01X210324Y320931D02*
X210199Y320681D01*
X210116Y320389D01*
Y320056D01*
X210241Y319681D01*
X210449Y319389D01*
X210699Y319181D01*
X211116Y319014D01*
X211491Y318972D01*
X211866Y319056D01*
X212116Y319181D01*
X212366Y319431D01*
X212533Y319722D01*
X212616Y320014D01*
Y320306D01*
X212533Y320597D01*
X212408Y320847D01*
X212241Y321056D01*
G01X212616Y323114D02*
X210116D01*
X210616Y322614D01*
G01X212616D02*
Y323614D01*
G01Y325297D02*
X210116D01*
Y326131D01*
X210241Y326464D01*
X210408Y326714D01*
X210658Y326922D01*
X210949Y327089D01*
X211366Y327131D01*
X211783Y327089D01*
X212074Y326922D01*
X212324Y326714D01*
X212491Y326464D01*
X212616Y326131D01*
Y325297D01*
G01X210533Y328522D02*
X210283Y328772D01*
X210158Y329064D01*
X210116Y329397D01*
X210199Y329814D01*
X210408Y330106D01*
X210658Y330189D01*
X210908Y330147D01*
X211116Y329981D01*
X211533Y329147D01*
X211824Y328772D01*
X212241Y328522D01*
X212616Y328439D01*
Y330189D01*
G01X212241Y331497D02*
X212449Y331747D01*
X212574Y332039D01*
X212616Y332414D01*
X212533Y332789D01*
X212366Y333081D01*
X212074Y333289D01*
X211741Y333331D01*
X211408Y333247D01*
X211199Y333039D01*
X211033Y332747D01*
X210991Y332456D01*
X211033Y332164D01*
X211199Y331789D01*
X210116Y331914D01*
Y333039D01*
G01X216721Y337646D02*
X215055D01*
Y340146D01*
X216721D01*
G01X216055Y338938D02*
X215055D01*
G01X218071Y340146D02*
Y338354D01*
X218238Y337979D01*
X218571Y337729D01*
X218988Y337646D01*
X219405Y337729D01*
X219738Y337979D01*
X219905Y338354D01*
Y340146D01*
G01X222088Y337646D02*
Y340146D01*
X221588Y339646D01*
G01Y337646D02*
X222588D01*
G01X224271D02*
Y340146D01*
X225105D01*
X225438Y340021D01*
X225688Y339854D01*
X225896Y339604D01*
X226063Y339313D01*
X226105Y338896D01*
X226063Y338479D01*
X225896Y338188D01*
X225688Y337938D01*
X225438Y337771D01*
X225105Y337646D01*
X224271D01*
G01X227496Y339729D02*
X227746Y339979D01*
X228038Y340104D01*
X228371Y340146D01*
X228788Y340063D01*
X229080Y339854D01*
X229163Y339604D01*
X229121Y339354D01*
X228955Y339146D01*
X228121Y338729D01*
X227746Y338438D01*
X227496Y338021D01*
X227413Y337646D01*
X229163D01*
G01X195310Y291462D02*
Y288962D01*
X196976D01*
G01X199243D02*
Y291462D01*
X198743Y290962D01*
G01Y288962D02*
X199743D01*
G01X201426D02*
Y291462D01*
X202260D01*
X202593Y291337D01*
X202843Y291170D01*
X203051Y290920D01*
X203218Y290629D01*
X203260Y290212D01*
X203218Y289795D01*
X203051Y289504D01*
X202843Y289254D01*
X202593Y289087D01*
X202260Y288962D01*
X201426D01*
G01X204651Y291045D02*
X204901Y291295D01*
X205193Y291420D01*
X205526Y291462D01*
X205943Y291379D01*
X206235Y291170D01*
X206318Y290920D01*
X206276Y290670D01*
X206110Y290462D01*
X205276Y290045D01*
X204901Y289754D01*
X204651Y289337D01*
X204568Y288962D01*
X206318D01*
G01X194486Y319640D02*
Y317140D01*
X196152D01*
G01X198419D02*
Y319640D01*
X197919Y319140D01*
G01Y317140D02*
X198919D01*
G01X200602D02*
Y319640D01*
X201436D01*
X201769Y319515D01*
X202019Y319348D01*
X202227Y319098D01*
X202394Y318807D01*
X202436Y318390D01*
X202394Y317973D01*
X202227Y317682D01*
X202019Y317432D01*
X201769Y317265D01*
X201436Y317140D01*
X200602D01*
G01X204619D02*
Y319640D01*
X204119Y319140D01*
G01Y317140D02*
X205119D01*
G01X217110Y367853D02*
X216310Y368203D01*
X215377Y368436D01*
X214310D01*
X213110Y368086D01*
X212177Y367503D01*
X211510Y366803D01*
X210977Y365636D01*
X210844Y364586D01*
X211110Y363536D01*
X211510Y362836D01*
X212310Y362136D01*
X213244Y361669D01*
X214177Y361436D01*
X215110D01*
X216044Y361669D01*
X216844Y362019D01*
X217510Y362486D01*
G01X206700Y374800D02*
Y389199D01*
X206699Y389200D01*
X194600D01*
Y416300D01*
G01X232567Y373265D02*
X230067D01*
Y374306D01*
X230192Y374640D01*
X230359Y374848D01*
X230692Y374931D01*
X231025Y374848D01*
X231234Y374598D01*
X231359Y374306D01*
Y373265D01*
G01Y374306D02*
X232567Y374931D01*
G01Y377198D02*
X230067D01*
X230567Y376698D01*
G01X232567D02*
Y377698D01*
G01Y379381D02*
X230067D01*
Y380215D01*
X230192Y380548D01*
X230359Y380798D01*
X230609Y381006D01*
X230900Y381173D01*
X231317Y381215D01*
X231734Y381173D01*
X232025Y381006D01*
X232275Y380798D01*
X232442Y380548D01*
X232567Y380215D01*
Y379381D01*
G01Y383398D02*
X230067D01*
X230567Y382898D01*
G01X232567D02*
Y383898D01*
G01X232067Y385581D02*
X232359Y385831D01*
X232525Y386165D01*
X232567Y386540D01*
X232525Y386873D01*
X232317Y387206D01*
X232067Y387415D01*
X231817Y387456D01*
X231525Y387373D01*
X231317Y387081D01*
X231234Y386790D01*
Y386415D01*
G01Y386790D02*
X231109Y387040D01*
X230900Y387248D01*
X230650Y387331D01*
X230400Y387248D01*
X230192Y387040D01*
X230067Y386665D01*
X230109Y386290D01*
X230275Y385915D01*
G01X208855Y379616D02*
Y382116D01*
X209896D01*
X210230Y381991D01*
X210438Y381824D01*
X210521Y381491D01*
X210438Y381158D01*
X210188Y380949D01*
X209896Y380824D01*
X208855D01*
G01X209896D02*
X210521Y379616D01*
G01X212788D02*
Y382116D01*
X212288Y381616D01*
G01Y379616D02*
X213288D01*
G01X214971D02*
Y382116D01*
X215805D01*
X216138Y381991D01*
X216388Y381824D01*
X216596Y381574D01*
X216763Y381283D01*
X216805Y380866D01*
X216763Y380449D01*
X216596Y380158D01*
X216388Y379908D01*
X216138Y379741D01*
X215805Y379616D01*
X214971D01*
G01X218988D02*
Y382116D01*
X218488Y381616D01*
G01Y379616D02*
X219488D01*
G01X222088D02*
Y382116D01*
X221588Y381616D01*
G01Y379616D02*
X222588D01*
G01X202197Y391092D02*
X199697D01*
Y392133D01*
X199822Y392467D01*
X199989Y392675D01*
X200322Y392758D01*
X200655Y392675D01*
X200864Y392425D01*
X200989Y392133D01*
Y391092D01*
G01Y392133D02*
X202197Y392758D01*
G01Y395025D02*
X199697D01*
X200197Y394525D01*
G01X202197D02*
Y395525D01*
G01Y397208D02*
X199697D01*
Y398042D01*
X199822Y398375D01*
X199989Y398625D01*
X200239Y398833D01*
X200530Y399000D01*
X200947Y399042D01*
X201364Y399000D01*
X201655Y398833D01*
X201905Y398625D01*
X202072Y398375D01*
X202197Y398042D01*
Y397208D01*
G01X201155Y400433D02*
X200864Y400725D01*
X200697Y400975D01*
X200614Y401308D01*
X200697Y401600D01*
X200864Y401808D01*
X201114Y401975D01*
X201405Y402017D01*
X201655Y401975D01*
X201905Y401808D01*
X202114Y401558D01*
X202197Y401267D01*
X202114Y400933D01*
X201864Y400642D01*
X201489Y400475D01*
X201072Y400433D01*
X200530Y400517D01*
X200239Y400642D01*
X199947Y400850D01*
X199739Y401142D01*
X199697Y401433D01*
X199780Y401725D01*
X199989Y401933D01*
G01X205697Y391092D02*
X203197D01*
Y392133D01*
X203322Y392467D01*
X203489Y392675D01*
X203822Y392758D01*
X204155Y392675D01*
X204364Y392425D01*
X204489Y392133D01*
Y391092D01*
G01Y392133D02*
X205697Y392758D01*
G01Y395025D02*
X203197D01*
X203697Y394525D01*
G01X205697D02*
Y395525D01*
G01Y397208D02*
X203197D01*
Y398042D01*
X203322Y398375D01*
X203489Y398625D01*
X203739Y398833D01*
X204030Y399000D01*
X204447Y399042D01*
X204864Y399000D01*
X205155Y398833D01*
X205405Y398625D01*
X205572Y398375D01*
X205697Y398042D01*
Y397208D01*
G01Y401142D02*
X205155Y401225D01*
X204697Y401350D01*
X204280Y401517D01*
X203822Y401725D01*
X203197Y402058D01*
Y400392D01*
G01X212697Y391092D02*
X210197D01*
Y392133D01*
X210322Y392467D01*
X210489Y392675D01*
X210822Y392758D01*
X211155Y392675D01*
X211364Y392425D01*
X211489Y392133D01*
Y391092D01*
G01Y392133D02*
X212697Y392758D01*
G01Y395025D02*
X210197D01*
X210697Y394525D01*
G01X212697D02*
Y395525D01*
G01Y397208D02*
X210197D01*
Y398042D01*
X210322Y398375D01*
X210489Y398625D01*
X210739Y398833D01*
X211030Y399000D01*
X211447Y399042D01*
X211864Y399000D01*
X212155Y398833D01*
X212405Y398625D01*
X212572Y398375D01*
X212697Y398042D01*
Y397208D01*
G01Y401225D02*
X212655Y401517D01*
X212530Y401850D01*
X212322Y402058D01*
X212030Y402142D01*
X211739Y402058D01*
X211489Y401808D01*
X211364Y401433D01*
Y401017D01*
X211280Y400767D01*
X211072Y400558D01*
X210780Y400475D01*
X210489Y400600D01*
X210280Y400892D01*
X210197Y401225D01*
X210280Y401558D01*
X210489Y401850D01*
X210780Y401975D01*
X211072Y401892D01*
X211280Y401683D01*
X211364Y401433D01*
Y401017D01*
X211489Y400642D01*
X211739Y400392D01*
X212030Y400308D01*
X212322Y400392D01*
X212530Y400600D01*
X212655Y400933D01*
X212697Y401225D01*
G01X219697Y391092D02*
X217197D01*
Y392133D01*
X217322Y392467D01*
X217489Y392675D01*
X217822Y392758D01*
X218155Y392675D01*
X218364Y392425D01*
X218489Y392133D01*
Y391092D01*
G01Y392133D02*
X219697Y392758D01*
G01Y395025D02*
X217197D01*
X217697Y394525D01*
G01X219697D02*
Y395525D01*
G01Y397208D02*
X217197D01*
Y398042D01*
X217322Y398375D01*
X217489Y398625D01*
X217739Y398833D01*
X218030Y399000D01*
X218447Y399042D01*
X218864Y399000D01*
X219155Y398833D01*
X219405Y398625D01*
X219572Y398375D01*
X219697Y398042D01*
Y397208D01*
G01X217614Y400433D02*
X217364Y400683D01*
X217239Y400975D01*
X217197Y401308D01*
X217280Y401725D01*
X217489Y402017D01*
X217739Y402100D01*
X217989Y402058D01*
X218197Y401892D01*
X218614Y401058D01*
X218905Y400683D01*
X219322Y400433D01*
X219697Y400350D01*
Y402100D01*
G01X216197Y391092D02*
X213697D01*
Y392133D01*
X213822Y392467D01*
X213989Y392675D01*
X214322Y392758D01*
X214655Y392675D01*
X214864Y392425D01*
X214989Y392133D01*
Y391092D01*
G01Y392133D02*
X216197Y392758D01*
G01Y395025D02*
X213697D01*
X214197Y394525D01*
G01X216197D02*
Y395525D01*
G01Y397208D02*
X213697D01*
Y398042D01*
X213822Y398375D01*
X213989Y398625D01*
X214239Y398833D01*
X214530Y399000D01*
X214947Y399042D01*
X215364Y399000D01*
X215655Y398833D01*
X215905Y398625D01*
X216072Y398375D01*
X216197Y398042D01*
Y397208D01*
G01X215905Y400517D02*
X216114Y400808D01*
X216197Y401142D01*
X216114Y401475D01*
X215864Y401767D01*
X215489Y401975D01*
X215114Y402058D01*
X214655D01*
X214280Y401975D01*
X213947Y401767D01*
X213780Y401517D01*
X213697Y401225D01*
X213780Y400892D01*
X213947Y400642D01*
X214197Y400475D01*
X214530Y400392D01*
X214822Y400475D01*
X215114Y400683D01*
X215280Y400933D01*
X215322Y401225D01*
X215239Y401558D01*
X215030Y401808D01*
X214655Y402058D01*
G01X209197Y391092D02*
X206697D01*
Y392133D01*
X206822Y392467D01*
X206989Y392675D01*
X207322Y392758D01*
X207655Y392675D01*
X207864Y392425D01*
X207989Y392133D01*
Y391092D01*
G01Y392133D02*
X209197Y392758D01*
G01Y395025D02*
X206697D01*
X207197Y394525D01*
G01X209197D02*
Y395525D01*
G01Y397208D02*
X206697D01*
Y398042D01*
X206822Y398375D01*
X206989Y398625D01*
X207239Y398833D01*
X207530Y399000D01*
X207947Y399042D01*
X208364Y399000D01*
X208655Y398833D01*
X208905Y398625D01*
X209072Y398375D01*
X209197Y398042D01*
Y397208D01*
G01Y401225D02*
X206697D01*
X207197Y400725D01*
G01X209197D02*
Y401725D01*
G01X222269Y344664D02*
X219769D01*
Y345705D01*
X219894Y346039D01*
X220061Y346247D01*
X220394Y346330D01*
X220727Y346247D01*
X220936Y345997D01*
X221061Y345705D01*
Y344664D01*
G01Y345705D02*
X222269Y346330D01*
G01Y348597D02*
X219769D01*
X220269Y348097D01*
G01X222269D02*
Y349097D01*
G01Y350780D02*
X219769D01*
Y351614D01*
X219894Y351947D01*
X220061Y352197D01*
X220311Y352405D01*
X220602Y352572D01*
X221019Y352614D01*
X221436Y352572D01*
X221727Y352405D01*
X221977Y352197D01*
X222144Y351947D01*
X222269Y351614D01*
Y350780D01*
G01X220186Y354005D02*
X219936Y354255D01*
X219811Y354547D01*
X219769Y354880D01*
X219852Y355297D01*
X220061Y355589D01*
X220311Y355672D01*
X220561Y355630D01*
X220769Y355464D01*
X221186Y354630D01*
X221477Y354255D01*
X221894Y354005D01*
X222269Y353922D01*
Y355672D01*
G01X221227Y357105D02*
X220936Y357397D01*
X220769Y357647D01*
X220686Y357980D01*
X220769Y358272D01*
X220936Y358480D01*
X221186Y358647D01*
X221477Y358689D01*
X221727Y358647D01*
X221977Y358480D01*
X222186Y358230D01*
X222269Y357939D01*
X222186Y357605D01*
X221936Y357314D01*
X221561Y357147D01*
X221144Y357105D01*
X220602Y357189D01*
X220311Y357314D01*
X220019Y357522D01*
X219811Y357814D01*
X219769Y358105D01*
X219852Y358397D01*
X220061Y358605D01*
G01X212069Y344664D02*
X209569D01*
Y345705D01*
X209694Y346039D01*
X209861Y346247D01*
X210194Y346330D01*
X210527Y346247D01*
X210736Y345997D01*
X210861Y345705D01*
Y344664D01*
G01Y345705D02*
X212069Y346330D01*
G01Y348597D02*
X209569D01*
X210069Y348097D01*
G01X212069D02*
Y349097D01*
G01Y350780D02*
X209569D01*
Y351614D01*
X209694Y351947D01*
X209861Y352197D01*
X210111Y352405D01*
X210402Y352572D01*
X210819Y352614D01*
X211236Y352572D01*
X211527Y352405D01*
X211777Y352197D01*
X211944Y351947D01*
X212069Y351614D01*
Y350780D01*
G01X209986Y354005D02*
X209736Y354255D01*
X209611Y354547D01*
X209569Y354880D01*
X209652Y355297D01*
X209861Y355589D01*
X210111Y355672D01*
X210361Y355630D01*
X210569Y355464D01*
X210986Y354630D01*
X211277Y354255D01*
X211694Y354005D01*
X212069Y353922D01*
Y355672D01*
G01Y357897D02*
X212027Y358189D01*
X211902Y358522D01*
X211694Y358730D01*
X211402Y358814D01*
X211111Y358730D01*
X210861Y358480D01*
X210736Y358105D01*
Y357689D01*
X210652Y357439D01*
X210444Y357230D01*
X210152Y357147D01*
X209861Y357272D01*
X209652Y357564D01*
X209569Y357897D01*
X209652Y358230D01*
X209861Y358522D01*
X210152Y358647D01*
X210444Y358564D01*
X210652Y358355D01*
X210736Y358105D01*
Y357689D01*
X210861Y357314D01*
X211111Y357064D01*
X211402Y356980D01*
X211694Y357064D01*
X211902Y357272D01*
X212027Y357605D01*
X212069Y357897D01*
G01X218869Y344664D02*
X216369D01*
Y345705D01*
X216494Y346039D01*
X216661Y346247D01*
X216994Y346330D01*
X217327Y346247D01*
X217536Y345997D01*
X217661Y345705D01*
Y344664D01*
G01Y345705D02*
X218869Y346330D01*
G01Y348597D02*
X216369D01*
X216869Y348097D01*
G01X218869D02*
Y349097D01*
G01Y350780D02*
X216369D01*
Y351614D01*
X216494Y351947D01*
X216661Y352197D01*
X216911Y352405D01*
X217202Y352572D01*
X217619Y352614D01*
X218036Y352572D01*
X218327Y352405D01*
X218577Y352197D01*
X218744Y351947D01*
X218869Y351614D01*
Y350780D01*
G01X216786Y354005D02*
X216536Y354255D01*
X216411Y354547D01*
X216369Y354880D01*
X216452Y355297D01*
X216661Y355589D01*
X216911Y355672D01*
X217161Y355630D01*
X217369Y355464D01*
X217786Y354630D01*
X218077Y354255D01*
X218494Y354005D01*
X218869Y353922D01*
Y355672D01*
G01X218494Y356980D02*
X218702Y357230D01*
X218827Y357522D01*
X218869Y357897D01*
X218786Y358272D01*
X218619Y358564D01*
X218327Y358772D01*
X217994Y358814D01*
X217661Y358730D01*
X217452Y358522D01*
X217286Y358230D01*
X217244Y357939D01*
X217286Y357647D01*
X217452Y357272D01*
X216369Y357397D01*
Y358522D01*
G01X215469Y344664D02*
X212969D01*
Y345705D01*
X213094Y346039D01*
X213261Y346247D01*
X213594Y346330D01*
X213927Y346247D01*
X214136Y345997D01*
X214261Y345705D01*
Y344664D01*
G01Y345705D02*
X215469Y346330D01*
G01Y348597D02*
X212969D01*
X213469Y348097D01*
G01X215469D02*
Y349097D01*
G01Y350780D02*
X212969D01*
Y351614D01*
X213094Y351947D01*
X213261Y352197D01*
X213511Y352405D01*
X213802Y352572D01*
X214219Y352614D01*
X214636Y352572D01*
X214927Y352405D01*
X215177Y352197D01*
X215344Y351947D01*
X215469Y351614D01*
Y350780D01*
G01X213386Y354005D02*
X213136Y354255D01*
X213011Y354547D01*
X212969Y354880D01*
X213052Y355297D01*
X213261Y355589D01*
X213511Y355672D01*
X213761Y355630D01*
X213969Y355464D01*
X214386Y354630D01*
X214677Y354255D01*
X215094Y354005D01*
X215469Y353922D01*
Y355672D01*
G01Y358397D02*
X212969D01*
X214761Y356855D01*
Y358939D01*
G01X231734Y352355D02*
X229234D01*
Y353396D01*
X229359Y353730D01*
X229526Y353938D01*
X229859Y354021D01*
X230192Y353938D01*
X230401Y353688D01*
X230526Y353396D01*
Y352355D01*
G01Y353396D02*
X231734Y354021D01*
G01Y356288D02*
X229234D01*
X229734Y355788D01*
G01X231734D02*
Y356788D01*
G01Y358471D02*
X229234D01*
Y359305D01*
X229359Y359638D01*
X229526Y359888D01*
X229776Y360096D01*
X230067Y360263D01*
X230484Y360305D01*
X230901Y360263D01*
X231192Y360096D01*
X231442Y359888D01*
X231609Y359638D01*
X231734Y359305D01*
Y358471D01*
G01X229651Y361696D02*
X229401Y361946D01*
X229276Y362238D01*
X229234Y362571D01*
X229317Y362988D01*
X229526Y363280D01*
X229776Y363363D01*
X230026Y363321D01*
X230234Y363155D01*
X230651Y362321D01*
X230942Y361946D01*
X231359Y361696D01*
X231734Y361613D01*
Y363363D01*
G01X231234Y364671D02*
X231526Y364921D01*
X231692Y365255D01*
X231734Y365630D01*
X231692Y365963D01*
X231484Y366296D01*
X231234Y366505D01*
X230984Y366546D01*
X230692Y366463D01*
X230484Y366171D01*
X230401Y365880D01*
Y365505D01*
G01Y365880D02*
X230276Y366130D01*
X230067Y366338D01*
X229817Y366421D01*
X229567Y366338D01*
X229359Y366130D01*
X229234Y365755D01*
X229276Y365380D01*
X229442Y365005D01*
G01X220319Y368760D02*
Y371260D01*
X221360D01*
X221694Y371135D01*
X221902Y370968D01*
X221985Y370635D01*
X221902Y370302D01*
X221652Y370093D01*
X221360Y369968D01*
X220319D01*
G01X221360D02*
X221985Y368760D01*
G01X224252D02*
Y371260D01*
X223752Y370760D01*
G01Y368760D02*
X224752D01*
G01X226435D02*
Y371260D01*
X227269D01*
X227602Y371135D01*
X227852Y370968D01*
X228060Y370718D01*
X228227Y370427D01*
X228269Y370010D01*
X228227Y369593D01*
X228060Y369302D01*
X227852Y369052D01*
X227602Y368885D01*
X227269Y368760D01*
X226435D01*
G01X230452D02*
Y371260D01*
X229952Y370760D01*
G01Y368760D02*
X230952D01*
G01X232760Y369802D02*
X233052Y370093D01*
X233302Y370260D01*
X233635Y370343D01*
X233927Y370260D01*
X234135Y370093D01*
X234302Y369843D01*
X234344Y369552D01*
X234302Y369302D01*
X234135Y369052D01*
X233885Y368843D01*
X233594Y368760D01*
X233260Y368843D01*
X232969Y369093D01*
X232802Y369468D01*
X232760Y369885D01*
X232844Y370427D01*
X232969Y370718D01*
X233177Y371010D01*
X233469Y371218D01*
X233760Y371260D01*
X234052Y371177D01*
X234260Y370968D01*
G01X208855Y372616D02*
Y375116D01*
X209896D01*
X210230Y374991D01*
X210438Y374824D01*
X210521Y374491D01*
X210438Y374158D01*
X210188Y373949D01*
X209896Y373824D01*
X208855D01*
G01X209896D02*
X210521Y372616D01*
G01X212788D02*
Y375116D01*
X212288Y374616D01*
G01Y372616D02*
X213288D01*
G01X214971D02*
Y375116D01*
X215805D01*
X216138Y374991D01*
X216388Y374824D01*
X216596Y374574D01*
X216763Y374283D01*
X216805Y373866D01*
X216763Y373449D01*
X216596Y373158D01*
X216388Y372908D01*
X216138Y372741D01*
X215805Y372616D01*
X214971D01*
G01X218988D02*
Y375116D01*
X218488Y374616D01*
G01Y372616D02*
X219488D01*
G01X222088D02*
X222380Y372658D01*
X222713Y372783D01*
X222921Y372991D01*
X223005Y373283D01*
X222921Y373574D01*
X222671Y373824D01*
X222296Y373949D01*
X221880D01*
X221630Y374033D01*
X221421Y374241D01*
X221338Y374533D01*
X221463Y374824D01*
X221755Y375033D01*
X222088Y375116D01*
X222421Y375033D01*
X222713Y374824D01*
X222838Y374533D01*
X222755Y374241D01*
X222546Y374033D01*
X222296Y373949D01*
X221880D01*
X221505Y373824D01*
X221255Y373574D01*
X221171Y373283D01*
X221255Y372991D01*
X221463Y372783D01*
X221796Y372658D01*
X222088Y372616D01*
G01X208855Y376116D02*
Y378616D01*
X209896D01*
X210230Y378491D01*
X210438Y378324D01*
X210521Y377991D01*
X210438Y377658D01*
X210188Y377449D01*
X209896Y377324D01*
X208855D01*
G01X209896D02*
X210521Y376116D01*
G01X212788D02*
Y378616D01*
X212288Y378116D01*
G01Y376116D02*
X213288D01*
G01X214971D02*
Y378616D01*
X215805D01*
X216138Y378491D01*
X216388Y378324D01*
X216596Y378074D01*
X216763Y377783D01*
X216805Y377366D01*
X216763Y376949D01*
X216596Y376658D01*
X216388Y376408D01*
X216138Y376241D01*
X215805Y376116D01*
X214971D01*
G01X218988D02*
Y378616D01*
X218488Y378116D01*
G01Y376116D02*
X219488D01*
G01X221171Y376491D02*
X221421Y376283D01*
X221713Y376158D01*
X222088Y376116D01*
X222463Y376199D01*
X222755Y376366D01*
X222963Y376658D01*
X223005Y376991D01*
X222921Y377324D01*
X222713Y377533D01*
X222421Y377699D01*
X222130Y377741D01*
X221838Y377699D01*
X221463Y377533D01*
X221588Y378616D01*
X222713D01*
G01X226697Y391092D02*
X224197D01*
Y392133D01*
X224322Y392467D01*
X224489Y392675D01*
X224822Y392758D01*
X225155Y392675D01*
X225364Y392425D01*
X225489Y392133D01*
Y391092D01*
G01Y392133D02*
X226697Y392758D01*
G01Y395025D02*
X224197D01*
X224697Y394525D01*
G01X226697D02*
Y395525D01*
G01Y397208D02*
X224197D01*
Y398042D01*
X224322Y398375D01*
X224489Y398625D01*
X224739Y398833D01*
X225030Y399000D01*
X225447Y399042D01*
X225864Y399000D01*
X226155Y398833D01*
X226405Y398625D01*
X226572Y398375D01*
X226697Y398042D01*
Y397208D01*
G01X226322Y400308D02*
X226530Y400558D01*
X226655Y400850D01*
X226697Y401225D01*
X226614Y401600D01*
X226447Y401892D01*
X226155Y402100D01*
X225822Y402142D01*
X225489Y402058D01*
X225280Y401850D01*
X225114Y401558D01*
X225072Y401267D01*
X225114Y400975D01*
X225280Y400600D01*
X224197Y400725D01*
Y401850D01*
G01X226197Y403408D02*
X226489Y403658D01*
X226655Y403992D01*
X226697Y404367D01*
X226655Y404700D01*
X226447Y405033D01*
X226197Y405242D01*
X225947Y405283D01*
X225655Y405200D01*
X225447Y404908D01*
X225364Y404617D01*
Y404242D01*
G01Y404617D02*
X225239Y404867D01*
X225030Y405075D01*
X224780Y405158D01*
X224530Y405075D01*
X224322Y404867D01*
X224197Y404492D01*
X224239Y404117D01*
X224405Y403742D01*
G01X223197Y391092D02*
X220697D01*
Y392133D01*
X220822Y392467D01*
X220989Y392675D01*
X221322Y392758D01*
X221655Y392675D01*
X221864Y392425D01*
X221989Y392133D01*
Y391092D01*
G01Y392133D02*
X223197Y392758D01*
G01Y395025D02*
X220697D01*
X221197Y394525D01*
G01X223197D02*
Y395525D01*
G01Y397208D02*
X220697D01*
Y398042D01*
X220822Y398375D01*
X220989Y398625D01*
X221239Y398833D01*
X221530Y399000D01*
X221947Y399042D01*
X222364Y399000D01*
X222655Y398833D01*
X222905Y398625D01*
X223072Y398375D01*
X223197Y398042D01*
Y397208D01*
G01X222697Y400308D02*
X222989Y400558D01*
X223155Y400892D01*
X223197Y401267D01*
X223155Y401600D01*
X222947Y401933D01*
X222697Y402142D01*
X222447Y402183D01*
X222155Y402100D01*
X221947Y401808D01*
X221864Y401517D01*
Y401142D01*
G01Y401517D02*
X221739Y401767D01*
X221530Y401975D01*
X221280Y402058D01*
X221030Y401975D01*
X220822Y401767D01*
X220697Y401392D01*
X220739Y401017D01*
X220905Y400642D01*
G01X201659Y361852D02*
X201534Y361602D01*
X201451Y361310D01*
Y360977D01*
X201576Y360602D01*
X201784Y360310D01*
X202034Y360102D01*
X202451Y359935D01*
X202826Y359893D01*
X203201Y359977D01*
X203451Y360102D01*
X203701Y360352D01*
X203868Y360643D01*
X203951Y360935D01*
Y361227D01*
X203868Y361518D01*
X203743Y361768D01*
X203576Y361977D01*
G01X203951Y364035D02*
X201451D01*
X201951Y363535D01*
G01X203951D02*
Y364535D01*
G01X201659Y368052D02*
X201534Y367802D01*
X201451Y367510D01*
Y367177D01*
X201576Y366802D01*
X201784Y366510D01*
X202034Y366302D01*
X202451Y366135D01*
X202826Y366093D01*
X203201Y366177D01*
X203451Y366302D01*
X203701Y366552D01*
X203868Y366843D01*
X203951Y367135D01*
Y367427D01*
X203868Y367718D01*
X203743Y367968D01*
X203576Y368177D01*
G01X203951Y370235D02*
X201451D01*
X201951Y369735D01*
G01X203951D02*
Y370735D01*
G01X203659Y372627D02*
X203868Y372918D01*
X203951Y373252D01*
X203868Y373585D01*
X203618Y373877D01*
X203243Y374085D01*
X202868Y374168D01*
X202409D01*
X202034Y374085D01*
X201701Y373877D01*
X201534Y373627D01*
X201451Y373335D01*
X201534Y373002D01*
X201701Y372752D01*
X201951Y372585D01*
X202284Y372502D01*
X202576Y372585D01*
X202868Y372793D01*
X203034Y373043D01*
X203076Y373335D01*
X202993Y373668D01*
X202784Y373918D01*
X202409Y374168D01*
G01X223377Y346414D02*
X223252Y346164D01*
X223169Y345872D01*
Y345539D01*
X223294Y345164D01*
X223502Y344872D01*
X223752Y344664D01*
X224169Y344497D01*
X224544Y344455D01*
X224919Y344539D01*
X225169Y344664D01*
X225419Y344914D01*
X225586Y345205D01*
X225669Y345497D01*
Y345789D01*
X225586Y346080D01*
X225461Y346330D01*
X225294Y346539D01*
G01X225669Y348597D02*
X223169D01*
X223669Y348097D01*
G01X225669D02*
Y349097D01*
G01Y350780D02*
X223169D01*
Y351614D01*
X223294Y351947D01*
X223461Y352197D01*
X223711Y352405D01*
X224002Y352572D01*
X224419Y352614D01*
X224836Y352572D01*
X225127Y352405D01*
X225377Y352197D01*
X225544Y351947D01*
X225669Y351614D01*
Y350780D01*
G01Y354797D02*
X223169D01*
X223669Y354297D01*
G01X225669D02*
Y355297D01*
G01Y357897D02*
X223169D01*
X223669Y357397D01*
G01X225669D02*
Y358397D01*
G01X228667Y376098D02*
X228625Y375765D01*
X228459Y375473D01*
X228209Y375223D01*
X227917Y375056D01*
X227584Y374973D01*
X227250D01*
X226917Y375056D01*
X226625Y375223D01*
X226375Y375473D01*
X226209Y375765D01*
X226167Y376098D01*
X226209Y376431D01*
X226375Y376723D01*
X226625Y376973D01*
X226917Y377140D01*
X227250Y377223D01*
X227584D01*
X227917Y377140D01*
X228209Y376973D01*
X228459Y376723D01*
X228625Y376431D01*
X228667Y376098D01*
G01X228000Y376431D02*
X228667Y376931D01*
G01Y379198D02*
X226167D01*
X226667Y378698D01*
G01X228667D02*
Y379698D01*
G01Y381381D02*
X226167D01*
Y382215D01*
X226292Y382548D01*
X226459Y382798D01*
X226709Y383006D01*
X227000Y383173D01*
X227417Y383215D01*
X227834Y383173D01*
X228125Y383006D01*
X228375Y382798D01*
X228542Y382548D01*
X228667Y382215D01*
Y381381D01*
G01Y385398D02*
X226167D01*
X226667Y384898D01*
G01X228667D02*
Y385898D01*
G01X194341Y385626D02*
Y383126D01*
X196007D01*
G01X198274D02*
Y385626D01*
X197774Y385126D01*
G01Y383126D02*
X198774D01*
G01X202291Y385418D02*
X202041Y385543D01*
X201749Y385626D01*
X201416D01*
X201041Y385501D01*
X200749Y385293D01*
X200541Y385043D01*
X200374Y384626D01*
X200332Y384251D01*
X200416Y383876D01*
X200541Y383626D01*
X200791Y383376D01*
X201082Y383209D01*
X201374Y383126D01*
X201666D01*
X201957Y383209D01*
X202207Y383334D01*
X202416Y383501D01*
G01X204474Y383126D02*
Y385626D01*
X203974Y385126D01*
G01Y383126D02*
X204974D01*
G01X194411Y355876D02*
Y353376D01*
X196077D01*
G01X198344D02*
Y355876D01*
X197844Y355376D01*
G01Y353376D02*
X198844D01*
G01X202361Y355668D02*
X202111Y355793D01*
X201819Y355876D01*
X201486D01*
X201111Y355751D01*
X200819Y355543D01*
X200611Y355293D01*
X200444Y354876D01*
X200402Y354501D01*
X200486Y354126D01*
X200611Y353876D01*
X200861Y353626D01*
X201152Y353459D01*
X201444Y353376D01*
X201736D01*
X202027Y353459D01*
X202277Y353584D01*
X202486Y353751D01*
G01X203752Y355459D02*
X204002Y355709D01*
X204294Y355834D01*
X204627Y355876D01*
X205044Y355793D01*
X205336Y355584D01*
X205419Y355334D01*
X205377Y355084D01*
X205211Y354876D01*
X204377Y354459D01*
X204002Y354168D01*
X203752Y353751D01*
X203669Y353376D01*
X205419D01*
G01X203467Y423600D02*
X204000Y423950D01*
X204400Y424534D01*
X204667Y425350D01*
X204400Y426050D01*
X203867Y426517D01*
X202933Y426867D01*
X199333D01*
Y419867D01*
X203733D01*
X204667Y420334D01*
X205200Y421034D01*
X205467Y421850D01*
X205200Y422667D01*
X204400Y423367D01*
X203467Y423600D01*
X199333D01*
G01X184721Y465209D02*
X188054Y472209D01*
X191387Y465209D01*
G01X190187Y467659D02*
X185921D01*
G01X204302Y508380D02*
Y461700D01*
X213671D01*
G01X213664Y461702D02*
X213671D01*
Y461700D01*
G01X199905Y408404D02*
Y410904D01*
X200946D01*
X201280Y410779D01*
X201488Y410612D01*
X201571Y410279D01*
X201488Y409946D01*
X201238Y409737D01*
X200946Y409612D01*
X199905D01*
G01X200946D02*
X201571Y408404D01*
G01X203838D02*
Y410904D01*
X203338Y410404D01*
G01Y408404D02*
X204338D01*
G01X207855Y410696D02*
X207605Y410821D01*
X207313Y410904D01*
X206980D01*
X206605Y410779D01*
X206313Y410571D01*
X206105Y410321D01*
X205938Y409904D01*
X205896Y409529D01*
X205980Y409154D01*
X206105Y408904D01*
X206355Y408654D01*
X206646Y408487D01*
X206938Y408404D01*
X207230D01*
X207521Y408487D01*
X207771Y408612D01*
X207980Y408779D01*
G01X209246Y410487D02*
X209496Y410737D01*
X209788Y410862D01*
X210121Y410904D01*
X210538Y410821D01*
X210830Y410612D01*
X210913Y410362D01*
X210871Y410112D01*
X210705Y409904D01*
X209871Y409487D01*
X209496Y409196D01*
X209246Y408779D01*
X209163Y408404D01*
X210913D01*
G01X213138D02*
X213430Y408446D01*
X213763Y408571D01*
X213971Y408779D01*
X214055Y409071D01*
X213971Y409362D01*
X213721Y409612D01*
X213346Y409737D01*
X212930D01*
X212680Y409821D01*
X212471Y410029D01*
X212388Y410321D01*
X212513Y410612D01*
X212805Y410821D01*
X213138Y410904D01*
X213471Y410821D01*
X213763Y410612D01*
X213888Y410321D01*
X213805Y410029D01*
X213596Y409821D01*
X213346Y409737D01*
X212930D01*
X212555Y409612D01*
X212305Y409362D01*
X212221Y409071D01*
X212305Y408779D01*
X212513Y408571D01*
X212846Y408446D01*
X213138Y408404D01*
G01X199905Y404904D02*
Y407404D01*
X200946D01*
X201280Y407279D01*
X201488Y407112D01*
X201571Y406779D01*
X201488Y406446D01*
X201238Y406237D01*
X200946Y406112D01*
X199905D01*
G01X200946D02*
X201571Y404904D01*
G01X203838D02*
Y407404D01*
X203338Y406904D01*
G01Y404904D02*
X204338D01*
G01X207855Y407196D02*
X207605Y407321D01*
X207313Y407404D01*
X206980D01*
X206605Y407279D01*
X206313Y407071D01*
X206105Y406821D01*
X205938Y406404D01*
X205896Y406029D01*
X205980Y405654D01*
X206105Y405404D01*
X206355Y405154D01*
X206646Y404987D01*
X206938Y404904D01*
X207230D01*
X207521Y404987D01*
X207771Y405112D01*
X207980Y405279D01*
G01X209121Y405404D02*
X209371Y405112D01*
X209705Y404946D01*
X210080Y404904D01*
X210413Y404946D01*
X210746Y405154D01*
X210955Y405404D01*
X210996Y405654D01*
X210913Y405946D01*
X210621Y406154D01*
X210330Y406237D01*
X209955D01*
G01X210330D02*
X210580Y406362D01*
X210788Y406571D01*
X210871Y406821D01*
X210788Y407071D01*
X210580Y407279D01*
X210205Y407404D01*
X209830Y407362D01*
X209455Y407196D01*
G01X213138Y407404D02*
X212805Y407321D01*
X212555Y407112D01*
X212388Y406862D01*
X212263Y406529D01*
X212221Y406154D01*
X212263Y405779D01*
X212388Y405446D01*
X212555Y405196D01*
X212805Y404987D01*
X213138Y404904D01*
X213471Y404987D01*
X213721Y405196D01*
X213888Y405446D01*
X214013Y405779D01*
X214055Y406154D01*
X214013Y406529D01*
X213888Y406862D01*
X213721Y407112D01*
X213471Y407321D01*
X213138Y407404D01*
G01X216978Y457006D02*
Y459506D01*
X218019D01*
X218353Y459381D01*
X218561Y459214D01*
X218644Y458881D01*
X218561Y458548D01*
X218311Y458339D01*
X218019Y458214D01*
X216978D01*
G01X218019D02*
X218644Y457006D01*
G01X220911D02*
Y459506D01*
X220411Y459006D01*
G01Y457006D02*
X221411D01*
G01X224928Y459298D02*
X224678Y459423D01*
X224386Y459506D01*
X224053D01*
X223678Y459381D01*
X223386Y459173D01*
X223178Y458923D01*
X223011Y458506D01*
X222969Y458131D01*
X223053Y457756D01*
X223178Y457506D01*
X223428Y457256D01*
X223719Y457089D01*
X224011Y457006D01*
X224303D01*
X224594Y457089D01*
X224844Y457214D01*
X225053Y457381D01*
G01X226194Y457506D02*
X226444Y457214D01*
X226778Y457048D01*
X227153Y457006D01*
X227486Y457048D01*
X227819Y457256D01*
X228028Y457506D01*
X228069Y457756D01*
X227986Y458048D01*
X227694Y458256D01*
X227403Y458339D01*
X227028D01*
G01X227403D02*
X227653Y458464D01*
X227861Y458673D01*
X227944Y458923D01*
X227861Y459173D01*
X227653Y459381D01*
X227278Y459506D01*
X226903Y459464D01*
X226528Y459298D01*
G01X229419Y459089D02*
X229669Y459339D01*
X229961Y459464D01*
X230294Y459506D01*
X230711Y459423D01*
X231003Y459214D01*
X231086Y458964D01*
X231044Y458714D01*
X230878Y458506D01*
X230044Y458089D01*
X229669Y457798D01*
X229419Y457381D01*
X229336Y457006D01*
X231086D01*
G01X216978Y453606D02*
Y456106D01*
X218019D01*
X218353Y455981D01*
X218561Y455814D01*
X218644Y455481D01*
X218561Y455148D01*
X218311Y454939D01*
X218019Y454814D01*
X216978D01*
G01X218019D02*
X218644Y453606D01*
G01X220911D02*
Y456106D01*
X220411Y455606D01*
G01Y453606D02*
X221411D01*
G01X224928Y455898D02*
X224678Y456023D01*
X224386Y456106D01*
X224053D01*
X223678Y455981D01*
X223386Y455773D01*
X223178Y455523D01*
X223011Y455106D01*
X222969Y454731D01*
X223053Y454356D01*
X223178Y454106D01*
X223428Y453856D01*
X223719Y453689D01*
X224011Y453606D01*
X224303D01*
X224594Y453689D01*
X224844Y453814D01*
X225053Y453981D01*
G01X226194Y454106D02*
X226444Y453814D01*
X226778Y453648D01*
X227153Y453606D01*
X227486Y453648D01*
X227819Y453856D01*
X228028Y454106D01*
X228069Y454356D01*
X227986Y454648D01*
X227694Y454856D01*
X227403Y454939D01*
X227028D01*
G01X227403D02*
X227653Y455064D01*
X227861Y455273D01*
X227944Y455523D01*
X227861Y455773D01*
X227653Y455981D01*
X227278Y456106D01*
X226903Y456064D01*
X226528Y455898D01*
G01X229294Y454106D02*
X229544Y453814D01*
X229878Y453648D01*
X230253Y453606D01*
X230586Y453648D01*
X230919Y453856D01*
X231128Y454106D01*
X231169Y454356D01*
X231086Y454648D01*
X230794Y454856D01*
X230503Y454939D01*
X230128D01*
G01X230503D02*
X230753Y455064D01*
X230961Y455273D01*
X231044Y455523D01*
X230961Y455773D01*
X230753Y455981D01*
X230378Y456106D01*
X230003Y456064D01*
X229628Y455898D01*
G01X216978Y450206D02*
Y452706D01*
X218019D01*
X218353Y452581D01*
X218561Y452414D01*
X218644Y452081D01*
X218561Y451748D01*
X218311Y451539D01*
X218019Y451414D01*
X216978D01*
G01X218019D02*
X218644Y450206D01*
G01X220911D02*
Y452706D01*
X220411Y452206D01*
G01Y450206D02*
X221411D01*
G01X224928Y452498D02*
X224678Y452623D01*
X224386Y452706D01*
X224053D01*
X223678Y452581D01*
X223386Y452373D01*
X223178Y452123D01*
X223011Y451706D01*
X222969Y451331D01*
X223053Y450956D01*
X223178Y450706D01*
X223428Y450456D01*
X223719Y450289D01*
X224011Y450206D01*
X224303D01*
X224594Y450289D01*
X224844Y450414D01*
X225053Y450581D01*
G01X226194Y450706D02*
X226444Y450414D01*
X226778Y450248D01*
X227153Y450206D01*
X227486Y450248D01*
X227819Y450456D01*
X228028Y450706D01*
X228069Y450956D01*
X227986Y451248D01*
X227694Y451456D01*
X227403Y451539D01*
X227028D01*
G01X227403D02*
X227653Y451664D01*
X227861Y451873D01*
X227944Y452123D01*
X227861Y452373D01*
X227653Y452581D01*
X227278Y452706D01*
X226903Y452664D01*
X226528Y452498D01*
G01X230711Y450206D02*
Y452706D01*
X229169Y450914D01*
X231253D01*
G01X216978Y443406D02*
Y445906D01*
X218019D01*
X218353Y445781D01*
X218561Y445614D01*
X218644Y445281D01*
X218561Y444948D01*
X218311Y444739D01*
X218019Y444614D01*
X216978D01*
G01X218019D02*
X218644Y443406D01*
G01X220911D02*
Y445906D01*
X220411Y445406D01*
G01Y443406D02*
X221411D01*
G01X224928Y445698D02*
X224678Y445823D01*
X224386Y445906D01*
X224053D01*
X223678Y445781D01*
X223386Y445573D01*
X223178Y445323D01*
X223011Y444906D01*
X222969Y444531D01*
X223053Y444156D01*
X223178Y443906D01*
X223428Y443656D01*
X223719Y443489D01*
X224011Y443406D01*
X224303D01*
X224594Y443489D01*
X224844Y443614D01*
X225053Y443781D01*
G01X226194Y443906D02*
X226444Y443614D01*
X226778Y443448D01*
X227153Y443406D01*
X227486Y443448D01*
X227819Y443656D01*
X228028Y443906D01*
X228069Y444156D01*
X227986Y444448D01*
X227694Y444656D01*
X227403Y444739D01*
X227028D01*
G01X227403D02*
X227653Y444864D01*
X227861Y445073D01*
X227944Y445323D01*
X227861Y445573D01*
X227653Y445781D01*
X227278Y445906D01*
X226903Y445864D01*
X226528Y445698D01*
G01X229419Y444448D02*
X229711Y444739D01*
X229961Y444906D01*
X230294Y444989D01*
X230586Y444906D01*
X230794Y444739D01*
X230961Y444489D01*
X231003Y444198D01*
X230961Y443948D01*
X230794Y443698D01*
X230544Y443489D01*
X230253Y443406D01*
X229919Y443489D01*
X229628Y443739D01*
X229461Y444114D01*
X229419Y444531D01*
X229503Y445073D01*
X229628Y445364D01*
X229836Y445656D01*
X230128Y445864D01*
X230419Y445906D01*
X230711Y445823D01*
X230919Y445614D01*
G01X216978Y446806D02*
Y449306D01*
X218019D01*
X218353Y449181D01*
X218561Y449014D01*
X218644Y448681D01*
X218561Y448348D01*
X218311Y448139D01*
X218019Y448014D01*
X216978D01*
G01X218019D02*
X218644Y446806D01*
G01X220911D02*
Y449306D01*
X220411Y448806D01*
G01Y446806D02*
X221411D01*
G01X224928Y449098D02*
X224678Y449223D01*
X224386Y449306D01*
X224053D01*
X223678Y449181D01*
X223386Y448973D01*
X223178Y448723D01*
X223011Y448306D01*
X222969Y447931D01*
X223053Y447556D01*
X223178Y447306D01*
X223428Y447056D01*
X223719Y446889D01*
X224011Y446806D01*
X224303D01*
X224594Y446889D01*
X224844Y447014D01*
X225053Y447181D01*
G01X226194Y447306D02*
X226444Y447014D01*
X226778Y446848D01*
X227153Y446806D01*
X227486Y446848D01*
X227819Y447056D01*
X228028Y447306D01*
X228069Y447556D01*
X227986Y447848D01*
X227694Y448056D01*
X227403Y448139D01*
X227028D01*
G01X227403D02*
X227653Y448264D01*
X227861Y448473D01*
X227944Y448723D01*
X227861Y448973D01*
X227653Y449181D01*
X227278Y449306D01*
X226903Y449264D01*
X226528Y449098D01*
G01X229294Y447181D02*
X229544Y446973D01*
X229836Y446848D01*
X230211Y446806D01*
X230586Y446889D01*
X230878Y447056D01*
X231086Y447348D01*
X231128Y447681D01*
X231044Y448014D01*
X230836Y448223D01*
X230544Y448389D01*
X230253Y448431D01*
X229961Y448389D01*
X229586Y448223D01*
X229711Y449306D01*
X230836D01*
G01X187043Y431627D02*
X184543D01*
Y432668D01*
X184668Y433002D01*
X184835Y433210D01*
X185168Y433293D01*
X185501Y433210D01*
X185710Y432960D01*
X185835Y432668D01*
Y431627D01*
G01Y432668D02*
X187043Y433293D01*
G01Y435560D02*
X184543D01*
X185043Y435060D01*
G01X187043D02*
Y436060D01*
G01X184751Y439577D02*
X184626Y439327D01*
X184543Y439035D01*
Y438702D01*
X184668Y438327D01*
X184876Y438035D01*
X185126Y437827D01*
X185543Y437660D01*
X185918Y437618D01*
X186293Y437702D01*
X186543Y437827D01*
X186793Y438077D01*
X186960Y438368D01*
X187043Y438660D01*
Y438952D01*
X186960Y439243D01*
X186835Y439493D01*
X186668Y439702D01*
G01X187043Y441760D02*
X184543D01*
X185043Y441260D01*
G01X187043D02*
Y442260D01*
G01X186001Y444068D02*
X185710Y444360D01*
X185543Y444610D01*
X185460Y444943D01*
X185543Y445235D01*
X185710Y445443D01*
X185960Y445610D01*
X186251Y445652D01*
X186501Y445610D01*
X186751Y445443D01*
X186960Y445193D01*
X187043Y444902D01*
X186960Y444568D01*
X186710Y444277D01*
X186335Y444110D01*
X185918Y444068D01*
X185376Y444152D01*
X185085Y444277D01*
X184793Y444485D01*
X184585Y444777D01*
X184543Y445068D01*
X184626Y445360D01*
X184835Y445568D01*
G01X204646Y431455D02*
X202146D01*
Y432496D01*
X202271Y432830D01*
X202438Y433038D01*
X202771Y433121D01*
X203104Y433038D01*
X203313Y432788D01*
X203438Y432496D01*
Y431455D01*
G01Y432496D02*
X204646Y433121D01*
G01Y435388D02*
X202146D01*
X202646Y434888D01*
G01X204646D02*
Y435888D01*
G01X202354Y439405D02*
X202229Y439155D01*
X202146Y438863D01*
Y438530D01*
X202271Y438155D01*
X202479Y437863D01*
X202729Y437655D01*
X203146Y437488D01*
X203521Y437446D01*
X203896Y437530D01*
X204146Y437655D01*
X204396Y437905D01*
X204563Y438196D01*
X204646Y438488D01*
Y438780D01*
X204563Y439071D01*
X204438Y439321D01*
X204271Y439530D01*
G01X204646Y441588D02*
X202146D01*
X202646Y441088D01*
G01X204646D02*
Y442088D01*
G01Y444688D02*
X204604Y444980D01*
X204479Y445313D01*
X204271Y445521D01*
X203979Y445605D01*
X203688Y445521D01*
X203438Y445271D01*
X203313Y444896D01*
Y444480D01*
X203229Y444230D01*
X203021Y444021D01*
X202729Y443938D01*
X202438Y444063D01*
X202229Y444355D01*
X202146Y444688D01*
X202229Y445021D01*
X202438Y445313D01*
X202729Y445438D01*
X203021Y445355D01*
X203229Y445146D01*
X203313Y444896D01*
Y444480D01*
X203438Y444105D01*
X203688Y443855D01*
X203979Y443771D01*
X204271Y443855D01*
X204479Y444063D01*
X204604Y444396D01*
X204646Y444688D01*
G01X209390Y434217D02*
X206890D01*
Y435258D01*
X207015Y435592D01*
X207182Y435800D01*
X207515Y435883D01*
X207848Y435800D01*
X208057Y435550D01*
X208182Y435258D01*
Y434217D01*
G01Y435258D02*
X209390Y435883D01*
G01Y437358D02*
X206890D01*
Y438942D01*
G01X208098Y438358D02*
Y437358D01*
G01X209390Y441250D02*
X206890D01*
X207390Y440750D01*
G01X209390D02*
Y441750D01*
G01X207307Y443558D02*
X207057Y443808D01*
X206932Y444100D01*
X206890Y444433D01*
X206973Y444850D01*
X207182Y445142D01*
X207432Y445225D01*
X207682Y445183D01*
X207890Y445017D01*
X208307Y444183D01*
X208598Y443808D01*
X209015Y443558D01*
X209390Y443475D01*
Y445225D01*
G01X198016Y456097D02*
Y458597D01*
X199057D01*
X199391Y458472D01*
X199599Y458305D01*
X199682Y457972D01*
X199599Y457639D01*
X199349Y457430D01*
X199057Y457305D01*
X198016D01*
G01X199057D02*
X199682Y456097D01*
G01X201949D02*
Y458597D01*
X201449Y458097D01*
G01Y456097D02*
X202449D01*
G01X205382Y457430D02*
X205549Y457555D01*
X205674Y457764D01*
X205757Y458055D01*
X205674Y458305D01*
X205507Y458472D01*
X205216Y458597D01*
X204091D01*
Y456097D01*
X205466D01*
X205757Y456264D01*
X205924Y456514D01*
X206007Y456805D01*
X205924Y457097D01*
X205674Y457347D01*
X205382Y457430D01*
X204091D01*
G01X208149Y456097D02*
Y458597D01*
X207649Y458097D01*
G01Y456097D02*
X208649D01*
G01X210457Y458180D02*
X210707Y458430D01*
X210999Y458555D01*
X211332Y458597D01*
X211749Y458514D01*
X212041Y458305D01*
X212124Y458055D01*
X212082Y457805D01*
X211916Y457597D01*
X211082Y457180D01*
X210707Y456889D01*
X210457Y456472D01*
X210374Y456097D01*
X212124D01*
G01X173046Y452054D02*
Y454554D01*
X174087D01*
X174421Y454429D01*
X174629Y454262D01*
X174712Y453929D01*
X174629Y453596D01*
X174379Y453387D01*
X174087Y453262D01*
X173046D01*
G01X174087D02*
X174712Y452054D01*
G01X176187D02*
Y454554D01*
X177771D01*
G01X177187Y453346D02*
X176187D01*
G01X179287Y454137D02*
X179537Y454387D01*
X179829Y454512D01*
X180162Y454554D01*
X180579Y454471D01*
X180871Y454262D01*
X180954Y454012D01*
X180912Y453762D01*
X180746Y453554D01*
X179912Y453137D01*
X179537Y452846D01*
X179287Y452429D01*
X179204Y452054D01*
X180954D01*
G01X183179D02*
Y454554D01*
X182679Y454054D01*
G01Y452054D02*
X183679D01*
G01X184961Y452139D02*
Y454639D01*
X186002D01*
X186336Y454514D01*
X186544Y454347D01*
X186627Y454014D01*
X186544Y453681D01*
X186294Y453472D01*
X186002Y453347D01*
X184961D01*
G01X186002D02*
X186627Y452139D01*
G01X188102D02*
Y454639D01*
X189686D01*
G01X189102Y453431D02*
X188102D01*
G01X191202Y454222D02*
X191452Y454472D01*
X191744Y454597D01*
X192077Y454639D01*
X192494Y454556D01*
X192786Y454347D01*
X192869Y454097D01*
X192827Y453847D01*
X192661Y453639D01*
X191827Y453222D01*
X191452Y452931D01*
X191202Y452514D01*
X191119Y452139D01*
X192869D01*
G01X194302Y454222D02*
X194552Y454472D01*
X194844Y454597D01*
X195177Y454639D01*
X195594Y454556D01*
X195886Y454347D01*
X195969Y454097D01*
X195927Y453847D01*
X195761Y453639D01*
X194927Y453222D01*
X194552Y452931D01*
X194302Y452514D01*
X194219Y452139D01*
X195969D01*
G01X197898Y448657D02*
Y451157D01*
X198939D01*
X199273Y451032D01*
X199481Y450865D01*
X199564Y450532D01*
X199481Y450199D01*
X199231Y449990D01*
X198939Y449865D01*
X197898D01*
G01X198939D02*
X199564Y448657D01*
G01X201831D02*
Y451157D01*
X201331Y450657D01*
G01Y448657D02*
X202331D01*
G01X205264Y449990D02*
X205431Y450115D01*
X205556Y450324D01*
X205639Y450615D01*
X205556Y450865D01*
X205389Y451032D01*
X205098Y451157D01*
X203973D01*
Y448657D01*
X205348D01*
X205639Y448824D01*
X205806Y449074D01*
X205889Y449365D01*
X205806Y449657D01*
X205556Y449907D01*
X205264Y449990D01*
X203973D01*
G01X208031Y448657D02*
Y451157D01*
X207531Y450657D01*
G01Y448657D02*
X208531D01*
G01X210214Y449032D02*
X210464Y448824D01*
X210756Y448699D01*
X211131Y448657D01*
X211506Y448740D01*
X211798Y448907D01*
X212006Y449199D01*
X212048Y449532D01*
X211964Y449865D01*
X211756Y450074D01*
X211464Y450240D01*
X211173Y450282D01*
X210881Y450240D01*
X210506Y450074D01*
X210631Y451157D01*
X211756D01*
G01X213644Y418187D02*
X211144D01*
Y419228D01*
X211269Y419562D01*
X211436Y419770D01*
X211769Y419853D01*
X212102Y419770D01*
X212311Y419520D01*
X212436Y419228D01*
Y418187D01*
G01Y419228D02*
X213644Y419853D01*
G01Y422120D02*
X211144D01*
X211644Y421620D01*
G01X213644D02*
Y422620D01*
G01X211352Y426137D02*
X211227Y425887D01*
X211144Y425595D01*
Y425262D01*
X211269Y424887D01*
X211477Y424595D01*
X211727Y424387D01*
X212144Y424220D01*
X212519Y424178D01*
X212894Y424262D01*
X213144Y424387D01*
X213394Y424637D01*
X213561Y424928D01*
X213644Y425220D01*
Y425512D01*
X213561Y425803D01*
X213436Y426053D01*
X213269Y426262D01*
G01X211561Y427528D02*
X211311Y427778D01*
X211186Y428070D01*
X211144Y428403D01*
X211227Y428820D01*
X211436Y429112D01*
X211686Y429195D01*
X211936Y429153D01*
X212144Y428987D01*
X212561Y428153D01*
X212852Y427778D01*
X213269Y427528D01*
X213644Y427445D01*
Y429195D01*
G01Y431420D02*
X211144D01*
X211644Y430920D01*
G01X213644D02*
Y431920D01*
G01X172732Y461205D02*
Y463705D01*
X173773D01*
X174107Y463580D01*
X174315Y463413D01*
X174398Y463080D01*
X174315Y462747D01*
X174065Y462538D01*
X173773Y462413D01*
X172732D01*
G01X173773D02*
X174398Y461205D01*
G01X176665D02*
Y463705D01*
X176165Y463205D01*
G01Y461205D02*
X177165D01*
G01X180098Y462538D02*
X180265Y462663D01*
X180390Y462872D01*
X180473Y463163D01*
X180390Y463413D01*
X180223Y463580D01*
X179932Y463705D01*
X178807D01*
Y461205D01*
X180182D01*
X180473Y461372D01*
X180640Y461622D01*
X180723Y461913D01*
X180640Y462205D01*
X180390Y462455D01*
X180098Y462538D01*
X178807D01*
G01X182865Y461205D02*
Y463705D01*
X182365Y463205D01*
G01Y461205D02*
X183365D01*
G01X185965D02*
Y463705D01*
X185465Y463205D01*
G01Y461205D02*
X186465D01*
G01X216955Y426053D02*
Y428553D01*
X217996D01*
X218330Y428428D01*
X218538Y428261D01*
X218621Y427928D01*
X218538Y427595D01*
X218288Y427386D01*
X217996Y427261D01*
X216955D01*
G01X217996D02*
X218621Y426053D01*
G01X220888D02*
Y428553D01*
X220388Y428053D01*
G01Y426053D02*
X221388D01*
G01X224905Y428345D02*
X224655Y428470D01*
X224363Y428553D01*
X224030D01*
X223655Y428428D01*
X223363Y428220D01*
X223155Y427970D01*
X222988Y427553D01*
X222946Y427178D01*
X223030Y426803D01*
X223155Y426553D01*
X223405Y426303D01*
X223696Y426136D01*
X223988Y426053D01*
X224280D01*
X224571Y426136D01*
X224821Y426261D01*
X225030Y426428D01*
G01X226171Y426553D02*
X226421Y426261D01*
X226755Y426095D01*
X227130Y426053D01*
X227463Y426095D01*
X227796Y426303D01*
X228005Y426553D01*
X228046Y426803D01*
X227963Y427095D01*
X227671Y427303D01*
X227380Y427386D01*
X227005D01*
G01X227380D02*
X227630Y427511D01*
X227838Y427720D01*
X227921Y427970D01*
X227838Y428220D01*
X227630Y428428D01*
X227255Y428553D01*
X226880Y428511D01*
X226505Y428345D01*
G01X230105Y426053D02*
X230188Y426595D01*
X230313Y427053D01*
X230480Y427470D01*
X230688Y427928D01*
X231021Y428553D01*
X229355D01*
G01X217282Y433421D02*
Y435921D01*
X218323D01*
X218657Y435796D01*
X218865Y435629D01*
X218948Y435296D01*
X218865Y434963D01*
X218615Y434754D01*
X218323Y434629D01*
X217282D01*
G01X218323D02*
X218948Y433421D01*
G01X221215Y435921D02*
Y433421D01*
G01X220257Y435921D02*
X222173D01*
G01X223398Y433921D02*
X223648Y433629D01*
X223982Y433463D01*
X224357Y433421D01*
X224690Y433463D01*
X225023Y433671D01*
X225232Y433921D01*
X225273Y434171D01*
X225190Y434463D01*
X224898Y434671D01*
X224607Y434754D01*
X224232D01*
G01X224607D02*
X224857Y434879D01*
X225065Y435088D01*
X225148Y435338D01*
X225065Y435588D01*
X224857Y435796D01*
X224482Y435921D01*
X224107Y435879D01*
X223732Y435713D01*
G01X227332Y433421D02*
X227415Y433963D01*
X227540Y434421D01*
X227707Y434838D01*
X227915Y435296D01*
X228248Y435921D01*
X226582D01*
G01X201655Y414196D02*
X201405Y414321D01*
X201113Y414404D01*
X200780D01*
X200405Y414279D01*
X200113Y414071D01*
X199905Y413821D01*
X199738Y413404D01*
X199696Y413029D01*
X199780Y412654D01*
X199905Y412404D01*
X200155Y412154D01*
X200446Y411987D01*
X200738Y411904D01*
X201030D01*
X201321Y411987D01*
X201571Y412112D01*
X201780Y412279D01*
G01X203838Y411904D02*
Y414404D01*
X203338Y413904D01*
G01Y411904D02*
X204338D01*
G01X207855Y414196D02*
X207605Y414321D01*
X207313Y414404D01*
X206980D01*
X206605Y414279D01*
X206313Y414071D01*
X206105Y413821D01*
X205938Y413404D01*
X205896Y413029D01*
X205980Y412654D01*
X206105Y412404D01*
X206355Y412154D01*
X206646Y411987D01*
X206938Y411904D01*
X207230D01*
X207521Y411987D01*
X207771Y412112D01*
X207980Y412279D01*
G01X209246Y413987D02*
X209496Y414237D01*
X209788Y414362D01*
X210121Y414404D01*
X210538Y414321D01*
X210830Y414112D01*
X210913Y413862D01*
X210871Y413612D01*
X210705Y413404D01*
X209871Y412987D01*
X209496Y412696D01*
X209246Y412279D01*
X209163Y411904D01*
X210913D01*
G01X212221Y412404D02*
X212471Y412112D01*
X212805Y411946D01*
X213180Y411904D01*
X213513Y411946D01*
X213846Y412154D01*
X214055Y412404D01*
X214096Y412654D01*
X214013Y412946D01*
X213721Y413154D01*
X213430Y413237D01*
X213055D01*
G01X213430D02*
X213680Y413362D01*
X213888Y413571D01*
X213971Y413821D01*
X213888Y414071D01*
X213680Y414279D01*
X213305Y414404D01*
X212930Y414362D01*
X212555Y414196D01*
G01X218982Y439713D02*
X218732Y439838D01*
X218440Y439921D01*
X218107D01*
X217732Y439796D01*
X217440Y439588D01*
X217232Y439338D01*
X217065Y438921D01*
X217023Y438546D01*
X217107Y438171D01*
X217232Y437921D01*
X217482Y437671D01*
X217773Y437504D01*
X218065Y437421D01*
X218357D01*
X218648Y437504D01*
X218898Y437629D01*
X219107Y437796D01*
G01X221165Y437421D02*
Y439921D01*
X220665Y439421D01*
G01Y437421D02*
X221665D01*
G01X225182Y439713D02*
X224932Y439838D01*
X224640Y439921D01*
X224307D01*
X223932Y439796D01*
X223640Y439588D01*
X223432Y439338D01*
X223265Y438921D01*
X223223Y438546D01*
X223307Y438171D01*
X223432Y437921D01*
X223682Y437671D01*
X223973Y437504D01*
X224265Y437421D01*
X224557D01*
X224848Y437504D01*
X225098Y437629D01*
X225307Y437796D01*
G01X227365Y437421D02*
Y439921D01*
X226865Y439421D01*
G01Y437421D02*
X227865D01*
G01X229673Y439504D02*
X229923Y439754D01*
X230215Y439879D01*
X230548Y439921D01*
X230965Y439838D01*
X231257Y439629D01*
X231340Y439379D01*
X231298Y439129D01*
X231132Y438921D01*
X230298Y438504D01*
X229923Y438213D01*
X229673Y437796D01*
X229590Y437421D01*
X231340D01*
G01X189154Y429605D02*
X189029Y429355D01*
X188946Y429063D01*
Y428730D01*
X189071Y428355D01*
X189279Y428063D01*
X189529Y427855D01*
X189946Y427688D01*
X190321Y427646D01*
X190696Y427730D01*
X190946Y427855D01*
X191196Y428105D01*
X191363Y428396D01*
X191446Y428688D01*
Y428980D01*
X191363Y429271D01*
X191238Y429521D01*
X191071Y429730D01*
G01X191446Y431788D02*
X188946D01*
X189446Y431288D01*
G01X191446D02*
Y432288D01*
G01X189154Y435805D02*
X189029Y435555D01*
X188946Y435263D01*
Y434930D01*
X189071Y434555D01*
X189279Y434263D01*
X189529Y434055D01*
X189946Y433888D01*
X190321Y433846D01*
X190696Y433930D01*
X190946Y434055D01*
X191196Y434305D01*
X191363Y434596D01*
X191446Y434888D01*
Y435180D01*
X191363Y435471D01*
X191238Y435721D01*
X191071Y435930D01*
G01X191446Y437988D02*
X191404Y438280D01*
X191279Y438613D01*
X191071Y438821D01*
X190779Y438905D01*
X190488Y438821D01*
X190238Y438571D01*
X190113Y438196D01*
Y437780D01*
X190029Y437530D01*
X189821Y437321D01*
X189529Y437238D01*
X189238Y437363D01*
X189029Y437655D01*
X188946Y437988D01*
X189029Y438321D01*
X189238Y438613D01*
X189529Y438738D01*
X189821Y438655D01*
X190029Y438446D01*
X190113Y438196D01*
Y437780D01*
X190238Y437405D01*
X190488Y437155D01*
X190779Y437071D01*
X191071Y437155D01*
X191279Y437363D01*
X191404Y437696D01*
X191446Y437988D01*
G01X177554Y431605D02*
X177429Y431355D01*
X177346Y431063D01*
Y430730D01*
X177471Y430355D01*
X177679Y430063D01*
X177929Y429855D01*
X178346Y429688D01*
X178721Y429646D01*
X179096Y429730D01*
X179346Y429855D01*
X179596Y430105D01*
X179763Y430396D01*
X179846Y430688D01*
Y430980D01*
X179763Y431271D01*
X179638Y431521D01*
X179471Y431730D01*
G01X179846Y433788D02*
X177346D01*
X177846Y433288D01*
G01X179846D02*
Y434288D01*
G01X177554Y437805D02*
X177429Y437555D01*
X177346Y437263D01*
Y436930D01*
X177471Y436555D01*
X177679Y436263D01*
X177929Y436055D01*
X178346Y435888D01*
X178721Y435846D01*
X179096Y435930D01*
X179346Y436055D01*
X179596Y436305D01*
X179763Y436596D01*
X179846Y436888D01*
Y437180D01*
X179763Y437471D01*
X179638Y437721D01*
X179471Y437930D01*
G01X179554Y439280D02*
X179763Y439571D01*
X179846Y439905D01*
X179763Y440238D01*
X179513Y440530D01*
X179138Y440738D01*
X178763Y440821D01*
X178304D01*
X177929Y440738D01*
X177596Y440530D01*
X177429Y440280D01*
X177346Y439988D01*
X177429Y439655D01*
X177596Y439405D01*
X177846Y439238D01*
X178179Y439155D01*
X178471Y439238D01*
X178763Y439446D01*
X178929Y439696D01*
X178971Y439988D01*
X178888Y440321D01*
X178679Y440571D01*
X178304Y440821D01*
G01X194254Y432905D02*
X194129Y432655D01*
X194046Y432363D01*
Y432030D01*
X194171Y431655D01*
X194379Y431363D01*
X194629Y431155D01*
X195046Y430988D01*
X195421Y430946D01*
X195796Y431030D01*
X196046Y431155D01*
X196296Y431405D01*
X196463Y431696D01*
X196546Y431988D01*
Y432280D01*
X196463Y432571D01*
X196338Y432821D01*
X196171Y433030D01*
G01X196546Y435088D02*
X194046D01*
X194546Y434588D01*
G01X196546D02*
Y435588D01*
G01X194254Y439105D02*
X194129Y438855D01*
X194046Y438563D01*
Y438230D01*
X194171Y437855D01*
X194379Y437563D01*
X194629Y437355D01*
X195046Y437188D01*
X195421Y437146D01*
X195796Y437230D01*
X196046Y437355D01*
X196296Y437605D01*
X196463Y437896D01*
X196546Y438188D01*
Y438480D01*
X196463Y438771D01*
X196338Y439021D01*
X196171Y439230D01*
G01X196546Y441288D02*
X194046D01*
X194546Y440788D01*
G01X196546D02*
Y441788D01*
G01X194046Y444388D02*
X194129Y444055D01*
X194338Y443805D01*
X194588Y443638D01*
X194921Y443513D01*
X195296Y443471D01*
X195671Y443513D01*
X196004Y443638D01*
X196254Y443805D01*
X196463Y444055D01*
X196546Y444388D01*
X196463Y444721D01*
X196254Y444971D01*
X196004Y445138D01*
X195671Y445263D01*
X195296Y445305D01*
X194921Y445263D01*
X194588Y445138D01*
X194338Y444971D01*
X194129Y444721D01*
X194046Y444388D01*
G01X198354Y433205D02*
X198229Y432955D01*
X198146Y432663D01*
Y432330D01*
X198271Y431955D01*
X198479Y431663D01*
X198729Y431455D01*
X199146Y431288D01*
X199521Y431246D01*
X199896Y431330D01*
X200146Y431455D01*
X200396Y431705D01*
X200563Y431996D01*
X200646Y432288D01*
Y432580D01*
X200563Y432871D01*
X200438Y433121D01*
X200271Y433330D01*
G01X200646Y435388D02*
X198146D01*
X198646Y434888D01*
G01X200646D02*
Y435888D01*
G01X198354Y439405D02*
X198229Y439155D01*
X198146Y438863D01*
Y438530D01*
X198271Y438155D01*
X198479Y437863D01*
X198729Y437655D01*
X199146Y437488D01*
X199521Y437446D01*
X199896Y437530D01*
X200146Y437655D01*
X200396Y437905D01*
X200563Y438196D01*
X200646Y438488D01*
Y438780D01*
X200563Y439071D01*
X200438Y439321D01*
X200271Y439530D01*
G01X200646Y441588D02*
X198146D01*
X198646Y441088D01*
G01X200646D02*
Y442088D01*
G01Y444688D02*
X198146D01*
X198646Y444188D01*
G01X200646D02*
Y445188D01*
G01X200393Y454800D02*
X200143Y454925D01*
X199851Y455008D01*
X199518D01*
X199143Y454883D01*
X198851Y454675D01*
X198643Y454425D01*
X198476Y454008D01*
X198434Y453633D01*
X198518Y453258D01*
X198643Y453008D01*
X198893Y452758D01*
X199184Y452591D01*
X199476Y452508D01*
X199768D01*
X200059Y452591D01*
X200309Y452716D01*
X200518Y452883D01*
G01X202576Y452508D02*
Y455008D01*
X202076Y454508D01*
G01Y452508D02*
X203076D01*
G01X206009Y453841D02*
X206176Y453966D01*
X206301Y454175D01*
X206384Y454466D01*
X206301Y454716D01*
X206134Y454883D01*
X205843Y455008D01*
X204718D01*
Y452508D01*
X206093D01*
X206384Y452675D01*
X206551Y452925D01*
X206634Y453216D01*
X206551Y453508D01*
X206301Y453758D01*
X206009Y453841D01*
X204718D01*
G01X208776Y452508D02*
Y455008D01*
X208276Y454508D01*
G01Y452508D02*
X209276D01*
G01X211876D02*
Y455008D01*
X211376Y454508D01*
G01Y452508D02*
X212376D01*
G01X197054Y461835D02*
X196929Y461585D01*
X196846Y461293D01*
Y460960D01*
X196971Y460585D01*
X197179Y460293D01*
X197429Y460085D01*
X197846Y459918D01*
X198221Y459876D01*
X198596Y459960D01*
X198846Y460085D01*
X199096Y460335D01*
X199263Y460626D01*
X199346Y460918D01*
Y461210D01*
X199263Y461501D01*
X199138Y461751D01*
X198971Y461960D01*
G01X199346Y464018D02*
X196846D01*
X197346Y463518D01*
G01X199346D02*
Y464518D01*
G01X197263Y466326D02*
X197013Y466576D01*
X196888Y466868D01*
X196846Y467201D01*
X196929Y467618D01*
X197138Y467910D01*
X197388Y467993D01*
X197638Y467951D01*
X197846Y467785D01*
X198263Y466951D01*
X198554Y466576D01*
X198971Y466326D01*
X199346Y466243D01*
Y467993D01*
G01X196846Y468968D02*
X199346Y469551D01*
X196846Y470218D01*
X199346Y470885D01*
X196846Y471468D01*
G01X199346Y473818D02*
X196846D01*
X198638Y472276D01*
Y474360D01*
G01X207052Y419437D02*
X206927Y419187D01*
X206844Y418895D01*
Y418562D01*
X206969Y418187D01*
X207177Y417895D01*
X207427Y417687D01*
X207844Y417520D01*
X208219Y417478D01*
X208594Y417562D01*
X208844Y417687D01*
X209094Y417937D01*
X209261Y418228D01*
X209344Y418520D01*
Y418812D01*
X209261Y419103D01*
X209136Y419353D01*
X208969Y419562D01*
G01X209344Y421620D02*
X206844D01*
X207344Y421120D01*
G01X209344D02*
Y422120D01*
G01X207052Y425637D02*
X206927Y425387D01*
X206844Y425095D01*
Y424762D01*
X206969Y424387D01*
X207177Y424095D01*
X207427Y423887D01*
X207844Y423720D01*
X208219Y423678D01*
X208594Y423762D01*
X208844Y423887D01*
X209094Y424137D01*
X209261Y424428D01*
X209344Y424720D01*
Y425012D01*
X209261Y425303D01*
X209136Y425553D01*
X208969Y425762D01*
G01X209344Y427820D02*
X206844D01*
X207344Y427320D01*
G01X209344D02*
Y428320D01*
G01X208302Y430128D02*
X208011Y430420D01*
X207844Y430670D01*
X207761Y431003D01*
X207844Y431295D01*
X208011Y431503D01*
X208261Y431670D01*
X208552Y431712D01*
X208802Y431670D01*
X209052Y431503D01*
X209261Y431253D01*
X209344Y430962D01*
X209261Y430628D01*
X209011Y430337D01*
X208636Y430170D01*
X208219Y430128D01*
X207677Y430212D01*
X207386Y430337D01*
X207094Y430545D01*
X206886Y430837D01*
X206844Y431128D01*
X206927Y431420D01*
X207136Y431628D01*
G01X202946Y459885D02*
X200446D01*
Y460926D01*
X200571Y461260D01*
X200738Y461468D01*
X201071Y461551D01*
X201404Y461468D01*
X201613Y461218D01*
X201738Y460926D01*
Y459885D01*
G01Y460926D02*
X202946Y461551D01*
G01Y463818D02*
X200446D01*
X200946Y463318D01*
G01X202946D02*
Y464318D01*
G01X200863Y466126D02*
X200613Y466376D01*
X200488Y466668D01*
X200446Y467001D01*
X200529Y467418D01*
X200738Y467710D01*
X200988Y467793D01*
X201238Y467751D01*
X201446Y467585D01*
X201863Y466751D01*
X202154Y466376D01*
X202571Y466126D01*
X202946Y466043D01*
Y467793D01*
G01X200446Y468768D02*
X202946Y469351D01*
X200446Y470018D01*
X202946Y470685D01*
X200446Y471268D01*
G01X200863Y472326D02*
X200613Y472576D01*
X200488Y472868D01*
X200446Y473201D01*
X200529Y473618D01*
X200738Y473910D01*
X200988Y473993D01*
X201238Y473951D01*
X201446Y473785D01*
X201863Y472951D01*
X202154Y472576D01*
X202571Y472326D01*
X202946Y472243D01*
Y473993D01*
G01X200446Y476218D02*
X200529Y475885D01*
X200738Y475635D01*
X200988Y475468D01*
X201321Y475343D01*
X201696Y475301D01*
X202071Y475343D01*
X202404Y475468D01*
X202654Y475635D01*
X202863Y475885D01*
X202946Y476218D01*
X202863Y476551D01*
X202654Y476801D01*
X202404Y476968D01*
X202071Y477093D01*
X201696Y477135D01*
X201321Y477093D01*
X200988Y476968D01*
X200738Y476801D01*
X200529Y476551D01*
X200446Y476218D01*
G01X211098Y435967D02*
X210973Y435717D01*
X210890Y435425D01*
Y435092D01*
X211015Y434717D01*
X211223Y434425D01*
X211473Y434217D01*
X211890Y434050D01*
X212265Y434008D01*
X212640Y434092D01*
X212890Y434217D01*
X213140Y434467D01*
X213307Y434758D01*
X213390Y435050D01*
Y435342D01*
X213307Y435633D01*
X213182Y435883D01*
X213015Y436092D01*
G01X213390Y437358D02*
X210890D01*
Y438942D01*
G01X212098Y438358D02*
Y437358D01*
G01X213390Y441250D02*
X210890D01*
X211390Y440750D01*
G01X213390D02*
Y441750D01*
G01X211307Y443558D02*
X211057Y443808D01*
X210932Y444100D01*
X210890Y444433D01*
X210973Y444850D01*
X211182Y445142D01*
X211432Y445225D01*
X211682Y445183D01*
X211890Y445017D01*
X212307Y444183D01*
X212598Y443808D01*
X213015Y443558D01*
X213390Y443475D01*
Y445225D01*
G01X186711Y451031D02*
X186461Y451156D01*
X186169Y451239D01*
X185836D01*
X185461Y451114D01*
X185169Y450906D01*
X184961Y450656D01*
X184794Y450239D01*
X184752Y449864D01*
X184836Y449489D01*
X184961Y449239D01*
X185211Y448989D01*
X185502Y448822D01*
X185794Y448739D01*
X186086D01*
X186377Y448822D01*
X186627Y448947D01*
X186836Y449114D01*
G01X188102Y448739D02*
Y451239D01*
X189686D01*
G01X189102Y450031D02*
X188102D01*
G01X191202Y450822D02*
X191452Y451072D01*
X191744Y451197D01*
X192077Y451239D01*
X192494Y451156D01*
X192786Y450947D01*
X192869Y450697D01*
X192827Y450447D01*
X192661Y450239D01*
X191827Y449822D01*
X191452Y449531D01*
X191202Y449114D01*
X191119Y448739D01*
X192869D01*
G01X194302Y450822D02*
X194552Y451072D01*
X194844Y451197D01*
X195177Y451239D01*
X195594Y451156D01*
X195886Y450947D01*
X195969Y450697D01*
X195927Y450447D01*
X195761Y450239D01*
X194927Y449822D01*
X194552Y449531D01*
X194302Y449114D01*
X194219Y448739D01*
X195969D01*
G01X174796Y450946D02*
X174546Y451071D01*
X174254Y451154D01*
X173921D01*
X173546Y451029D01*
X173254Y450821D01*
X173046Y450571D01*
X172879Y450154D01*
X172837Y449779D01*
X172921Y449404D01*
X173046Y449154D01*
X173296Y448904D01*
X173587Y448737D01*
X173879Y448654D01*
X174171D01*
X174462Y448737D01*
X174712Y448862D01*
X174921Y449029D01*
G01X176187Y448654D02*
Y451154D01*
X177771D01*
G01X177187Y449946D02*
X176187D01*
G01X179287Y450737D02*
X179537Y450987D01*
X179829Y451112D01*
X180162Y451154D01*
X180579Y451071D01*
X180871Y450862D01*
X180954Y450612D01*
X180912Y450362D01*
X180746Y450154D01*
X179912Y449737D01*
X179537Y449446D01*
X179287Y449029D01*
X179204Y448654D01*
X180954D01*
G01X183179D02*
Y451154D01*
X182679Y450654D01*
G01Y448654D02*
X183679D01*
G01X218696Y410118D02*
X217030D01*
Y412618D01*
X218696D01*
G01X218030Y411410D02*
X217030D01*
G01X220046Y412618D02*
Y410826D01*
X220213Y410451D01*
X220546Y410201D01*
X220963Y410118D01*
X221380Y410201D01*
X221713Y410451D01*
X221880Y410826D01*
Y412618D01*
G01X224063Y410118D02*
Y412618D01*
X223563Y412118D01*
G01Y410118D02*
X224563D01*
G01X228080Y412410D02*
X227830Y412535D01*
X227538Y412618D01*
X227205D01*
X226830Y412493D01*
X226538Y412285D01*
X226330Y412035D01*
X226163Y411618D01*
X226121Y411243D01*
X226205Y410868D01*
X226330Y410618D01*
X226580Y410368D01*
X226871Y410201D01*
X227163Y410118D01*
X227455D01*
X227746Y410201D01*
X227996Y410326D01*
X228205Y410493D01*
G01X229471Y412201D02*
X229721Y412451D01*
X230013Y412576D01*
X230346Y412618D01*
X230763Y412535D01*
X231055Y412326D01*
X231138Y412076D01*
X231096Y411826D01*
X230930Y411618D01*
X230096Y411201D01*
X229721Y410910D01*
X229471Y410493D01*
X229388Y410118D01*
X231138D01*
G01X194598Y458775D02*
Y457109D01*
X192098D01*
Y458775D01*
G01X193306Y458109D02*
Y457109D01*
G01X192098Y460125D02*
X193890D01*
X194265Y460292D01*
X194515Y460625D01*
X194598Y461042D01*
X194515Y461459D01*
X194265Y461792D01*
X193890Y461959D01*
X192098D01*
G01X194598Y464142D02*
X192098D01*
X192598Y463642D01*
G01X194598D02*
Y464642D01*
G01X193265Y467575D02*
X193140Y467742D01*
X192931Y467867D01*
X192640Y467950D01*
X192390Y467867D01*
X192223Y467700D01*
X192098Y467409D01*
Y466284D01*
X194598D01*
Y467659D01*
X194431Y467950D01*
X194181Y468117D01*
X193890Y468200D01*
X193598Y468117D01*
X193348Y467867D01*
X193265Y467575D01*
Y466284D01*
G01X194598Y470342D02*
X192098D01*
X192598Y469842D01*
G01X194598D02*
Y470842D01*
G01X173175Y481370D02*
X170675D01*
Y482411D01*
X170800Y482745D01*
X170967Y482953D01*
X171300Y483036D01*
X171633Y482953D01*
X171842Y482703D01*
X171967Y482411D01*
Y481370D01*
G01Y482411D02*
X173175Y483036D01*
G01Y485303D02*
X170675D01*
X171175Y484803D01*
G01X173175D02*
Y485803D01*
G01X171842Y488736D02*
X171717Y488903D01*
X171508Y489028D01*
X171217Y489111D01*
X170967Y489028D01*
X170800Y488861D01*
X170675Y488570D01*
Y487445D01*
X173175D01*
Y488820D01*
X173008Y489111D01*
X172758Y489278D01*
X172467Y489361D01*
X172175Y489278D01*
X171925Y489028D01*
X171842Y488736D01*
Y487445D01*
G01X172800Y490586D02*
X173008Y490836D01*
X173133Y491128D01*
X173175Y491503D01*
X173092Y491878D01*
X172925Y492170D01*
X172633Y492378D01*
X172300Y492420D01*
X171967Y492336D01*
X171758Y492128D01*
X171592Y491836D01*
X171550Y491545D01*
X171592Y491253D01*
X171758Y490878D01*
X170675Y491003D01*
Y492128D01*
G01X176675Y481370D02*
X174175D01*
Y482411D01*
X174300Y482745D01*
X174467Y482953D01*
X174800Y483036D01*
X175133Y482953D01*
X175342Y482703D01*
X175467Y482411D01*
Y481370D01*
G01Y482411D02*
X176675Y483036D01*
G01Y485303D02*
X174175D01*
X174675Y484803D01*
G01X176675D02*
Y485803D01*
G01X175342Y488736D02*
X175217Y488903D01*
X175008Y489028D01*
X174717Y489111D01*
X174467Y489028D01*
X174300Y488861D01*
X174175Y488570D01*
Y487445D01*
X176675D01*
Y488820D01*
X176508Y489111D01*
X176258Y489278D01*
X175967Y489361D01*
X175675Y489278D01*
X175425Y489028D01*
X175342Y488736D01*
Y487445D01*
G01X174592Y490711D02*
X174342Y490961D01*
X174217Y491253D01*
X174175Y491586D01*
X174258Y492003D01*
X174467Y492295D01*
X174717Y492378D01*
X174967Y492336D01*
X175175Y492170D01*
X175592Y491336D01*
X175883Y490961D01*
X176300Y490711D01*
X176675Y490628D01*
Y492378D01*
G01X190096Y490541D02*
X189971Y490291D01*
X189888Y489999D01*
Y489666D01*
X190013Y489291D01*
X190221Y488999D01*
X190471Y488791D01*
X190888Y488624D01*
X191263Y488582D01*
X191638Y488666D01*
X191888Y488791D01*
X192138Y489041D01*
X192305Y489332D01*
X192388Y489624D01*
Y489916D01*
X192305Y490207D01*
X192180Y490457D01*
X192013Y490666D01*
G01X192388Y492724D02*
X189888D01*
X190388Y492224D01*
G01X192388D02*
Y493224D01*
G01X191055Y496157D02*
X190930Y496324D01*
X190721Y496449D01*
X190430Y496532D01*
X190180Y496449D01*
X190013Y496282D01*
X189888Y495991D01*
Y494866D01*
X192388D01*
Y496241D01*
X192221Y496532D01*
X191971Y496699D01*
X191680Y496782D01*
X191388Y496699D01*
X191138Y496449D01*
X191055Y496157D01*
Y494866D01*
G01X190305Y498132D02*
X190055Y498382D01*
X189930Y498674D01*
X189888Y499007D01*
X189971Y499424D01*
X190180Y499716D01*
X190430Y499799D01*
X190680Y499757D01*
X190888Y499591D01*
X191305Y498757D01*
X191596Y498382D01*
X192013Y498132D01*
X192388Y498049D01*
Y499799D01*
G01Y502024D02*
X189888D01*
X190388Y501524D01*
G01X192388D02*
Y502524D01*
G01X186196Y490541D02*
X186071Y490291D01*
X185988Y489999D01*
Y489666D01*
X186113Y489291D01*
X186321Y488999D01*
X186571Y488791D01*
X186988Y488624D01*
X187363Y488582D01*
X187738Y488666D01*
X187988Y488791D01*
X188238Y489041D01*
X188405Y489332D01*
X188488Y489624D01*
Y489916D01*
X188405Y490207D01*
X188280Y490457D01*
X188113Y490666D01*
G01X188488Y492724D02*
X185988D01*
X186488Y492224D01*
G01X188488D02*
Y493224D01*
G01X187155Y496157D02*
X187030Y496324D01*
X186821Y496449D01*
X186530Y496532D01*
X186280Y496449D01*
X186113Y496282D01*
X185988Y495991D01*
Y494866D01*
X188488D01*
Y496241D01*
X188321Y496532D01*
X188071Y496699D01*
X187780Y496782D01*
X187488Y496699D01*
X187238Y496449D01*
X187155Y496157D01*
Y494866D01*
G01X186405Y498132D02*
X186155Y498382D01*
X186030Y498674D01*
X185988Y499007D01*
X186071Y499424D01*
X186280Y499716D01*
X186530Y499799D01*
X186780Y499757D01*
X186988Y499591D01*
X187405Y498757D01*
X187696Y498382D01*
X188113Y498132D01*
X188488Y498049D01*
Y499799D01*
G01X185988Y502024D02*
X186071Y501691D01*
X186280Y501441D01*
X186530Y501274D01*
X186863Y501149D01*
X187238Y501107D01*
X187613Y501149D01*
X187946Y501274D01*
X188196Y501441D01*
X188405Y501691D01*
X188488Y502024D01*
X188405Y502357D01*
X188196Y502607D01*
X187946Y502774D01*
X187613Y502899D01*
X187238Y502941D01*
X186863Y502899D01*
X186530Y502774D01*
X186280Y502607D01*
X186071Y502357D01*
X185988Y502024D01*
G01X196145Y478098D02*
X196020Y477848D01*
X195937Y477556D01*
Y477223D01*
X196062Y476848D01*
X196270Y476556D01*
X196520Y476348D01*
X196937Y476181D01*
X197312Y476139D01*
X197687Y476223D01*
X197937Y476348D01*
X198187Y476598D01*
X198354Y476889D01*
X198437Y477181D01*
Y477473D01*
X198354Y477764D01*
X198229Y478014D01*
X198062Y478223D01*
G01X198437Y480281D02*
X195937D01*
X196437Y479781D01*
G01X198437D02*
Y480781D01*
G01X197104Y483714D02*
X196979Y483881D01*
X196770Y484006D01*
X196479Y484089D01*
X196229Y484006D01*
X196062Y483839D01*
X195937Y483548D01*
Y482423D01*
X198437D01*
Y483798D01*
X198270Y484089D01*
X198020Y484256D01*
X197729Y484339D01*
X197437Y484256D01*
X197187Y484006D01*
X197104Y483714D01*
Y482423D01*
G01X198062Y485564D02*
X198270Y485814D01*
X198395Y486106D01*
X198437Y486481D01*
X198354Y486856D01*
X198187Y487148D01*
X197895Y487356D01*
X197562Y487398D01*
X197229Y487314D01*
X197020Y487106D01*
X196854Y486814D01*
X196812Y486523D01*
X196854Y486231D01*
X197020Y485856D01*
X195937Y485981D01*
Y487106D01*
G01X200374Y480695D02*
X200249Y480445D01*
X200166Y480153D01*
Y479820D01*
X200291Y479445D01*
X200499Y479153D01*
X200749Y478945D01*
X201166Y478778D01*
X201541Y478736D01*
X201916Y478820D01*
X202166Y478945D01*
X202416Y479195D01*
X202583Y479486D01*
X202666Y479778D01*
Y480070D01*
X202583Y480361D01*
X202458Y480611D01*
X202291Y480820D01*
G01X202666Y482878D02*
X200166D01*
X200666Y482378D01*
G01X202666D02*
Y483378D01*
G01X201333Y486311D02*
X201208Y486478D01*
X200999Y486603D01*
X200708Y486686D01*
X200458Y486603D01*
X200291Y486436D01*
X200166Y486145D01*
Y485020D01*
X202666D01*
Y486395D01*
X202499Y486686D01*
X202249Y486853D01*
X201958Y486936D01*
X201666Y486853D01*
X201416Y486603D01*
X201333Y486311D01*
Y485020D01*
G01X201624Y488286D02*
X201333Y488578D01*
X201166Y488828D01*
X201083Y489161D01*
X201166Y489453D01*
X201333Y489661D01*
X201583Y489828D01*
X201874Y489870D01*
X202124Y489828D01*
X202374Y489661D01*
X202583Y489411D01*
X202666Y489120D01*
X202583Y488786D01*
X202333Y488495D01*
X201958Y488328D01*
X201541Y488286D01*
X200999Y488370D01*
X200708Y488495D01*
X200416Y488703D01*
X200208Y488995D01*
X200166Y489286D01*
X200249Y489578D01*
X200458Y489786D01*
G01X188071Y477804D02*
X187946Y477554D01*
X187863Y477262D01*
Y476929D01*
X187988Y476554D01*
X188196Y476262D01*
X188446Y476054D01*
X188863Y475887D01*
X189238Y475845D01*
X189613Y475929D01*
X189863Y476054D01*
X190113Y476304D01*
X190280Y476595D01*
X190363Y476887D01*
Y477179D01*
X190280Y477470D01*
X190155Y477720D01*
X189988Y477929D01*
G01X190363Y479987D02*
X187863D01*
X188363Y479487D01*
G01X190363D02*
Y480487D01*
G01X189030Y483420D02*
X188905Y483587D01*
X188696Y483712D01*
X188405Y483795D01*
X188155Y483712D01*
X187988Y483545D01*
X187863Y483254D01*
Y482129D01*
X190363D01*
Y483504D01*
X190196Y483795D01*
X189946Y483962D01*
X189655Y484045D01*
X189363Y483962D01*
X189113Y483712D01*
X189030Y483420D01*
Y482129D01*
G01X188280Y485395D02*
X188030Y485645D01*
X187905Y485937D01*
X187863Y486270D01*
X187946Y486687D01*
X188155Y486979D01*
X188405Y487062D01*
X188655Y487020D01*
X188863Y486854D01*
X189280Y486020D01*
X189571Y485645D01*
X189988Y485395D01*
X190363Y485312D01*
Y487062D01*
G01X190412Y510960D02*
X190162Y511085D01*
X189870Y511168D01*
X189537D01*
X189162Y511043D01*
X188870Y510835D01*
X188662Y510585D01*
X188495Y510168D01*
X188453Y509793D01*
X188537Y509418D01*
X188662Y509168D01*
X188912Y508918D01*
X189203Y508751D01*
X189495Y508668D01*
X189787D01*
X190078Y508751D01*
X190328Y508876D01*
X190537Y509043D01*
G01X192595Y508668D02*
Y511168D01*
X192095Y510668D01*
G01Y508668D02*
X193095D01*
G01X194653D02*
X195695Y511168D01*
X196737Y508668D01*
G01X196362Y509543D02*
X195028D01*
G01X198795Y508668D02*
Y511168D01*
X198295Y510668D01*
G01Y508668D02*
X199295D01*
G01X201895Y511168D02*
X201562Y511085D01*
X201312Y510876D01*
X201145Y510626D01*
X201020Y510293D01*
X200978Y509918D01*
X201020Y509543D01*
X201145Y509210D01*
X201312Y508960D01*
X201562Y508751D01*
X201895Y508668D01*
X202228Y508751D01*
X202478Y508960D01*
X202645Y509210D01*
X202770Y509543D01*
X202812Y509918D01*
X202770Y510293D01*
X202645Y510626D01*
X202478Y510876D01*
X202228Y511085D01*
X201895Y511168D01*
G01X192071Y478004D02*
X191946Y477754D01*
X191863Y477462D01*
Y477129D01*
X191988Y476754D01*
X192196Y476462D01*
X192446Y476254D01*
X192863Y476087D01*
X193238Y476045D01*
X193613Y476129D01*
X193863Y476254D01*
X194113Y476504D01*
X194280Y476795D01*
X194363Y477087D01*
Y477379D01*
X194280Y477670D01*
X194155Y477920D01*
X193988Y478129D01*
G01X194363Y480187D02*
X191863D01*
X192363Y479687D01*
G01X194363D02*
Y480687D01*
G01X193030Y483620D02*
X192905Y483787D01*
X192696Y483912D01*
X192405Y483995D01*
X192155Y483912D01*
X191988Y483745D01*
X191863Y483454D01*
Y482329D01*
X194363D01*
Y483704D01*
X194196Y483995D01*
X193946Y484162D01*
X193655Y484245D01*
X193363Y484162D01*
X193113Y483912D01*
X193030Y483620D01*
Y482329D01*
G01X193863Y485470D02*
X194155Y485720D01*
X194321Y486054D01*
X194363Y486429D01*
X194321Y486762D01*
X194113Y487095D01*
X193863Y487304D01*
X193613Y487345D01*
X193321Y487262D01*
X193113Y486970D01*
X193030Y486679D01*
Y486304D01*
G01Y486679D02*
X192905Y486929D01*
X192696Y487137D01*
X192446Y487220D01*
X192196Y487137D01*
X191988Y486929D01*
X191863Y486554D01*
X191905Y486179D01*
X192071Y485804D01*
G01X198296Y494041D02*
X198171Y493791D01*
X198088Y493499D01*
Y493166D01*
X198213Y492791D01*
X198421Y492499D01*
X198671Y492291D01*
X199088Y492124D01*
X199463Y492082D01*
X199838Y492166D01*
X200088Y492291D01*
X200338Y492541D01*
X200505Y492832D01*
X200588Y493124D01*
Y493416D01*
X200505Y493707D01*
X200380Y493957D01*
X200213Y494166D01*
G01X198088Y496224D02*
X200588D01*
G01X198088Y495266D02*
Y497182D01*
G01X200296Y498616D02*
X200505Y498907D01*
X200588Y499241D01*
X200505Y499574D01*
X200255Y499866D01*
X199880Y500074D01*
X199505Y500157D01*
X199046D01*
X198671Y500074D01*
X198338Y499866D01*
X198171Y499616D01*
X198088Y499324D01*
X198171Y498991D01*
X198338Y498741D01*
X198588Y498574D01*
X198921Y498491D01*
X199213Y498574D01*
X199505Y498782D01*
X199671Y499032D01*
X199713Y499324D01*
X199630Y499657D01*
X199421Y499907D01*
X199046Y500157D01*
G01X182302Y493486D02*
X182177Y493236D01*
X182094Y492944D01*
Y492611D01*
X182219Y492236D01*
X182427Y491944D01*
X182677Y491736D01*
X183094Y491569D01*
X183469Y491527D01*
X183844Y491611D01*
X184094Y491736D01*
X184344Y491986D01*
X184511Y492277D01*
X184594Y492569D01*
Y492861D01*
X184511Y493152D01*
X184386Y493402D01*
X184219Y493611D01*
G01X182094Y495669D02*
X184594D01*
G01X182094Y494711D02*
Y496627D01*
G01X184594Y498686D02*
X184052Y498769D01*
X183594Y498894D01*
X183177Y499061D01*
X182719Y499269D01*
X182094Y499602D01*
Y497936D01*
G01X178083Y483220D02*
X177958Y482970D01*
X177875Y482678D01*
Y482345D01*
X178000Y481970D01*
X178208Y481678D01*
X178458Y481470D01*
X178875Y481303D01*
X179250Y481261D01*
X179625Y481345D01*
X179875Y481470D01*
X180125Y481720D01*
X180292Y482011D01*
X180375Y482303D01*
Y482595D01*
X180292Y482886D01*
X180167Y483136D01*
X180000Y483345D01*
G01X180375Y485403D02*
X177875D01*
X178375Y484903D01*
G01X180375D02*
Y485903D01*
G01X179042Y488836D02*
X178917Y489003D01*
X178708Y489128D01*
X178417Y489211D01*
X178167Y489128D01*
X178000Y488961D01*
X177875Y488670D01*
Y487545D01*
X180375D01*
Y488920D01*
X180208Y489211D01*
X179958Y489378D01*
X179667Y489461D01*
X179375Y489378D01*
X179125Y489128D01*
X179042Y488836D01*
Y487545D01*
G01X180375Y492103D02*
X177875D01*
X179667Y490561D01*
Y492645D01*
G01X196388Y492291D02*
X193888D01*
Y493332D01*
X194013Y493666D01*
X194180Y493874D01*
X194513Y493957D01*
X194846Y493874D01*
X195055Y493624D01*
X195180Y493332D01*
Y492291D01*
G01Y493332D02*
X196388Y493957D01*
G01X193888Y496224D02*
X196388D01*
G01X193888Y495266D02*
Y497182D01*
G01X195346Y498532D02*
X195055Y498824D01*
X194888Y499074D01*
X194805Y499407D01*
X194888Y499699D01*
X195055Y499907D01*
X195305Y500074D01*
X195596Y500116D01*
X195846Y500074D01*
X196096Y499907D01*
X196305Y499657D01*
X196388Y499366D01*
X196305Y499032D01*
X196055Y498741D01*
X195680Y498574D01*
X195263Y498532D01*
X194721Y498616D01*
X194430Y498741D01*
X194138Y498949D01*
X193930Y499241D01*
X193888Y499532D01*
X193971Y499824D01*
X194180Y500032D01*
G01X190191Y504651D02*
X188525D01*
Y507151D01*
X190191D01*
G01X189525Y505943D02*
X188525D01*
G01X191541Y507151D02*
Y505359D01*
X191708Y504984D01*
X192041Y504734D01*
X192458Y504651D01*
X192875Y504734D01*
X193208Y504984D01*
X193375Y505359D01*
Y507151D01*
G01X195558Y504651D02*
Y507151D01*
X195058Y506651D01*
G01Y504651D02*
X196058D01*
G01X197616D02*
X198658Y507151D01*
X199700Y504651D01*
G01X199325Y505526D02*
X197991D01*
G01X200966Y506734D02*
X201216Y506984D01*
X201508Y507109D01*
X201841Y507151D01*
X202258Y507068D01*
X202550Y506859D01*
X202633Y506609D01*
X202591Y506359D01*
X202425Y506151D01*
X201591Y505734D01*
X201216Y505443D01*
X200966Y505026D01*
X200883Y504651D01*
X202633D01*
G01X225520Y640270D02*
X192820D01*
Y658970D01*
X225520D01*
Y640270D01*
G01X227582Y659170D02*
X260282D01*
Y640470D01*
X227582D01*
Y659170D01*
G01X293917Y18359D02*
X293667Y18484D01*
X293375Y18567D01*
X293042D01*
X292667Y18442D01*
X292375Y18234D01*
X292167Y17984D01*
X292000Y17567D01*
X291958Y17192D01*
X292042Y16817D01*
X292167Y16567D01*
X292417Y16317D01*
X292708Y16150D01*
X293000Y16067D01*
X293292D01*
X293583Y16150D01*
X293833Y16275D01*
X294042Y16442D01*
G01X295308Y18150D02*
X295558Y18400D01*
X295850Y18525D01*
X296183Y18567D01*
X296600Y18484D01*
X296892Y18275D01*
X296975Y18025D01*
X296933Y17775D01*
X296767Y17567D01*
X295933Y17150D01*
X295558Y16859D01*
X295308Y16442D01*
X295225Y16067D01*
X296975D01*
G01X299450Y17317D02*
X300283D01*
Y16567D01*
X300033Y16317D01*
X299742Y16150D01*
X299325Y16067D01*
X298908Y16150D01*
X298617Y16317D01*
X298367Y16567D01*
X298200Y16859D01*
X298117Y17192D01*
Y17484D01*
X298200Y17734D01*
X298367Y18025D01*
X298617Y18275D01*
X298867Y18442D01*
X299200Y18567D01*
X299492D01*
X299825Y18484D01*
X300075Y18317D01*
G01X302300Y16067D02*
Y18567D01*
X301800Y18067D01*
G01Y16067D02*
X302800D01*
G01X304483Y16442D02*
X304733Y16234D01*
X305025Y16109D01*
X305400Y16067D01*
X305775Y16150D01*
X306067Y16317D01*
X306275Y16609D01*
X306317Y16942D01*
X306233Y17275D01*
X306025Y17484D01*
X305733Y17650D01*
X305442Y17692D01*
X305150Y17650D01*
X304775Y17484D01*
X304900Y18567D01*
X306025D01*
G01X276717Y13259D02*
X276467Y13384D01*
X276175Y13467D01*
X275842D01*
X275467Y13342D01*
X275175Y13134D01*
X274967Y12884D01*
X274800Y12467D01*
X274758Y12092D01*
X274842Y11717D01*
X274967Y11467D01*
X275217Y11217D01*
X275508Y11050D01*
X275800Y10967D01*
X276092D01*
X276383Y11050D01*
X276633Y11175D01*
X276842Y11342D01*
G01X278108Y13050D02*
X278358Y13300D01*
X278650Y13425D01*
X278983Y13467D01*
X279400Y13384D01*
X279692Y13175D01*
X279775Y12925D01*
X279733Y12675D01*
X279567Y12467D01*
X278733Y12050D01*
X278358Y11759D01*
X278108Y11342D01*
X278025Y10967D01*
X279775D01*
G01X282250Y12217D02*
X283083D01*
Y11467D01*
X282833Y11217D01*
X282542Y11050D01*
X282125Y10967D01*
X281708Y11050D01*
X281417Y11217D01*
X281167Y11467D01*
X281000Y11759D01*
X280917Y12092D01*
Y12384D01*
X281000Y12634D01*
X281167Y12925D01*
X281417Y13175D01*
X281667Y13342D01*
X282000Y13467D01*
X282292D01*
X282625Y13384D01*
X282875Y13217D01*
G01X285100Y10967D02*
Y13467D01*
X284600Y12967D01*
G01Y10967D02*
X285600D01*
G01X287408Y13050D02*
X287658Y13300D01*
X287950Y13425D01*
X288283Y13467D01*
X288700Y13384D01*
X288992Y13175D01*
X289075Y12925D01*
X289033Y12675D01*
X288867Y12467D01*
X288033Y12050D01*
X287658Y11759D01*
X287408Y11342D01*
X287325Y10967D01*
X289075D01*
G01X274317Y18259D02*
X274067Y18384D01*
X273775Y18467D01*
X273442D01*
X273067Y18342D01*
X272775Y18134D01*
X272567Y17884D01*
X272400Y17467D01*
X272358Y17092D01*
X272442Y16717D01*
X272567Y16467D01*
X272817Y16217D01*
X273108Y16050D01*
X273400Y15967D01*
X273692D01*
X273983Y16050D01*
X274233Y16175D01*
X274442Y16342D01*
G01X275708Y18050D02*
X275958Y18300D01*
X276250Y18425D01*
X276583Y18467D01*
X277000Y18384D01*
X277292Y18175D01*
X277375Y17925D01*
X277333Y17675D01*
X277167Y17467D01*
X276333Y17050D01*
X275958Y16759D01*
X275708Y16342D01*
X275625Y15967D01*
X277375D01*
G01X279850Y17217D02*
X280683D01*
Y16467D01*
X280433Y16217D01*
X280142Y16050D01*
X279725Y15967D01*
X279308Y16050D01*
X279017Y16217D01*
X278767Y16467D01*
X278600Y16759D01*
X278517Y17092D01*
Y17384D01*
X278600Y17634D01*
X278767Y17925D01*
X279017Y18175D01*
X279267Y18342D01*
X279600Y18467D01*
X279892D01*
X280225Y18384D01*
X280475Y18217D01*
G01X282700Y15967D02*
Y18467D01*
X282200Y17967D01*
G01Y15967D02*
X283200D01*
G01X285800D02*
Y18467D01*
X285300Y17967D01*
G01Y15967D02*
X286300D01*
G01X257817Y13559D02*
X257567Y13684D01*
X257275Y13767D01*
X256942D01*
X256567Y13642D01*
X256275Y13434D01*
X256067Y13184D01*
X255900Y12767D01*
X255858Y12392D01*
X255942Y12017D01*
X256067Y11767D01*
X256317Y11517D01*
X256608Y11350D01*
X256900Y11267D01*
X257192D01*
X257483Y11350D01*
X257733Y11475D01*
X257942Y11642D01*
G01X259208Y13350D02*
X259458Y13600D01*
X259750Y13725D01*
X260083Y13767D01*
X260500Y13684D01*
X260792Y13475D01*
X260875Y13225D01*
X260833Y12975D01*
X260667Y12767D01*
X259833Y12350D01*
X259458Y12059D01*
X259208Y11642D01*
X259125Y11267D01*
X260875D01*
G01X263350Y12517D02*
X264183D01*
Y11767D01*
X263933Y11517D01*
X263642Y11350D01*
X263225Y11267D01*
X262808Y11350D01*
X262517Y11517D01*
X262267Y11767D01*
X262100Y12059D01*
X262017Y12392D01*
Y12684D01*
X262100Y12934D01*
X262267Y13225D01*
X262517Y13475D01*
X262767Y13642D01*
X263100Y13767D01*
X263392D01*
X263725Y13684D01*
X263975Y13517D01*
G01X266200Y11267D02*
Y13767D01*
X265700Y13267D01*
G01Y11267D02*
X266700D01*
G01X269300Y13767D02*
X268967Y13684D01*
X268717Y13475D01*
X268550Y13225D01*
X268425Y12892D01*
X268383Y12517D01*
X268425Y12142D01*
X268550Y11809D01*
X268717Y11559D01*
X268967Y11350D01*
X269300Y11267D01*
X269633Y11350D01*
X269883Y11559D01*
X270050Y11809D01*
X270175Y12142D01*
X270217Y12517D01*
X270175Y12892D01*
X270050Y13225D01*
X269883Y13475D01*
X269633Y13684D01*
X269300Y13767D01*
G01X255767Y17959D02*
X255517Y18084D01*
X255225Y18167D01*
X254892D01*
X254517Y18042D01*
X254225Y17834D01*
X254017Y17584D01*
X253850Y17167D01*
X253808Y16792D01*
X253892Y16417D01*
X254017Y16167D01*
X254267Y15917D01*
X254558Y15750D01*
X254850Y15667D01*
X255142D01*
X255433Y15750D01*
X255683Y15875D01*
X255892Y16042D01*
G01X257158Y17750D02*
X257408Y18000D01*
X257700Y18125D01*
X258033Y18167D01*
X258450Y18084D01*
X258742Y17875D01*
X258825Y17625D01*
X258783Y17375D01*
X258617Y17167D01*
X257783Y16750D01*
X257408Y16459D01*
X257158Y16042D01*
X257075Y15667D01*
X258825D01*
G01X261300Y16917D02*
X262133D01*
Y16167D01*
X261883Y15917D01*
X261592Y15750D01*
X261175Y15667D01*
X260758Y15750D01*
X260467Y15917D01*
X260217Y16167D01*
X260050Y16459D01*
X259967Y16792D01*
Y17084D01*
X260050Y17334D01*
X260217Y17625D01*
X260467Y17875D01*
X260717Y18042D01*
X261050Y18167D01*
X261342D01*
X261675Y18084D01*
X261925Y17917D01*
G01X263442Y15959D02*
X263733Y15750D01*
X264067Y15667D01*
X264400Y15750D01*
X264692Y16000D01*
X264900Y16375D01*
X264983Y16750D01*
Y17209D01*
X264900Y17584D01*
X264692Y17917D01*
X264442Y18084D01*
X264150Y18167D01*
X263817Y18084D01*
X263567Y17917D01*
X263400Y17667D01*
X263317Y17334D01*
X263400Y17042D01*
X263608Y16750D01*
X263858Y16584D01*
X264150Y16542D01*
X264483Y16625D01*
X264733Y16834D01*
X264983Y17209D01*
G01X293948Y52802D02*
X293698Y52927D01*
X293406Y53010D01*
X293073D01*
X292698Y52885D01*
X292406Y52677D01*
X292198Y52427D01*
X292031Y52010D01*
X291989Y51635D01*
X292073Y51260D01*
X292198Y51010D01*
X292448Y50760D01*
X292739Y50593D01*
X293031Y50510D01*
X293323D01*
X293614Y50593D01*
X293864Y50718D01*
X294073Y50885D01*
G01X295339Y52593D02*
X295589Y52843D01*
X295881Y52968D01*
X296214Y53010D01*
X296631Y52927D01*
X296923Y52718D01*
X297006Y52468D01*
X296964Y52218D01*
X296798Y52010D01*
X295964Y51593D01*
X295589Y51302D01*
X295339Y50885D01*
X295256Y50510D01*
X297006D01*
G01X299481Y51760D02*
X300314D01*
Y51010D01*
X300064Y50760D01*
X299773Y50593D01*
X299356Y50510D01*
X298939Y50593D01*
X298648Y50760D01*
X298398Y51010D01*
X298231Y51302D01*
X298148Y51635D01*
Y51927D01*
X298231Y52177D01*
X298398Y52468D01*
X298648Y52718D01*
X298898Y52885D01*
X299231Y53010D01*
X299523D01*
X299856Y52927D01*
X300106Y52760D01*
G01X302331Y50510D02*
X302623Y50552D01*
X302956Y50677D01*
X303164Y50885D01*
X303248Y51177D01*
X303164Y51468D01*
X302914Y51718D01*
X302539Y51843D01*
X302123D01*
X301873Y51927D01*
X301664Y52135D01*
X301581Y52427D01*
X301706Y52718D01*
X301998Y52927D01*
X302331Y53010D01*
X302664Y52927D01*
X302956Y52718D01*
X303081Y52427D01*
X302998Y52135D01*
X302789Y51927D01*
X302539Y51843D01*
X302123D01*
X301748Y51718D01*
X301498Y51468D01*
X301414Y51177D01*
X301498Y50885D01*
X301706Y50677D01*
X302039Y50552D01*
X302331Y50510D01*
G01X282573Y50076D02*
X282323Y50201D01*
X282031Y50284D01*
X281698D01*
X281323Y50159D01*
X281031Y49951D01*
X280823Y49701D01*
X280656Y49284D01*
X280614Y48909D01*
X280698Y48534D01*
X280823Y48284D01*
X281073Y48034D01*
X281364Y47867D01*
X281656Y47784D01*
X281948D01*
X282239Y47867D01*
X282489Y47992D01*
X282698Y48159D01*
G01X283964Y49867D02*
X284214Y50117D01*
X284506Y50242D01*
X284839Y50284D01*
X285256Y50201D01*
X285548Y49992D01*
X285631Y49742D01*
X285589Y49492D01*
X285423Y49284D01*
X284589Y48867D01*
X284214Y48576D01*
X283964Y48159D01*
X283881Y47784D01*
X285631D01*
G01X288106Y49034D02*
X288939D01*
Y48284D01*
X288689Y48034D01*
X288398Y47867D01*
X287981Y47784D01*
X287564Y47867D01*
X287273Y48034D01*
X287023Y48284D01*
X286856Y48576D01*
X286773Y48909D01*
Y49201D01*
X286856Y49451D01*
X287023Y49742D01*
X287273Y49992D01*
X287523Y50159D01*
X287856Y50284D01*
X288148D01*
X288481Y50201D01*
X288731Y50034D01*
G01X291456Y47784D02*
Y50284D01*
X289914Y48492D01*
X291998D01*
G01X272384Y53749D02*
X272134Y53874D01*
X271842Y53957D01*
X271509D01*
X271134Y53832D01*
X270842Y53624D01*
X270634Y53374D01*
X270467Y52957D01*
X270425Y52582D01*
X270509Y52207D01*
X270634Y51957D01*
X270884Y51707D01*
X271175Y51540D01*
X271467Y51457D01*
X271759D01*
X272050Y51540D01*
X272300Y51665D01*
X272509Y51832D01*
G01X273775Y53540D02*
X274025Y53790D01*
X274317Y53915D01*
X274650Y53957D01*
X275067Y53874D01*
X275359Y53665D01*
X275442Y53415D01*
X275400Y53165D01*
X275234Y52957D01*
X274400Y52540D01*
X274025Y52249D01*
X273775Y51832D01*
X273692Y51457D01*
X275442D01*
G01X277917Y52707D02*
X278750D01*
Y51957D01*
X278500Y51707D01*
X278209Y51540D01*
X277792Y51457D01*
X277375Y51540D01*
X277084Y51707D01*
X276834Y51957D01*
X276667Y52249D01*
X276584Y52582D01*
Y52874D01*
X276667Y53124D01*
X276834Y53415D01*
X277084Y53665D01*
X277334Y53832D01*
X277667Y53957D01*
X277959D01*
X278292Y53874D01*
X278542Y53707D01*
G01X279850Y51957D02*
X280100Y51665D01*
X280434Y51499D01*
X280809Y51457D01*
X281142Y51499D01*
X281475Y51707D01*
X281684Y51957D01*
X281725Y52207D01*
X281642Y52499D01*
X281350Y52707D01*
X281059Y52790D01*
X280684D01*
G01X281059D02*
X281309Y52915D01*
X281517Y53124D01*
X281600Y53374D01*
X281517Y53624D01*
X281309Y53832D01*
X280934Y53957D01*
X280559Y53915D01*
X280184Y53749D01*
G01X260417Y50313D02*
X260167Y50438D01*
X259875Y50521D01*
X259542D01*
X259167Y50396D01*
X258875Y50188D01*
X258667Y49938D01*
X258500Y49521D01*
X258458Y49146D01*
X258542Y48771D01*
X258667Y48521D01*
X258917Y48271D01*
X259208Y48104D01*
X259500Y48021D01*
X259792D01*
X260083Y48104D01*
X260333Y48229D01*
X260542Y48396D01*
G01X261808Y50104D02*
X262058Y50354D01*
X262350Y50479D01*
X262683Y50521D01*
X263100Y50438D01*
X263392Y50229D01*
X263475Y49979D01*
X263433Y49729D01*
X263267Y49521D01*
X262433Y49104D01*
X262058Y48813D01*
X261808Y48396D01*
X261725Y48021D01*
X263475D01*
G01X265950Y49271D02*
X266783D01*
Y48521D01*
X266533Y48271D01*
X266242Y48104D01*
X265825Y48021D01*
X265408Y48104D01*
X265117Y48271D01*
X264867Y48521D01*
X264700Y48813D01*
X264617Y49146D01*
Y49438D01*
X264700Y49688D01*
X264867Y49979D01*
X265117Y50229D01*
X265367Y50396D01*
X265700Y50521D01*
X265992D01*
X266325Y50438D01*
X266575Y50271D01*
G01X268008Y50104D02*
X268258Y50354D01*
X268550Y50479D01*
X268883Y50521D01*
X269300Y50438D01*
X269592Y50229D01*
X269675Y49979D01*
X269633Y49729D01*
X269467Y49521D01*
X268633Y49104D01*
X268258Y48813D01*
X268008Y48396D01*
X267925Y48021D01*
X269675D01*
G01X256744Y55645D02*
X256494Y55770D01*
X256202Y55853D01*
X255869D01*
X255494Y55728D01*
X255202Y55520D01*
X254994Y55270D01*
X254827Y54853D01*
X254785Y54478D01*
X254869Y54103D01*
X254994Y53853D01*
X255244Y53603D01*
X255535Y53436D01*
X255827Y53353D01*
X256119D01*
X256410Y53436D01*
X256660Y53561D01*
X256869Y53728D01*
G01X258135Y55436D02*
X258385Y55686D01*
X258677Y55811D01*
X259010Y55853D01*
X259427Y55770D01*
X259719Y55561D01*
X259802Y55311D01*
X259760Y55061D01*
X259594Y54853D01*
X258760Y54436D01*
X258385Y54145D01*
X258135Y53728D01*
X258052Y53353D01*
X259802D01*
G01X262277Y54603D02*
X263110D01*
Y53853D01*
X262860Y53603D01*
X262569Y53436D01*
X262152Y53353D01*
X261735Y53436D01*
X261444Y53603D01*
X261194Y53853D01*
X261027Y54145D01*
X260944Y54478D01*
Y54770D01*
X261027Y55020D01*
X261194Y55311D01*
X261444Y55561D01*
X261694Y55728D01*
X262027Y55853D01*
X262319D01*
X262652Y55770D01*
X262902Y55603D01*
G01X265127Y53353D02*
Y55853D01*
X264627Y55353D01*
G01Y53353D02*
X265627D01*
G01X265298Y116300D02*
X265299Y116301D01*
Y141600D01*
X266100D01*
G01X296500Y107000D02*
X290500D01*
G01X288000D02*
X281500D01*
G01X279000D02*
X275500D01*
G01X272500D02*
X269000D01*
G01X271000Y154700D02*
X324910D01*
Y148320D01*
X378499D01*
X378500Y148319D01*
Y108500D01*
G01X243600Y123067D02*
X241100D01*
Y124108D01*
X241225Y124442D01*
X241392Y124650D01*
X241725Y124733D01*
X242058Y124650D01*
X242267Y124400D01*
X242392Y124108D01*
Y123067D01*
G01Y124108D02*
X243600Y124733D01*
G01X243100Y126083D02*
X243392Y126333D01*
X243558Y126667D01*
X243600Y127042D01*
X243558Y127375D01*
X243350Y127708D01*
X243100Y127917D01*
X242850Y127958D01*
X242558Y127875D01*
X242350Y127583D01*
X242267Y127292D01*
Y126917D01*
G01Y127292D02*
X242142Y127542D01*
X241933Y127750D01*
X241683Y127833D01*
X241433Y127750D01*
X241225Y127542D01*
X241100Y127167D01*
X241142Y126792D01*
X241308Y126417D01*
G01X243600Y129183D02*
X241100D01*
Y130017D01*
X241225Y130350D01*
X241392Y130600D01*
X241642Y130808D01*
X241933Y130975D01*
X242350Y131017D01*
X242767Y130975D01*
X243058Y130808D01*
X243308Y130600D01*
X243475Y130350D01*
X243600Y130017D01*
Y129183D01*
G01X241517Y132408D02*
X241267Y132658D01*
X241142Y132950D01*
X241100Y133283D01*
X241183Y133700D01*
X241392Y133992D01*
X241642Y134075D01*
X241892Y134033D01*
X242100Y133867D01*
X242517Y133033D01*
X242808Y132658D01*
X243225Y132408D01*
X243600Y132325D01*
Y134075D01*
G01X242558Y135508D02*
X242267Y135800D01*
X242100Y136050D01*
X242017Y136383D01*
X242100Y136675D01*
X242267Y136883D01*
X242517Y137050D01*
X242808Y137092D01*
X243058Y137050D01*
X243308Y136883D01*
X243517Y136633D01*
X243600Y136342D01*
X243517Y136008D01*
X243267Y135717D01*
X242892Y135550D01*
X242475Y135508D01*
X241933Y135592D01*
X241642Y135717D01*
X241350Y135925D01*
X241142Y136217D01*
X241100Y136508D01*
X241183Y136800D01*
X241392Y137008D01*
G01X247367Y126100D02*
Y128600D01*
X248408D01*
X248742Y128475D01*
X248950Y128308D01*
X249033Y127975D01*
X248950Y127642D01*
X248700Y127433D01*
X248408Y127308D01*
X247367D01*
G01X248408D02*
X249033Y126100D01*
G01X250383Y126600D02*
X250633Y126308D01*
X250967Y126142D01*
X251342Y126100D01*
X251675Y126142D01*
X252008Y126350D01*
X252217Y126600D01*
X252258Y126850D01*
X252175Y127142D01*
X251883Y127350D01*
X251592Y127433D01*
X251217D01*
G01X251592D02*
X251842Y127558D01*
X252050Y127767D01*
X252133Y128017D01*
X252050Y128267D01*
X251842Y128475D01*
X251467Y128600D01*
X251092Y128558D01*
X250717Y128392D01*
G01X253483Y126100D02*
Y128600D01*
X254317D01*
X254650Y128475D01*
X254900Y128308D01*
X255108Y128058D01*
X255275Y127767D01*
X255317Y127350D01*
X255275Y126933D01*
X255108Y126642D01*
X254900Y126392D01*
X254650Y126225D01*
X254317Y126100D01*
X253483D01*
G01X256708Y128183D02*
X256958Y128433D01*
X257250Y128558D01*
X257583Y128600D01*
X258000Y128517D01*
X258292Y128308D01*
X258375Y128058D01*
X258333Y127808D01*
X258167Y127600D01*
X257333Y127183D01*
X256958Y126892D01*
X256708Y126475D01*
X256625Y126100D01*
X258375D01*
G01X259683Y126475D02*
X259933Y126267D01*
X260225Y126142D01*
X260600Y126100D01*
X260975Y126183D01*
X261267Y126350D01*
X261475Y126642D01*
X261517Y126975D01*
X261433Y127308D01*
X261225Y127517D01*
X260933Y127683D01*
X260642Y127725D01*
X260350Y127683D01*
X259975Y127517D01*
X260100Y128600D01*
X261225D01*
G01X255383Y149963D02*
Y152463D01*
X256424D01*
X256758Y152338D01*
X256966Y152171D01*
X257049Y151838D01*
X256966Y151505D01*
X256716Y151296D01*
X256424Y151171D01*
X255383D01*
G01X256424D02*
X257049Y149963D01*
G01X258399Y150463D02*
X258649Y150171D01*
X258983Y150005D01*
X259358Y149963D01*
X259691Y150005D01*
X260024Y150213D01*
X260233Y150463D01*
X260274Y150713D01*
X260191Y151005D01*
X259899Y151213D01*
X259608Y151296D01*
X259233D01*
G01X259608D02*
X259858Y151421D01*
X260066Y151630D01*
X260149Y151880D01*
X260066Y152130D01*
X259858Y152338D01*
X259483Y152463D01*
X259108Y152421D01*
X258733Y152255D01*
G01X261499Y149963D02*
Y152463D01*
X262333D01*
X262666Y152338D01*
X262916Y152171D01*
X263124Y151921D01*
X263291Y151630D01*
X263333Y151213D01*
X263291Y150796D01*
X263124Y150505D01*
X262916Y150255D01*
X262666Y150088D01*
X262333Y149963D01*
X261499D01*
G01X265516D02*
Y152463D01*
X265016Y151963D01*
G01Y149963D02*
X266016D01*
G01X267824Y151005D02*
X268116Y151296D01*
X268366Y151463D01*
X268699Y151546D01*
X268991Y151463D01*
X269199Y151296D01*
X269366Y151046D01*
X269408Y150755D01*
X269366Y150505D01*
X269199Y150255D01*
X268949Y150046D01*
X268658Y149963D01*
X268324Y150046D01*
X268033Y150296D01*
X267866Y150671D01*
X267824Y151088D01*
X267908Y151630D01*
X268033Y151921D01*
X268241Y152213D01*
X268533Y152421D01*
X268824Y152463D01*
X269116Y152380D01*
X269324Y152171D01*
G01X255383Y153363D02*
Y155863D01*
X256424D01*
X256758Y155738D01*
X256966Y155571D01*
X257049Y155238D01*
X256966Y154905D01*
X256716Y154696D01*
X256424Y154571D01*
X255383D01*
G01X256424D02*
X257049Y153363D01*
G01X258399Y153863D02*
X258649Y153571D01*
X258983Y153405D01*
X259358Y153363D01*
X259691Y153405D01*
X260024Y153613D01*
X260233Y153863D01*
X260274Y154113D01*
X260191Y154405D01*
X259899Y154613D01*
X259608Y154696D01*
X259233D01*
G01X259608D02*
X259858Y154821D01*
X260066Y155030D01*
X260149Y155280D01*
X260066Y155530D01*
X259858Y155738D01*
X259483Y155863D01*
X259108Y155821D01*
X258733Y155655D01*
G01X261499Y153363D02*
Y155863D01*
X262333D01*
X262666Y155738D01*
X262916Y155571D01*
X263124Y155321D01*
X263291Y155030D01*
X263333Y154613D01*
X263291Y154196D01*
X263124Y153905D01*
X262916Y153655D01*
X262666Y153488D01*
X262333Y153363D01*
X261499D01*
G01X265516D02*
Y155863D01*
X265016Y155363D01*
G01Y153363D02*
X266016D01*
G01X267699Y153738D02*
X267949Y153530D01*
X268241Y153405D01*
X268616Y153363D01*
X268991Y153446D01*
X269283Y153613D01*
X269491Y153905D01*
X269533Y154238D01*
X269449Y154571D01*
X269241Y154780D01*
X268949Y154946D01*
X268658Y154988D01*
X268366Y154946D01*
X267991Y154780D01*
X268116Y155863D01*
X269241D01*
G01X255383Y143163D02*
Y145663D01*
X256424D01*
X256758Y145538D01*
X256966Y145371D01*
X257049Y145038D01*
X256966Y144705D01*
X256716Y144496D01*
X256424Y144371D01*
X255383D01*
G01X256424D02*
X257049Y143163D01*
G01X258399Y143663D02*
X258649Y143371D01*
X258983Y143205D01*
X259358Y143163D01*
X259691Y143205D01*
X260024Y143413D01*
X260233Y143663D01*
X260274Y143913D01*
X260191Y144205D01*
X259899Y144413D01*
X259608Y144496D01*
X259233D01*
G01X259608D02*
X259858Y144621D01*
X260066Y144830D01*
X260149Y145080D01*
X260066Y145330D01*
X259858Y145538D01*
X259483Y145663D01*
X259108Y145621D01*
X258733Y145455D01*
G01X261499Y143163D02*
Y145663D01*
X262333D01*
X262666Y145538D01*
X262916Y145371D01*
X263124Y145121D01*
X263291Y144830D01*
X263333Y144413D01*
X263291Y143996D01*
X263124Y143705D01*
X262916Y143455D01*
X262666Y143288D01*
X262333Y143163D01*
X261499D01*
G01X265516D02*
Y145663D01*
X265016Y145163D01*
G01Y143163D02*
X266016D01*
G01X267908Y143455D02*
X268199Y143246D01*
X268533Y143163D01*
X268866Y143246D01*
X269158Y143496D01*
X269366Y143871D01*
X269449Y144246D01*
Y144705D01*
X269366Y145080D01*
X269158Y145413D01*
X268908Y145580D01*
X268616Y145663D01*
X268283Y145580D01*
X268033Y145413D01*
X267866Y145163D01*
X267783Y144830D01*
X267866Y144538D01*
X268074Y144246D01*
X268324Y144080D01*
X268616Y144038D01*
X268949Y144121D01*
X269199Y144330D01*
X269449Y144705D01*
G01X255383Y146563D02*
Y149063D01*
X256424D01*
X256758Y148938D01*
X256966Y148771D01*
X257049Y148438D01*
X256966Y148105D01*
X256716Y147896D01*
X256424Y147771D01*
X255383D01*
G01X256424D02*
X257049Y146563D01*
G01X258399Y147063D02*
X258649Y146771D01*
X258983Y146605D01*
X259358Y146563D01*
X259691Y146605D01*
X260024Y146813D01*
X260233Y147063D01*
X260274Y147313D01*
X260191Y147605D01*
X259899Y147813D01*
X259608Y147896D01*
X259233D01*
G01X259608D02*
X259858Y148021D01*
X260066Y148230D01*
X260149Y148480D01*
X260066Y148730D01*
X259858Y148938D01*
X259483Y149063D01*
X259108Y149021D01*
X258733Y148855D01*
G01X261499Y146563D02*
Y149063D01*
X262333D01*
X262666Y148938D01*
X262916Y148771D01*
X263124Y148521D01*
X263291Y148230D01*
X263333Y147813D01*
X263291Y147396D01*
X263124Y147105D01*
X262916Y146855D01*
X262666Y146688D01*
X262333Y146563D01*
X261499D01*
G01X265516D02*
Y149063D01*
X265016Y148563D01*
G01Y146563D02*
X266016D01*
G01X268533D02*
X268616Y147105D01*
X268741Y147563D01*
X268908Y147980D01*
X269116Y148438D01*
X269449Y149063D01*
X267783D01*
G01X255383Y156763D02*
Y159263D01*
X256424D01*
X256758Y159138D01*
X256966Y158971D01*
X257049Y158638D01*
X256966Y158305D01*
X256716Y158096D01*
X256424Y157971D01*
X255383D01*
G01X256424D02*
X257049Y156763D01*
G01X258399Y157263D02*
X258649Y156971D01*
X258983Y156805D01*
X259358Y156763D01*
X259691Y156805D01*
X260024Y157013D01*
X260233Y157263D01*
X260274Y157513D01*
X260191Y157805D01*
X259899Y158013D01*
X259608Y158096D01*
X259233D01*
G01X259608D02*
X259858Y158221D01*
X260066Y158430D01*
X260149Y158680D01*
X260066Y158930D01*
X259858Y159138D01*
X259483Y159263D01*
X259108Y159221D01*
X258733Y159055D01*
G01X261499Y156763D02*
Y159263D01*
X262333D01*
X262666Y159138D01*
X262916Y158971D01*
X263124Y158721D01*
X263291Y158430D01*
X263333Y158013D01*
X263291Y157596D01*
X263124Y157305D01*
X262916Y157055D01*
X262666Y156888D01*
X262333Y156763D01*
X261499D01*
G01X264599Y157263D02*
X264849Y156971D01*
X265183Y156805D01*
X265558Y156763D01*
X265891Y156805D01*
X266224Y157013D01*
X266433Y157263D01*
X266474Y157513D01*
X266391Y157805D01*
X266099Y158013D01*
X265808Y158096D01*
X265433D01*
G01X265808D02*
X266058Y158221D01*
X266266Y158430D01*
X266349Y158680D01*
X266266Y158930D01*
X266058Y159138D01*
X265683Y159263D01*
X265308Y159221D01*
X264933Y159055D01*
G01X268616Y156763D02*
Y159263D01*
X268116Y158763D01*
G01Y156763D02*
X269116D01*
G01X238800Y122667D02*
X236300D01*
Y123708D01*
X236425Y124042D01*
X236592Y124250D01*
X236925Y124333D01*
X237258Y124250D01*
X237467Y124000D01*
X237592Y123708D01*
Y122667D01*
G01Y123708D02*
X238800Y124333D01*
G01X238300Y125683D02*
X238592Y125933D01*
X238758Y126267D01*
X238800Y126642D01*
X238758Y126975D01*
X238550Y127308D01*
X238300Y127517D01*
X238050Y127558D01*
X237758Y127475D01*
X237550Y127183D01*
X237467Y126892D01*
Y126517D01*
G01Y126892D02*
X237342Y127142D01*
X237133Y127350D01*
X236883Y127433D01*
X236633Y127350D01*
X236425Y127142D01*
X236300Y126767D01*
X236342Y126392D01*
X236508Y126017D01*
G01X238800Y128783D02*
X236300D01*
Y129617D01*
X236425Y129950D01*
X236592Y130200D01*
X236842Y130408D01*
X237133Y130575D01*
X237550Y130617D01*
X237967Y130575D01*
X238258Y130408D01*
X238508Y130200D01*
X238675Y129950D01*
X238800Y129617D01*
Y128783D01*
G01X236717Y132008D02*
X236467Y132258D01*
X236342Y132550D01*
X236300Y132883D01*
X236383Y133300D01*
X236592Y133592D01*
X236842Y133675D01*
X237092Y133633D01*
X237300Y133467D01*
X237717Y132633D01*
X238008Y132258D01*
X238425Y132008D01*
X238800Y131925D01*
Y133675D01*
G01Y136400D02*
X236300D01*
X238092Y134858D01*
Y136942D01*
G01X266586Y123335D02*
Y125835D01*
X267627D01*
X267961Y125710D01*
X268169Y125543D01*
X268252Y125210D01*
X268169Y124877D01*
X267919Y124668D01*
X267627Y124543D01*
X266586D01*
G01X267627D02*
X268252Y123335D01*
G01X269727D02*
Y125835D01*
X271311D01*
G01X270727Y124627D02*
X269727D01*
G01X273619Y123335D02*
Y125835D01*
X273119Y125335D01*
G01Y123335D02*
X274119D01*
G01X276011Y123627D02*
X276302Y123418D01*
X276636Y123335D01*
X276969Y123418D01*
X277261Y123668D01*
X277469Y124043D01*
X277552Y124418D01*
Y124877D01*
X277469Y125252D01*
X277261Y125585D01*
X277011Y125752D01*
X276719Y125835D01*
X276386Y125752D01*
X276136Y125585D01*
X275969Y125335D01*
X275886Y125002D01*
X275969Y124710D01*
X276177Y124418D01*
X276427Y124252D01*
X276719Y124210D01*
X277052Y124293D01*
X277302Y124502D01*
X277552Y124877D01*
G01X266377Y119218D02*
Y121718D01*
X267418D01*
X267752Y121593D01*
X267960Y121426D01*
X268043Y121093D01*
X267960Y120760D01*
X267710Y120551D01*
X267418Y120426D01*
X266377D01*
G01X267418D02*
X268043Y119218D01*
G01X269518D02*
Y121718D01*
X271102D01*
G01X270518Y120510D02*
X269518D01*
G01X272618Y121301D02*
X272868Y121551D01*
X273160Y121676D01*
X273493Y121718D01*
X273910Y121635D01*
X274202Y121426D01*
X274285Y121176D01*
X274243Y120926D01*
X274077Y120718D01*
X273243Y120301D01*
X272868Y120010D01*
X272618Y119593D01*
X272535Y119218D01*
X274285D01*
G01X276510Y121718D02*
X276177Y121635D01*
X275927Y121426D01*
X275760Y121176D01*
X275635Y120843D01*
X275593Y120468D01*
X275635Y120093D01*
X275760Y119760D01*
X275927Y119510D01*
X276177Y119301D01*
X276510Y119218D01*
X276843Y119301D01*
X277093Y119510D01*
X277260Y119760D01*
X277385Y120093D01*
X277427Y120468D01*
X277385Y120843D01*
X277260Y121176D01*
X277093Y121426D01*
X276843Y121635D01*
X276510Y121718D01*
G01X286773Y136505D02*
X284273D01*
Y137546D01*
X284398Y137880D01*
X284565Y138088D01*
X284898Y138171D01*
X285231Y138088D01*
X285440Y137838D01*
X285565Y137546D01*
Y136505D01*
G01Y137546D02*
X286773Y138171D01*
G01Y140438D02*
X284273D01*
X284773Y139938D01*
G01X286773D02*
Y140938D01*
G01X284690Y142746D02*
X284440Y142996D01*
X284315Y143288D01*
X284273Y143621D01*
X284356Y144038D01*
X284565Y144330D01*
X284815Y144413D01*
X285065Y144371D01*
X285273Y144205D01*
X285690Y143371D01*
X285981Y142996D01*
X286398Y142746D01*
X286773Y142663D01*
Y144413D01*
G01X284273Y145388D02*
X286773Y145971D01*
X284273Y146638D01*
X286773Y147305D01*
X284273Y147888D01*
G01X286273Y148821D02*
X286565Y149071D01*
X286731Y149405D01*
X286773Y149780D01*
X286731Y150113D01*
X286523Y150446D01*
X286273Y150655D01*
X286023Y150696D01*
X285731Y150613D01*
X285523Y150321D01*
X285440Y150030D01*
Y149655D01*
G01Y150030D02*
X285315Y150280D01*
X285106Y150488D01*
X284856Y150571D01*
X284606Y150488D01*
X284398Y150280D01*
X284273Y149905D01*
X284315Y149530D01*
X284481Y149155D01*
G01X286273Y151921D02*
X286565Y152171D01*
X286731Y152505D01*
X286773Y152880D01*
X286731Y153213D01*
X286523Y153546D01*
X286273Y153755D01*
X286023Y153796D01*
X285731Y153713D01*
X285523Y153421D01*
X285440Y153130D01*
Y152755D01*
G01Y153130D02*
X285315Y153380D01*
X285106Y153588D01*
X284856Y153671D01*
X284606Y153588D01*
X284398Y153380D01*
X284273Y153005D01*
X284315Y152630D01*
X284481Y152255D01*
G01X283786Y114012D02*
Y116512D01*
X284827D01*
X285161Y116387D01*
X285369Y116220D01*
X285452Y115887D01*
X285369Y115554D01*
X285119Y115345D01*
X284827Y115220D01*
X283786D01*
G01X284827D02*
X285452Y114012D01*
G01X287719D02*
Y116512D01*
X287219Y116012D01*
G01Y114012D02*
X288219D01*
G01X291069Y115262D02*
X291902D01*
Y114512D01*
X291652Y114262D01*
X291361Y114095D01*
X290944Y114012D01*
X290527Y114095D01*
X290236Y114262D01*
X289986Y114512D01*
X289819Y114804D01*
X289736Y115137D01*
Y115429D01*
X289819Y115679D01*
X289986Y115970D01*
X290236Y116220D01*
X290486Y116387D01*
X290819Y116512D01*
X291111D01*
X291444Y116429D01*
X291694Y116262D01*
G01X293127Y116095D02*
X293377Y116345D01*
X293669Y116470D01*
X294002Y116512D01*
X294419Y116429D01*
X294711Y116220D01*
X294794Y115970D01*
X294752Y115720D01*
X294586Y115512D01*
X293752Y115095D01*
X293377Y114804D01*
X293127Y114387D01*
X293044Y114012D01*
X294794D01*
G01X296102Y114512D02*
X296352Y114220D01*
X296686Y114054D01*
X297061Y114012D01*
X297394Y114054D01*
X297727Y114262D01*
X297936Y114512D01*
X297977Y114762D01*
X297894Y115054D01*
X297602Y115262D01*
X297311Y115345D01*
X296936D01*
G01X297311D02*
X297561Y115470D01*
X297769Y115679D01*
X297852Y115929D01*
X297769Y116179D01*
X297561Y116387D01*
X297186Y116512D01*
X296811Y116470D01*
X296436Y116304D01*
G01X283582Y120626D02*
Y123126D01*
X284623D01*
X284957Y123001D01*
X285165Y122834D01*
X285248Y122501D01*
X285165Y122168D01*
X284915Y121959D01*
X284623Y121834D01*
X283582D01*
G01X284623D02*
X285248Y120626D01*
G01X287515D02*
Y123126D01*
X287015Y122626D01*
G01Y120626D02*
X288015D01*
G01X290865Y121876D02*
X291698D01*
Y121126D01*
X291448Y120876D01*
X291157Y120709D01*
X290740Y120626D01*
X290323Y120709D01*
X290032Y120876D01*
X289782Y121126D01*
X289615Y121418D01*
X289532Y121751D01*
Y122043D01*
X289615Y122293D01*
X289782Y122584D01*
X290032Y122834D01*
X290282Y123001D01*
X290615Y123126D01*
X290907D01*
X291240Y123043D01*
X291490Y122876D01*
G01X292923Y122709D02*
X293173Y122959D01*
X293465Y123084D01*
X293798Y123126D01*
X294215Y123043D01*
X294507Y122834D01*
X294590Y122584D01*
X294548Y122334D01*
X294382Y122126D01*
X293548Y121709D01*
X293173Y121418D01*
X292923Y121001D01*
X292840Y120626D01*
X294590D01*
G01X296023Y122709D02*
X296273Y122959D01*
X296565Y123084D01*
X296898Y123126D01*
X297315Y123043D01*
X297607Y122834D01*
X297690Y122584D01*
X297648Y122334D01*
X297482Y122126D01*
X296648Y121709D01*
X296273Y121418D01*
X296023Y121001D01*
X295940Y120626D01*
X297690D01*
G01X294679Y136636D02*
X292179D01*
Y137677D01*
X292304Y138011D01*
X292471Y138219D01*
X292804Y138302D01*
X293137Y138219D01*
X293346Y137969D01*
X293471Y137677D01*
Y136636D01*
G01Y137677D02*
X294679Y138302D01*
G01Y140569D02*
X292179D01*
X292679Y140069D01*
G01X294679D02*
Y141069D01*
G01X293429Y143919D02*
Y144752D01*
X294179D01*
X294429Y144502D01*
X294596Y144211D01*
X294679Y143794D01*
X294596Y143377D01*
X294429Y143086D01*
X294179Y142836D01*
X293887Y142669D01*
X293554Y142586D01*
X293262D01*
X293012Y142669D01*
X292721Y142836D01*
X292471Y143086D01*
X292304Y143336D01*
X292179Y143669D01*
Y143961D01*
X292262Y144294D01*
X292429Y144544D01*
G01X294679Y146769D02*
X292179D01*
X292679Y146269D01*
G01X294679D02*
Y147269D01*
G01X292179Y149869D02*
X292262Y149536D01*
X292471Y149286D01*
X292721Y149119D01*
X293054Y148994D01*
X293429Y148952D01*
X293804Y148994D01*
X294137Y149119D01*
X294387Y149286D01*
X294596Y149536D01*
X294679Y149869D01*
X294596Y150202D01*
X294387Y150452D01*
X294137Y150619D01*
X293804Y150744D01*
X293429Y150786D01*
X293054Y150744D01*
X292721Y150619D01*
X292471Y150452D01*
X292262Y150202D01*
X292179Y149869D01*
G01X269065Y138090D02*
Y140590D01*
X270106D01*
X270440Y140465D01*
X270648Y140298D01*
X270731Y139965D01*
X270648Y139632D01*
X270398Y139423D01*
X270106Y139298D01*
X269065D01*
G01X270106D02*
X270731Y138090D01*
G01X272998D02*
Y140590D01*
X272498Y140090D01*
G01Y138090D02*
X273498D01*
G01X276348Y139340D02*
X277181D01*
Y138590D01*
X276931Y138340D01*
X276640Y138173D01*
X276223Y138090D01*
X275806Y138173D01*
X275515Y138340D01*
X275265Y138590D01*
X275098Y138882D01*
X275015Y139215D01*
Y139507D01*
X275098Y139757D01*
X275265Y140048D01*
X275515Y140298D01*
X275765Y140465D01*
X276098Y140590D01*
X276390D01*
X276723Y140507D01*
X276973Y140340D01*
G01X278281Y138465D02*
X278531Y138257D01*
X278823Y138132D01*
X279198Y138090D01*
X279573Y138173D01*
X279865Y138340D01*
X280073Y138632D01*
X280115Y138965D01*
X280031Y139298D01*
X279823Y139507D01*
X279531Y139673D01*
X279240Y139715D01*
X278948Y139673D01*
X278573Y139507D01*
X278698Y140590D01*
X279823D01*
G01X290622Y136442D02*
X288122D01*
Y137483D01*
X288247Y137817D01*
X288414Y138025D01*
X288747Y138108D01*
X289080Y138025D01*
X289289Y137775D01*
X289414Y137483D01*
Y136442D01*
G01Y137483D02*
X290622Y138108D01*
G01Y140375D02*
X288122D01*
X288622Y139875D01*
G01X290622D02*
Y140875D01*
G01X289372Y143725D02*
Y144558D01*
X290122D01*
X290372Y144308D01*
X290539Y144017D01*
X290622Y143600D01*
X290539Y143183D01*
X290372Y142892D01*
X290122Y142642D01*
X289830Y142475D01*
X289497Y142392D01*
X289205D01*
X288955Y142475D01*
X288664Y142642D01*
X288414Y142892D01*
X288247Y143142D01*
X288122Y143475D01*
Y143767D01*
X288205Y144100D01*
X288372Y144350D01*
G01X290330Y145867D02*
X290539Y146158D01*
X290622Y146492D01*
X290539Y146825D01*
X290289Y147117D01*
X289914Y147325D01*
X289539Y147408D01*
X289080D01*
X288705Y147325D01*
X288372Y147117D01*
X288205Y146867D01*
X288122Y146575D01*
X288205Y146242D01*
X288372Y145992D01*
X288622Y145825D01*
X288955Y145742D01*
X289247Y145825D01*
X289539Y146033D01*
X289705Y146283D01*
X289747Y146575D01*
X289664Y146908D01*
X289455Y147158D01*
X289080Y147408D01*
G01X247882Y145217D02*
X247757Y144967D01*
X247674Y144675D01*
Y144342D01*
X247799Y143967D01*
X248007Y143675D01*
X248257Y143467D01*
X248674Y143300D01*
X249049Y143258D01*
X249424Y143342D01*
X249674Y143467D01*
X249924Y143717D01*
X250091Y144008D01*
X250174Y144300D01*
Y144592D01*
X250091Y144883D01*
X249966Y145133D01*
X249799Y145342D01*
G01X249674Y146483D02*
X249966Y146733D01*
X250132Y147067D01*
X250174Y147442D01*
X250132Y147775D01*
X249924Y148108D01*
X249674Y148317D01*
X249424Y148358D01*
X249132Y148275D01*
X248924Y147983D01*
X248841Y147692D01*
Y147317D01*
G01Y147692D02*
X248716Y147942D01*
X248507Y148150D01*
X248257Y148233D01*
X248007Y148150D01*
X247799Y147942D01*
X247674Y147567D01*
X247716Y147192D01*
X247882Y146817D01*
G01X250174Y149583D02*
X247674D01*
Y150417D01*
X247799Y150750D01*
X247966Y151000D01*
X248216Y151208D01*
X248507Y151375D01*
X248924Y151417D01*
X249341Y151375D01*
X249632Y151208D01*
X249882Y151000D01*
X250049Y150750D01*
X250174Y150417D01*
Y149583D01*
G01X248091Y152808D02*
X247841Y153058D01*
X247716Y153350D01*
X247674Y153683D01*
X247757Y154100D01*
X247966Y154392D01*
X248216Y154475D01*
X248466Y154433D01*
X248674Y154267D01*
X249091Y153433D01*
X249382Y153058D01*
X249799Y152808D01*
X250174Y152725D01*
Y154475D01*
G01X249674Y155783D02*
X249966Y156033D01*
X250132Y156367D01*
X250174Y156742D01*
X250132Y157075D01*
X249924Y157408D01*
X249674Y157617D01*
X249424Y157658D01*
X249132Y157575D01*
X248924Y157283D01*
X248841Y156992D01*
Y156617D01*
G01Y156992D02*
X248716Y157242D01*
X248507Y157450D01*
X248257Y157533D01*
X248007Y157450D01*
X247799Y157242D01*
X247674Y156867D01*
X247716Y156492D01*
X247882Y156117D01*
G01X244382Y145317D02*
X244257Y145067D01*
X244174Y144775D01*
Y144442D01*
X244299Y144067D01*
X244507Y143775D01*
X244757Y143567D01*
X245174Y143400D01*
X245549Y143358D01*
X245924Y143442D01*
X246174Y143567D01*
X246424Y143817D01*
X246591Y144108D01*
X246674Y144400D01*
Y144692D01*
X246591Y144983D01*
X246466Y145233D01*
X246299Y145442D01*
G01X246174Y146583D02*
X246466Y146833D01*
X246632Y147167D01*
X246674Y147542D01*
X246632Y147875D01*
X246424Y148208D01*
X246174Y148417D01*
X245924Y148458D01*
X245632Y148375D01*
X245424Y148083D01*
X245341Y147792D01*
Y147417D01*
G01Y147792D02*
X245216Y148042D01*
X245007Y148250D01*
X244757Y148333D01*
X244507Y148250D01*
X244299Y148042D01*
X244174Y147667D01*
X244216Y147292D01*
X244382Y146917D01*
G01X246674Y149683D02*
X244174D01*
Y150517D01*
X244299Y150850D01*
X244466Y151100D01*
X244716Y151308D01*
X245007Y151475D01*
X245424Y151517D01*
X245841Y151475D01*
X246132Y151308D01*
X246382Y151100D01*
X246549Y150850D01*
X246674Y150517D01*
Y149683D01*
G01X244591Y152908D02*
X244341Y153158D01*
X244216Y153450D01*
X244174Y153783D01*
X244257Y154200D01*
X244466Y154492D01*
X244716Y154575D01*
X244966Y154533D01*
X245174Y154367D01*
X245591Y153533D01*
X245882Y153158D01*
X246299Y152908D01*
X246674Y152825D01*
Y154575D01*
G01X244174Y156800D02*
X244257Y156467D01*
X244466Y156217D01*
X244716Y156050D01*
X245049Y155925D01*
X245424Y155883D01*
X245799Y155925D01*
X246132Y156050D01*
X246382Y156217D01*
X246591Y156467D01*
X246674Y156800D01*
X246591Y157133D01*
X246382Y157383D01*
X246132Y157550D01*
X245799Y157675D01*
X245424Y157717D01*
X245049Y157675D01*
X244716Y157550D01*
X244466Y157383D01*
X244257Y157133D01*
X244174Y156800D01*
G01X237582Y145317D02*
X237457Y145067D01*
X237374Y144775D01*
Y144442D01*
X237499Y144067D01*
X237707Y143775D01*
X237957Y143567D01*
X238374Y143400D01*
X238749Y143358D01*
X239124Y143442D01*
X239374Y143567D01*
X239624Y143817D01*
X239791Y144108D01*
X239874Y144400D01*
Y144692D01*
X239791Y144983D01*
X239666Y145233D01*
X239499Y145442D01*
G01X239374Y146583D02*
X239666Y146833D01*
X239832Y147167D01*
X239874Y147542D01*
X239832Y147875D01*
X239624Y148208D01*
X239374Y148417D01*
X239124Y148458D01*
X238832Y148375D01*
X238624Y148083D01*
X238541Y147792D01*
Y147417D01*
G01Y147792D02*
X238416Y148042D01*
X238207Y148250D01*
X237957Y148333D01*
X237707Y148250D01*
X237499Y148042D01*
X237374Y147667D01*
X237416Y147292D01*
X237582Y146917D01*
G01X239874Y149683D02*
X237374D01*
Y150517D01*
X237499Y150850D01*
X237666Y151100D01*
X237916Y151308D01*
X238207Y151475D01*
X238624Y151517D01*
X239041Y151475D01*
X239332Y151308D01*
X239582Y151100D01*
X239749Y150850D01*
X239874Y150517D01*
Y149683D01*
G01Y153700D02*
X237374D01*
X237874Y153200D01*
G01X239874D02*
Y154200D01*
G01Y156800D02*
X239832Y157092D01*
X239707Y157425D01*
X239499Y157633D01*
X239207Y157717D01*
X238916Y157633D01*
X238666Y157383D01*
X238541Y157008D01*
Y156592D01*
X238457Y156342D01*
X238249Y156133D01*
X237957Y156050D01*
X237666Y156175D01*
X237457Y156467D01*
X237374Y156800D01*
X237457Y157133D01*
X237666Y157425D01*
X237957Y157550D01*
X238249Y157467D01*
X238457Y157258D01*
X238541Y157008D01*
Y156592D01*
X238666Y156217D01*
X238916Y155967D01*
X239207Y155883D01*
X239499Y155967D01*
X239707Y156175D01*
X239832Y156508D01*
X239874Y156800D01*
G01X240982Y145317D02*
X240857Y145067D01*
X240774Y144775D01*
Y144442D01*
X240899Y144067D01*
X241107Y143775D01*
X241357Y143567D01*
X241774Y143400D01*
X242149Y143358D01*
X242524Y143442D01*
X242774Y143567D01*
X243024Y143817D01*
X243191Y144108D01*
X243274Y144400D01*
Y144692D01*
X243191Y144983D01*
X243066Y145233D01*
X242899Y145442D01*
G01X242774Y146583D02*
X243066Y146833D01*
X243232Y147167D01*
X243274Y147542D01*
X243232Y147875D01*
X243024Y148208D01*
X242774Y148417D01*
X242524Y148458D01*
X242232Y148375D01*
X242024Y148083D01*
X241941Y147792D01*
Y147417D01*
G01Y147792D02*
X241816Y148042D01*
X241607Y148250D01*
X241357Y148333D01*
X241107Y148250D01*
X240899Y148042D01*
X240774Y147667D01*
X240816Y147292D01*
X240982Y146917D01*
G01X243274Y149683D02*
X240774D01*
Y150517D01*
X240899Y150850D01*
X241066Y151100D01*
X241316Y151308D01*
X241607Y151475D01*
X242024Y151517D01*
X242441Y151475D01*
X242732Y151308D01*
X242982Y151100D01*
X243149Y150850D01*
X243274Y150517D01*
Y149683D01*
G01Y153700D02*
X240774D01*
X241274Y153200D01*
G01X243274D02*
Y154200D01*
G01X242982Y156092D02*
X243191Y156383D01*
X243274Y156717D01*
X243191Y157050D01*
X242941Y157342D01*
X242566Y157550D01*
X242191Y157633D01*
X241732D01*
X241357Y157550D01*
X241024Y157342D01*
X240857Y157092D01*
X240774Y156800D01*
X240857Y156467D01*
X241024Y156217D01*
X241274Y156050D01*
X241607Y155967D01*
X241899Y156050D01*
X242191Y156258D01*
X242357Y156508D01*
X242399Y156800D01*
X242316Y157133D01*
X242107Y157383D01*
X241732Y157633D01*
G01X234182Y145317D02*
X234057Y145067D01*
X233974Y144775D01*
Y144442D01*
X234099Y144067D01*
X234307Y143775D01*
X234557Y143567D01*
X234974Y143400D01*
X235349Y143358D01*
X235724Y143442D01*
X235974Y143567D01*
X236224Y143817D01*
X236391Y144108D01*
X236474Y144400D01*
Y144692D01*
X236391Y144983D01*
X236266Y145233D01*
X236099Y145442D01*
G01X235974Y146583D02*
X236266Y146833D01*
X236432Y147167D01*
X236474Y147542D01*
X236432Y147875D01*
X236224Y148208D01*
X235974Y148417D01*
X235724Y148458D01*
X235432Y148375D01*
X235224Y148083D01*
X235141Y147792D01*
Y147417D01*
G01Y147792D02*
X235016Y148042D01*
X234807Y148250D01*
X234557Y148333D01*
X234307Y148250D01*
X234099Y148042D01*
X233974Y147667D01*
X234016Y147292D01*
X234182Y146917D01*
G01X236474Y149683D02*
X233974D01*
Y150517D01*
X234099Y150850D01*
X234266Y151100D01*
X234516Y151308D01*
X234807Y151475D01*
X235224Y151517D01*
X235641Y151475D01*
X235932Y151308D01*
X236182Y151100D01*
X236349Y150850D01*
X236474Y150517D01*
Y149683D01*
G01Y153700D02*
X233974D01*
X234474Y153200D01*
G01X236474D02*
Y154200D01*
G01Y156717D02*
X235932Y156800D01*
X235474Y156925D01*
X235057Y157092D01*
X234599Y157300D01*
X233974Y157633D01*
Y155967D01*
G01X251282Y145217D02*
X251157Y144967D01*
X251074Y144675D01*
Y144342D01*
X251199Y143967D01*
X251407Y143675D01*
X251657Y143467D01*
X252074Y143300D01*
X252449Y143258D01*
X252824Y143342D01*
X253074Y143467D01*
X253324Y143717D01*
X253491Y144008D01*
X253574Y144300D01*
Y144592D01*
X253491Y144883D01*
X253366Y145133D01*
X253199Y145342D01*
G01X253074Y146483D02*
X253366Y146733D01*
X253532Y147067D01*
X253574Y147442D01*
X253532Y147775D01*
X253324Y148108D01*
X253074Y148317D01*
X252824Y148358D01*
X252532Y148275D01*
X252324Y147983D01*
X252241Y147692D01*
Y147317D01*
G01Y147692D02*
X252116Y147942D01*
X251907Y148150D01*
X251657Y148233D01*
X251407Y148150D01*
X251199Y147942D01*
X251074Y147567D01*
X251116Y147192D01*
X251282Y146817D01*
G01X253574Y149583D02*
X251074D01*
Y150417D01*
X251199Y150750D01*
X251366Y151000D01*
X251616Y151208D01*
X251907Y151375D01*
X252324Y151417D01*
X252741Y151375D01*
X253032Y151208D01*
X253282Y151000D01*
X253449Y150750D01*
X253574Y150417D01*
Y149583D01*
G01X251491Y152808D02*
X251241Y153058D01*
X251116Y153350D01*
X251074Y153683D01*
X251157Y154100D01*
X251366Y154392D01*
X251616Y154475D01*
X251866Y154433D01*
X252074Y154267D01*
X252491Y153433D01*
X252782Y153058D01*
X253199Y152808D01*
X253574Y152725D01*
Y154475D01*
G01Y157200D02*
X251074D01*
X252866Y155658D01*
Y157742D01*
G01X268110Y132849D02*
X267860Y132974D01*
X267568Y133057D01*
X267235D01*
X266860Y132932D01*
X266568Y132724D01*
X266360Y132474D01*
X266193Y132057D01*
X266151Y131682D01*
X266235Y131307D01*
X266360Y131057D01*
X266610Y130807D01*
X266901Y130640D01*
X267193Y130557D01*
X267485D01*
X267776Y130640D01*
X268026Y130765D01*
X268235Y130932D01*
G01X270293Y130557D02*
Y133057D01*
X269793Y132557D01*
G01Y130557D02*
X270793D01*
G01X273643Y131807D02*
X274476D01*
Y131057D01*
X274226Y130807D01*
X273935Y130640D01*
X273518Y130557D01*
X273101Y130640D01*
X272810Y130807D01*
X272560Y131057D01*
X272393Y131349D01*
X272310Y131682D01*
Y131974D01*
X272393Y132224D01*
X272560Y132515D01*
X272810Y132765D01*
X273060Y132932D01*
X273393Y133057D01*
X273685D01*
X274018Y132974D01*
X274268Y132807D01*
G01X276493Y130557D02*
Y133057D01*
X275993Y132557D01*
G01Y130557D02*
X276993D01*
G01X278801Y131599D02*
X279093Y131890D01*
X279343Y132057D01*
X279676Y132140D01*
X279968Y132057D01*
X280176Y131890D01*
X280343Y131640D01*
X280385Y131349D01*
X280343Y131099D01*
X280176Y130849D01*
X279926Y130640D01*
X279635Y130557D01*
X279301Y130640D01*
X279010Y130890D01*
X278843Y131265D01*
X278801Y131682D01*
X278885Y132224D01*
X279010Y132515D01*
X279218Y132807D01*
X279510Y133015D01*
X279801Y133057D01*
X280093Y132974D01*
X280301Y132765D01*
G01X279460Y112233D02*
X279335Y111983D01*
X279252Y111691D01*
Y111358D01*
X279377Y110983D01*
X279585Y110691D01*
X279835Y110483D01*
X280252Y110316D01*
X280627Y110274D01*
X281002Y110358D01*
X281252Y110483D01*
X281502Y110733D01*
X281669Y111024D01*
X281752Y111316D01*
Y111608D01*
X281669Y111899D01*
X281544Y112149D01*
X281377Y112358D01*
G01X281752Y114416D02*
X279252D01*
X279752Y113916D01*
G01X281752D02*
Y114916D01*
G01X280502Y117766D02*
Y118599D01*
X281252D01*
X281502Y118349D01*
X281669Y118058D01*
X281752Y117641D01*
X281669Y117224D01*
X281502Y116933D01*
X281252Y116683D01*
X280960Y116516D01*
X280627Y116433D01*
X280335D01*
X280085Y116516D01*
X279794Y116683D01*
X279544Y116933D01*
X279377Y117183D01*
X279252Y117516D01*
Y117808D01*
X279335Y118141D01*
X279502Y118391D01*
G01X279669Y119824D02*
X279419Y120074D01*
X279294Y120366D01*
X279252Y120699D01*
X279335Y121116D01*
X279544Y121408D01*
X279794Y121491D01*
X280044Y121449D01*
X280252Y121283D01*
X280669Y120449D01*
X280960Y120074D01*
X281377Y119824D01*
X281752Y119741D01*
Y121491D01*
G01Y124216D02*
X279252D01*
X281044Y122674D01*
Y124758D01*
G01X268127Y117510D02*
X267877Y117635D01*
X267585Y117718D01*
X267252D01*
X266877Y117593D01*
X266585Y117385D01*
X266377Y117135D01*
X266210Y116718D01*
X266168Y116343D01*
X266252Y115968D01*
X266377Y115718D01*
X266627Y115468D01*
X266918Y115301D01*
X267210Y115218D01*
X267502D01*
X267793Y115301D01*
X268043Y115426D01*
X268252Y115593D01*
G01X269518Y115218D02*
Y117718D01*
X271102D01*
G01X270518Y116510D02*
X269518D01*
G01X272618Y117301D02*
X272868Y117551D01*
X273160Y117676D01*
X273493Y117718D01*
X273910Y117635D01*
X274202Y117426D01*
X274285Y117176D01*
X274243Y116926D01*
X274077Y116718D01*
X273243Y116301D01*
X272868Y116010D01*
X272618Y115593D01*
X272535Y115218D01*
X274285D01*
G01X276510Y117718D02*
X276177Y117635D01*
X275927Y117426D01*
X275760Y117176D01*
X275635Y116843D01*
X275593Y116468D01*
X275635Y116093D01*
X275760Y115760D01*
X275927Y115510D01*
X276177Y115301D01*
X276510Y115218D01*
X276843Y115301D01*
X277093Y115510D01*
X277260Y115760D01*
X277385Y116093D01*
X277427Y116468D01*
X277385Y116843D01*
X277260Y117176D01*
X277093Y117426D01*
X276843Y117635D01*
X276510Y117718D01*
G01X268406Y129227D02*
X268156Y129352D01*
X267864Y129435D01*
X267531D01*
X267156Y129310D01*
X266864Y129102D01*
X266656Y128852D01*
X266489Y128435D01*
X266447Y128060D01*
X266531Y127685D01*
X266656Y127435D01*
X266906Y127185D01*
X267197Y127018D01*
X267489Y126935D01*
X267781D01*
X268072Y127018D01*
X268322Y127143D01*
X268531Y127310D01*
G01X269797Y126935D02*
Y129435D01*
X271381D01*
G01X270797Y128227D02*
X269797D01*
G01X273689Y126935D02*
Y129435D01*
X273189Y128935D01*
G01Y126935D02*
X274189D01*
G01X276081Y127227D02*
X276372Y127018D01*
X276706Y126935D01*
X277039Y127018D01*
X277331Y127268D01*
X277539Y127643D01*
X277622Y128018D01*
Y128477D01*
X277539Y128852D01*
X277331Y129185D01*
X277081Y129352D01*
X276789Y129435D01*
X276456Y129352D01*
X276206Y129185D01*
X276039Y128935D01*
X275956Y128602D01*
X276039Y128310D01*
X276247Y128018D01*
X276497Y127852D01*
X276789Y127810D01*
X277122Y127893D01*
X277372Y128102D01*
X277622Y128477D01*
G01X283963Y129830D02*
X282297D01*
Y132330D01*
X283963D01*
G01X283297Y131122D02*
X282297D01*
G01X285313Y132330D02*
Y130538D01*
X285480Y130163D01*
X285813Y129913D01*
X286230Y129830D01*
X286647Y129913D01*
X286980Y130163D01*
X287147Y130538D01*
Y132330D01*
G01X289330Y129830D02*
Y132330D01*
X288830Y131830D01*
G01Y129830D02*
X289830D01*
G01X292680Y131080D02*
X293513D01*
Y130330D01*
X293263Y130080D01*
X292972Y129913D01*
X292555Y129830D01*
X292138Y129913D01*
X291847Y130080D01*
X291597Y130330D01*
X291430Y130622D01*
X291347Y130955D01*
Y131247D01*
X291430Y131497D01*
X291597Y131788D01*
X291847Y132038D01*
X292097Y132205D01*
X292430Y132330D01*
X292722D01*
X293055Y132247D01*
X293305Y132080D01*
G01X294738Y131913D02*
X294988Y132163D01*
X295280Y132288D01*
X295613Y132330D01*
X296030Y132247D01*
X296322Y132038D01*
X296405Y131788D01*
X296363Y131538D01*
X296197Y131330D01*
X295363Y130913D01*
X294988Y130622D01*
X294738Y130205D01*
X294655Y129830D01*
X296405D01*
G01X239061Y199513D02*
X250182D01*
Y199313D01*
X247182Y196313D01*
Y202413D01*
X249982Y199613D01*
Y199413D01*
G01X255383Y163563D02*
Y166063D01*
X256424D01*
X256758Y165938D01*
X256966Y165771D01*
X257049Y165438D01*
X256966Y165105D01*
X256716Y164896D01*
X256424Y164771D01*
X255383D01*
G01X256424D02*
X257049Y163563D01*
G01X258399Y164063D02*
X258649Y163771D01*
X258983Y163605D01*
X259358Y163563D01*
X259691Y163605D01*
X260024Y163813D01*
X260233Y164063D01*
X260274Y164313D01*
X260191Y164605D01*
X259899Y164813D01*
X259608Y164896D01*
X259233D01*
G01X259608D02*
X259858Y165021D01*
X260066Y165230D01*
X260149Y165480D01*
X260066Y165730D01*
X259858Y165938D01*
X259483Y166063D01*
X259108Y166021D01*
X258733Y165855D01*
G01X261499Y163563D02*
Y166063D01*
X262333D01*
X262666Y165938D01*
X262916Y165771D01*
X263124Y165521D01*
X263291Y165230D01*
X263333Y164813D01*
X263291Y164396D01*
X263124Y164105D01*
X262916Y163855D01*
X262666Y163688D01*
X262333Y163563D01*
X261499D01*
G01X265516D02*
Y166063D01*
X265016Y165563D01*
G01Y163563D02*
X266016D01*
G01X267824Y165646D02*
X268074Y165896D01*
X268366Y166021D01*
X268699Y166063D01*
X269116Y165980D01*
X269408Y165771D01*
X269491Y165521D01*
X269449Y165271D01*
X269283Y165063D01*
X268449Y164646D01*
X268074Y164355D01*
X267824Y163938D01*
X267741Y163563D01*
X269491D01*
G01X255383Y166963D02*
Y169463D01*
X256424D01*
X256758Y169338D01*
X256966Y169171D01*
X257049Y168838D01*
X256966Y168505D01*
X256716Y168296D01*
X256424Y168171D01*
X255383D01*
G01X256424D02*
X257049Y166963D01*
G01X258399Y167463D02*
X258649Y167171D01*
X258983Y167005D01*
X259358Y166963D01*
X259691Y167005D01*
X260024Y167213D01*
X260233Y167463D01*
X260274Y167713D01*
X260191Y168005D01*
X259899Y168213D01*
X259608Y168296D01*
X259233D01*
G01X259608D02*
X259858Y168421D01*
X260066Y168630D01*
X260149Y168880D01*
X260066Y169130D01*
X259858Y169338D01*
X259483Y169463D01*
X259108Y169421D01*
X258733Y169255D01*
G01X261499Y166963D02*
Y169463D01*
X262333D01*
X262666Y169338D01*
X262916Y169171D01*
X263124Y168921D01*
X263291Y168630D01*
X263333Y168213D01*
X263291Y167796D01*
X263124Y167505D01*
X262916Y167255D01*
X262666Y167088D01*
X262333Y166963D01*
X261499D01*
G01X264808Y167255D02*
X265099Y167046D01*
X265433Y166963D01*
X265766Y167046D01*
X266058Y167296D01*
X266266Y167671D01*
X266349Y168046D01*
Y168505D01*
X266266Y168880D01*
X266058Y169213D01*
X265808Y169380D01*
X265516Y169463D01*
X265183Y169380D01*
X264933Y169213D01*
X264766Y168963D01*
X264683Y168630D01*
X264766Y168338D01*
X264974Y168046D01*
X265224Y167880D01*
X265516Y167838D01*
X265849Y167921D01*
X266099Y168130D01*
X266349Y168505D01*
G01X255383Y160163D02*
Y162663D01*
X256424D01*
X256758Y162538D01*
X256966Y162371D01*
X257049Y162038D01*
X256966Y161705D01*
X256716Y161496D01*
X256424Y161371D01*
X255383D01*
G01X256424D02*
X257049Y160163D01*
G01X258399Y160663D02*
X258649Y160371D01*
X258983Y160205D01*
X259358Y160163D01*
X259691Y160205D01*
X260024Y160413D01*
X260233Y160663D01*
X260274Y160913D01*
X260191Y161205D01*
X259899Y161413D01*
X259608Y161496D01*
X259233D01*
G01X259608D02*
X259858Y161621D01*
X260066Y161830D01*
X260149Y162080D01*
X260066Y162330D01*
X259858Y162538D01*
X259483Y162663D01*
X259108Y162621D01*
X258733Y162455D01*
G01X261499Y160163D02*
Y162663D01*
X262333D01*
X262666Y162538D01*
X262916Y162371D01*
X263124Y162121D01*
X263291Y161830D01*
X263333Y161413D01*
X263291Y160996D01*
X263124Y160705D01*
X262916Y160455D01*
X262666Y160288D01*
X262333Y160163D01*
X261499D01*
G01X265516D02*
Y162663D01*
X265016Y162163D01*
G01Y160163D02*
X266016D01*
G01X267699Y160663D02*
X267949Y160371D01*
X268283Y160205D01*
X268658Y160163D01*
X268991Y160205D01*
X269324Y160413D01*
X269533Y160663D01*
X269574Y160913D01*
X269491Y161205D01*
X269199Y161413D01*
X268908Y161496D01*
X268533D01*
G01X268908D02*
X269158Y161621D01*
X269366Y161830D01*
X269449Y162080D01*
X269366Y162330D01*
X269158Y162538D01*
X268783Y162663D01*
X268408Y162621D01*
X268033Y162455D01*
G01X237000Y192517D02*
X234500D01*
Y193558D01*
X234625Y193892D01*
X234792Y194100D01*
X235125Y194183D01*
X235458Y194100D01*
X235667Y193850D01*
X235792Y193558D01*
Y192517D01*
G01Y193558D02*
X237000Y194183D01*
G01X236500Y195533D02*
X236792Y195783D01*
X236958Y196117D01*
X237000Y196492D01*
X236958Y196825D01*
X236750Y197158D01*
X236500Y197367D01*
X236250Y197408D01*
X235958Y197325D01*
X235750Y197033D01*
X235667Y196742D01*
Y196367D01*
G01Y196742D02*
X235542Y196992D01*
X235333Y197200D01*
X235083Y197283D01*
X234833Y197200D01*
X234625Y196992D01*
X234500Y196617D01*
X234542Y196242D01*
X234708Y195867D01*
G01X237000Y198633D02*
X234500D01*
Y199467D01*
X234625Y199800D01*
X234792Y200050D01*
X235042Y200258D01*
X235333Y200425D01*
X235750Y200467D01*
X236167Y200425D01*
X236458Y200258D01*
X236708Y200050D01*
X236875Y199800D01*
X237000Y199467D01*
Y198633D01*
G01Y203150D02*
X234500D01*
X236292Y201608D01*
Y203692D01*
G01X247481Y161293D02*
X247356Y161043D01*
X247273Y160751D01*
Y160418D01*
X247398Y160043D01*
X247606Y159751D01*
X247856Y159543D01*
X248273Y159376D01*
X248648Y159334D01*
X249023Y159418D01*
X249273Y159543D01*
X249523Y159793D01*
X249690Y160084D01*
X249773Y160376D01*
Y160668D01*
X249690Y160959D01*
X249565Y161209D01*
X249398Y161418D01*
G01X249273Y162559D02*
X249565Y162809D01*
X249731Y163143D01*
X249773Y163518D01*
X249731Y163851D01*
X249523Y164184D01*
X249273Y164393D01*
X249023Y164434D01*
X248731Y164351D01*
X248523Y164059D01*
X248440Y163768D01*
Y163393D01*
G01Y163768D02*
X248315Y164018D01*
X248106Y164226D01*
X247856Y164309D01*
X247606Y164226D01*
X247398Y164018D01*
X247273Y163643D01*
X247315Y163268D01*
X247481Y162893D01*
G01X249773Y165659D02*
X247273D01*
Y166493D01*
X247398Y166826D01*
X247565Y167076D01*
X247815Y167284D01*
X248106Y167451D01*
X248523Y167493D01*
X248940Y167451D01*
X249231Y167284D01*
X249481Y167076D01*
X249648Y166826D01*
X249773Y166493D01*
Y165659D01*
G01Y169676D02*
X247273D01*
X247773Y169176D01*
G01X249773D02*
Y170176D01*
G01X249398Y171859D02*
X249606Y172109D01*
X249731Y172401D01*
X249773Y172776D01*
X249690Y173151D01*
X249523Y173443D01*
X249231Y173651D01*
X248898Y173693D01*
X248565Y173609D01*
X248356Y173401D01*
X248190Y173109D01*
X248148Y172818D01*
X248190Y172526D01*
X248356Y172151D01*
X247273Y172276D01*
Y173401D01*
G01X233881Y161293D02*
X233756Y161043D01*
X233673Y160751D01*
Y160418D01*
X233798Y160043D01*
X234006Y159751D01*
X234256Y159543D01*
X234673Y159376D01*
X235048Y159334D01*
X235423Y159418D01*
X235673Y159543D01*
X235923Y159793D01*
X236090Y160084D01*
X236173Y160376D01*
Y160668D01*
X236090Y160959D01*
X235965Y161209D01*
X235798Y161418D01*
G01X235673Y162559D02*
X235965Y162809D01*
X236131Y163143D01*
X236173Y163518D01*
X236131Y163851D01*
X235923Y164184D01*
X235673Y164393D01*
X235423Y164434D01*
X235131Y164351D01*
X234923Y164059D01*
X234840Y163768D01*
Y163393D01*
G01Y163768D02*
X234715Y164018D01*
X234506Y164226D01*
X234256Y164309D01*
X234006Y164226D01*
X233798Y164018D01*
X233673Y163643D01*
X233715Y163268D01*
X233881Y162893D01*
G01X236173Y165659D02*
X233673D01*
Y166493D01*
X233798Y166826D01*
X233965Y167076D01*
X234215Y167284D01*
X234506Y167451D01*
X234923Y167493D01*
X235340Y167451D01*
X235631Y167284D01*
X235881Y167076D01*
X236048Y166826D01*
X236173Y166493D01*
Y165659D01*
G01Y169676D02*
X233673D01*
X234173Y169176D01*
G01X236173D02*
Y170176D01*
G01Y172776D02*
X233673D01*
X234173Y172276D01*
G01X236173D02*
Y173276D01*
G01X250881Y161293D02*
X250756Y161043D01*
X250673Y160751D01*
Y160418D01*
X250798Y160043D01*
X251006Y159751D01*
X251256Y159543D01*
X251673Y159376D01*
X252048Y159334D01*
X252423Y159418D01*
X252673Y159543D01*
X252923Y159793D01*
X253090Y160084D01*
X253173Y160376D01*
Y160668D01*
X253090Y160959D01*
X252965Y161209D01*
X252798Y161418D01*
G01X252673Y162559D02*
X252965Y162809D01*
X253131Y163143D01*
X253173Y163518D01*
X253131Y163851D01*
X252923Y164184D01*
X252673Y164393D01*
X252423Y164434D01*
X252131Y164351D01*
X251923Y164059D01*
X251840Y163768D01*
Y163393D01*
G01Y163768D02*
X251715Y164018D01*
X251506Y164226D01*
X251256Y164309D01*
X251006Y164226D01*
X250798Y164018D01*
X250673Y163643D01*
X250715Y163268D01*
X250881Y162893D01*
G01X253173Y165659D02*
X250673D01*
Y166493D01*
X250798Y166826D01*
X250965Y167076D01*
X251215Y167284D01*
X251506Y167451D01*
X251923Y167493D01*
X252340Y167451D01*
X252631Y167284D01*
X252881Y167076D01*
X253048Y166826D01*
X253173Y166493D01*
Y165659D01*
G01Y169676D02*
X250673D01*
X251173Y169176D01*
G01X253173D02*
Y170176D01*
G01X252131Y171984D02*
X251840Y172276D01*
X251673Y172526D01*
X251590Y172859D01*
X251673Y173151D01*
X251840Y173359D01*
X252090Y173526D01*
X252381Y173568D01*
X252631Y173526D01*
X252881Y173359D01*
X253090Y173109D01*
X253173Y172818D01*
X253090Y172484D01*
X252840Y172193D01*
X252465Y172026D01*
X252048Y171984D01*
X251506Y172068D01*
X251215Y172193D01*
X250923Y172401D01*
X250715Y172693D01*
X250673Y172984D01*
X250756Y173276D01*
X250965Y173484D01*
G01X240681Y161293D02*
X240556Y161043D01*
X240473Y160751D01*
Y160418D01*
X240598Y160043D01*
X240806Y159751D01*
X241056Y159543D01*
X241473Y159376D01*
X241848Y159334D01*
X242223Y159418D01*
X242473Y159543D01*
X242723Y159793D01*
X242890Y160084D01*
X242973Y160376D01*
Y160668D01*
X242890Y160959D01*
X242765Y161209D01*
X242598Y161418D01*
G01X242473Y162559D02*
X242765Y162809D01*
X242931Y163143D01*
X242973Y163518D01*
X242931Y163851D01*
X242723Y164184D01*
X242473Y164393D01*
X242223Y164434D01*
X241931Y164351D01*
X241723Y164059D01*
X241640Y163768D01*
Y163393D01*
G01Y163768D02*
X241515Y164018D01*
X241306Y164226D01*
X241056Y164309D01*
X240806Y164226D01*
X240598Y164018D01*
X240473Y163643D01*
X240515Y163268D01*
X240681Y162893D01*
G01X242973Y165659D02*
X240473D01*
Y166493D01*
X240598Y166826D01*
X240765Y167076D01*
X241015Y167284D01*
X241306Y167451D01*
X241723Y167493D01*
X242140Y167451D01*
X242431Y167284D01*
X242681Y167076D01*
X242848Y166826D01*
X242973Y166493D01*
Y165659D01*
G01Y169676D02*
X240473D01*
X240973Y169176D01*
G01X242973D02*
Y170176D01*
G01X242473Y171859D02*
X242765Y172109D01*
X242931Y172443D01*
X242973Y172818D01*
X242931Y173151D01*
X242723Y173484D01*
X242473Y173693D01*
X242223Y173734D01*
X241931Y173651D01*
X241723Y173359D01*
X241640Y173068D01*
Y172693D01*
G01Y173068D02*
X241515Y173318D01*
X241306Y173526D01*
X241056Y173609D01*
X240806Y173526D01*
X240598Y173318D01*
X240473Y172943D01*
X240515Y172568D01*
X240681Y172193D01*
G01X237281Y161293D02*
X237156Y161043D01*
X237073Y160751D01*
Y160418D01*
X237198Y160043D01*
X237406Y159751D01*
X237656Y159543D01*
X238073Y159376D01*
X238448Y159334D01*
X238823Y159418D01*
X239073Y159543D01*
X239323Y159793D01*
X239490Y160084D01*
X239573Y160376D01*
Y160668D01*
X239490Y160959D01*
X239365Y161209D01*
X239198Y161418D01*
G01X239073Y162559D02*
X239365Y162809D01*
X239531Y163143D01*
X239573Y163518D01*
X239531Y163851D01*
X239323Y164184D01*
X239073Y164393D01*
X238823Y164434D01*
X238531Y164351D01*
X238323Y164059D01*
X238240Y163768D01*
Y163393D01*
G01Y163768D02*
X238115Y164018D01*
X237906Y164226D01*
X237656Y164309D01*
X237406Y164226D01*
X237198Y164018D01*
X237073Y163643D01*
X237115Y163268D01*
X237281Y162893D01*
G01X239573Y165659D02*
X237073D01*
Y166493D01*
X237198Y166826D01*
X237365Y167076D01*
X237615Y167284D01*
X237906Y167451D01*
X238323Y167493D01*
X238740Y167451D01*
X239031Y167284D01*
X239281Y167076D01*
X239448Y166826D01*
X239573Y166493D01*
Y165659D01*
G01Y169676D02*
X237073D01*
X237573Y169176D01*
G01X239573D02*
Y170176D01*
G01X237490Y171984D02*
X237240Y172234D01*
X237115Y172526D01*
X237073Y172859D01*
X237156Y173276D01*
X237365Y173568D01*
X237615Y173651D01*
X237865Y173609D01*
X238073Y173443D01*
X238490Y172609D01*
X238781Y172234D01*
X239198Y171984D01*
X239573Y171901D01*
Y173651D01*
G01X244081Y161293D02*
X243956Y161043D01*
X243873Y160751D01*
Y160418D01*
X243998Y160043D01*
X244206Y159751D01*
X244456Y159543D01*
X244873Y159376D01*
X245248Y159334D01*
X245623Y159418D01*
X245873Y159543D01*
X246123Y159793D01*
X246290Y160084D01*
X246373Y160376D01*
Y160668D01*
X246290Y160959D01*
X246165Y161209D01*
X245998Y161418D01*
G01X245873Y162559D02*
X246165Y162809D01*
X246331Y163143D01*
X246373Y163518D01*
X246331Y163851D01*
X246123Y164184D01*
X245873Y164393D01*
X245623Y164434D01*
X245331Y164351D01*
X245123Y164059D01*
X245040Y163768D01*
Y163393D01*
G01Y163768D02*
X244915Y164018D01*
X244706Y164226D01*
X244456Y164309D01*
X244206Y164226D01*
X243998Y164018D01*
X243873Y163643D01*
X243915Y163268D01*
X244081Y162893D01*
G01X246373Y165659D02*
X243873D01*
Y166493D01*
X243998Y166826D01*
X244165Y167076D01*
X244415Y167284D01*
X244706Y167451D01*
X245123Y167493D01*
X245540Y167451D01*
X245831Y167284D01*
X246081Y167076D01*
X246248Y166826D01*
X246373Y166493D01*
Y165659D01*
G01Y169676D02*
X243873D01*
X244373Y169176D01*
G01X246373D02*
Y170176D01*
G01Y173276D02*
X243873D01*
X245665Y171734D01*
Y173818D01*
G01X234008Y177367D02*
X233883Y177117D01*
X233800Y176825D01*
Y176492D01*
X233925Y176117D01*
X234133Y175825D01*
X234383Y175617D01*
X234800Y175450D01*
X235175Y175408D01*
X235550Y175492D01*
X235800Y175617D01*
X236050Y175867D01*
X236217Y176158D01*
X236300Y176450D01*
Y176742D01*
X236217Y177033D01*
X236092Y177283D01*
X235925Y177492D01*
G01X235800Y178633D02*
X236092Y178883D01*
X236258Y179217D01*
X236300Y179592D01*
X236258Y179925D01*
X236050Y180258D01*
X235800Y180467D01*
X235550Y180508D01*
X235258Y180425D01*
X235050Y180133D01*
X234967Y179842D01*
Y179467D01*
G01Y179842D02*
X234842Y180092D01*
X234633Y180300D01*
X234383Y180383D01*
X234133Y180300D01*
X233925Y180092D01*
X233800Y179717D01*
X233842Y179342D01*
X234008Y178967D01*
G01X236300Y181733D02*
X233800D01*
Y182567D01*
X233925Y182900D01*
X234092Y183150D01*
X234342Y183358D01*
X234633Y183525D01*
X235050Y183567D01*
X235467Y183525D01*
X235758Y183358D01*
X236008Y183150D01*
X236175Y182900D01*
X236300Y182567D01*
Y181733D01*
G01Y186250D02*
X233800D01*
X235592Y184708D01*
Y186792D01*
G01X256717Y176492D02*
X256467Y176617D01*
X256175Y176700D01*
X255842D01*
X255467Y176575D01*
X255175Y176367D01*
X254967Y176117D01*
X254800Y175700D01*
X254758Y175325D01*
X254842Y174950D01*
X254967Y174700D01*
X255217Y174450D01*
X255508Y174283D01*
X255800Y174200D01*
X256092D01*
X256383Y174283D01*
X256633Y174408D01*
X256842Y174575D01*
G01X257983Y174700D02*
X258233Y174408D01*
X258567Y174242D01*
X258942Y174200D01*
X259275Y174242D01*
X259608Y174450D01*
X259817Y174700D01*
X259858Y174950D01*
X259775Y175242D01*
X259483Y175450D01*
X259192Y175533D01*
X258817D01*
G01X259192D02*
X259442Y175658D01*
X259650Y175867D01*
X259733Y176117D01*
X259650Y176367D01*
X259442Y176575D01*
X259067Y176700D01*
X258692Y176658D01*
X258317Y176492D01*
G01X261083Y174200D02*
Y176700D01*
X261917D01*
X262250Y176575D01*
X262500Y176408D01*
X262708Y176158D01*
X262875Y175867D01*
X262917Y175450D01*
X262875Y175033D01*
X262708Y174742D01*
X262500Y174492D01*
X262250Y174325D01*
X261917Y174200D01*
X261083D01*
G01X264392Y174492D02*
X264683Y174283D01*
X265017Y174200D01*
X265350Y174283D01*
X265642Y174533D01*
X265850Y174908D01*
X265933Y175283D01*
Y175742D01*
X265850Y176117D01*
X265642Y176450D01*
X265392Y176617D01*
X265100Y176700D01*
X264767Y176617D01*
X264517Y176450D01*
X264350Y176200D01*
X264267Y175867D01*
X264350Y175575D01*
X264558Y175283D01*
X264808Y175117D01*
X265100Y175075D01*
X265433Y175158D01*
X265683Y175367D01*
X265933Y175742D01*
G01X240908Y177367D02*
X240783Y177117D01*
X240700Y176825D01*
Y176492D01*
X240825Y176117D01*
X241033Y175825D01*
X241283Y175617D01*
X241700Y175450D01*
X242075Y175408D01*
X242450Y175492D01*
X242700Y175617D01*
X242950Y175867D01*
X243117Y176158D01*
X243200Y176450D01*
Y176742D01*
X243117Y177033D01*
X242992Y177283D01*
X242825Y177492D01*
G01X242700Y178633D02*
X242992Y178883D01*
X243158Y179217D01*
X243200Y179592D01*
X243158Y179925D01*
X242950Y180258D01*
X242700Y180467D01*
X242450Y180508D01*
X242158Y180425D01*
X241950Y180133D01*
X241867Y179842D01*
Y179467D01*
G01Y179842D02*
X241742Y180092D01*
X241533Y180300D01*
X241283Y180383D01*
X241033Y180300D01*
X240825Y180092D01*
X240700Y179717D01*
X240742Y179342D01*
X240908Y178967D01*
G01X243200Y181733D02*
X240700D01*
Y182567D01*
X240825Y182900D01*
X240992Y183150D01*
X241242Y183358D01*
X241533Y183525D01*
X241950Y183567D01*
X242367Y183525D01*
X242658Y183358D01*
X242908Y183150D01*
X243075Y182900D01*
X243200Y182567D01*
Y181733D01*
G01X242158Y184958D02*
X241867Y185250D01*
X241700Y185500D01*
X241617Y185833D01*
X241700Y186125D01*
X241867Y186333D01*
X242117Y186500D01*
X242408Y186542D01*
X242658Y186500D01*
X242908Y186333D01*
X243117Y186083D01*
X243200Y185792D01*
X243117Y185458D01*
X242867Y185167D01*
X242492Y185000D01*
X242075Y184958D01*
X241533Y185042D01*
X241242Y185167D01*
X240950Y185375D01*
X240742Y185667D01*
X240700Y185958D01*
X240783Y186250D01*
X240992Y186458D01*
G01X237508Y177367D02*
X237383Y177117D01*
X237300Y176825D01*
Y176492D01*
X237425Y176117D01*
X237633Y175825D01*
X237883Y175617D01*
X238300Y175450D01*
X238675Y175408D01*
X239050Y175492D01*
X239300Y175617D01*
X239550Y175867D01*
X239717Y176158D01*
X239800Y176450D01*
Y176742D01*
X239717Y177033D01*
X239592Y177283D01*
X239425Y177492D01*
G01X239300Y178633D02*
X239592Y178883D01*
X239758Y179217D01*
X239800Y179592D01*
X239758Y179925D01*
X239550Y180258D01*
X239300Y180467D01*
X239050Y180508D01*
X238758Y180425D01*
X238550Y180133D01*
X238467Y179842D01*
Y179467D01*
G01Y179842D02*
X238342Y180092D01*
X238133Y180300D01*
X237883Y180383D01*
X237633Y180300D01*
X237425Y180092D01*
X237300Y179717D01*
X237342Y179342D01*
X237508Y178967D01*
G01X239800Y181733D02*
X237300D01*
Y182567D01*
X237425Y182900D01*
X237592Y183150D01*
X237842Y183358D01*
X238133Y183525D01*
X238550Y183567D01*
X238967Y183525D01*
X239258Y183358D01*
X239508Y183150D01*
X239675Y182900D01*
X239800Y182567D01*
Y181733D01*
G01X239425Y184833D02*
X239633Y185083D01*
X239758Y185375D01*
X239800Y185750D01*
X239717Y186125D01*
X239550Y186417D01*
X239258Y186625D01*
X238925Y186667D01*
X238592Y186583D01*
X238383Y186375D01*
X238217Y186083D01*
X238175Y185792D01*
X238217Y185500D01*
X238383Y185125D01*
X237300Y185250D01*
Y186375D01*
G01X244308Y177267D02*
X244183Y177017D01*
X244100Y176725D01*
Y176392D01*
X244225Y176017D01*
X244433Y175725D01*
X244683Y175517D01*
X245100Y175350D01*
X245475Y175308D01*
X245850Y175392D01*
X246100Y175517D01*
X246350Y175767D01*
X246517Y176058D01*
X246600Y176350D01*
Y176642D01*
X246517Y176933D01*
X246392Y177183D01*
X246225Y177392D01*
G01X246100Y178533D02*
X246392Y178783D01*
X246558Y179117D01*
X246600Y179492D01*
X246558Y179825D01*
X246350Y180158D01*
X246100Y180367D01*
X245850Y180408D01*
X245558Y180325D01*
X245350Y180033D01*
X245267Y179742D01*
Y179367D01*
G01Y179742D02*
X245142Y179992D01*
X244933Y180200D01*
X244683Y180283D01*
X244433Y180200D01*
X244225Y179992D01*
X244100Y179617D01*
X244142Y179242D01*
X244308Y178867D01*
G01X246600Y181633D02*
X244100D01*
Y182467D01*
X244225Y182800D01*
X244392Y183050D01*
X244642Y183258D01*
X244933Y183425D01*
X245350Y183467D01*
X245767Y183425D01*
X246058Y183258D01*
X246308Y183050D01*
X246475Y182800D01*
X246600Y182467D01*
Y181633D01*
G01Y185567D02*
X246058Y185650D01*
X245600Y185775D01*
X245183Y185942D01*
X244725Y186150D01*
X244100Y186483D01*
Y184817D01*
G01X247708Y177067D02*
X247583Y176817D01*
X247500Y176525D01*
Y176192D01*
X247625Y175817D01*
X247833Y175525D01*
X248083Y175317D01*
X248500Y175150D01*
X248875Y175108D01*
X249250Y175192D01*
X249500Y175317D01*
X249750Y175567D01*
X249917Y175858D01*
X250000Y176150D01*
Y176442D01*
X249917Y176733D01*
X249792Y176983D01*
X249625Y177192D01*
G01X249500Y178333D02*
X249792Y178583D01*
X249958Y178917D01*
X250000Y179292D01*
X249958Y179625D01*
X249750Y179958D01*
X249500Y180167D01*
X249250Y180208D01*
X248958Y180125D01*
X248750Y179833D01*
X248667Y179542D01*
Y179167D01*
G01Y179542D02*
X248542Y179792D01*
X248333Y180000D01*
X248083Y180083D01*
X247833Y180000D01*
X247625Y179792D01*
X247500Y179417D01*
X247542Y179042D01*
X247708Y178667D01*
G01X250000Y181433D02*
X247500D01*
Y182267D01*
X247625Y182600D01*
X247792Y182850D01*
X248042Y183058D01*
X248333Y183225D01*
X248750Y183267D01*
X249167Y183225D01*
X249458Y183058D01*
X249708Y182850D01*
X249875Y182600D01*
X250000Y182267D01*
Y181433D01*
G01Y185450D02*
X249958Y185742D01*
X249833Y186075D01*
X249625Y186283D01*
X249333Y186367D01*
X249042Y186283D01*
X248792Y186033D01*
X248667Y185658D01*
Y185242D01*
X248583Y184992D01*
X248375Y184783D01*
X248083Y184700D01*
X247792Y184825D01*
X247583Y185117D01*
X247500Y185450D01*
X247583Y185783D01*
X247792Y186075D01*
X248083Y186200D01*
X248375Y186117D01*
X248583Y185908D01*
X248667Y185658D01*
Y185242D01*
X248792Y184867D01*
X249042Y184617D01*
X249333Y184533D01*
X249625Y184617D01*
X249833Y184825D01*
X249958Y185158D01*
X250000Y185450D01*
G01X256567Y173092D02*
X256317Y173217D01*
X256025Y173300D01*
X255692D01*
X255317Y173175D01*
X255025Y172967D01*
X254817Y172717D01*
X254650Y172300D01*
X254608Y171925D01*
X254692Y171550D01*
X254817Y171300D01*
X255067Y171050D01*
X255358Y170883D01*
X255650Y170800D01*
X255942D01*
X256233Y170883D01*
X256483Y171008D01*
X256692Y171175D01*
G01X257833Y171300D02*
X258083Y171008D01*
X258417Y170842D01*
X258792Y170800D01*
X259125Y170842D01*
X259458Y171050D01*
X259667Y171300D01*
X259708Y171550D01*
X259625Y171842D01*
X259333Y172050D01*
X259042Y172133D01*
X258667D01*
G01X259042D02*
X259292Y172258D01*
X259500Y172467D01*
X259583Y172717D01*
X259500Y172967D01*
X259292Y173175D01*
X258917Y173300D01*
X258542Y173258D01*
X258167Y173092D01*
G01X260933Y170800D02*
Y173300D01*
X261767D01*
X262100Y173175D01*
X262350Y173008D01*
X262558Y172758D01*
X262725Y172467D01*
X262767Y172050D01*
X262725Y171633D01*
X262558Y171342D01*
X262350Y171092D01*
X262100Y170925D01*
X261767Y170800D01*
X260933D01*
G01X264033Y171300D02*
X264283Y171008D01*
X264617Y170842D01*
X264992Y170800D01*
X265325Y170842D01*
X265658Y171050D01*
X265867Y171300D01*
X265908Y171550D01*
X265825Y171842D01*
X265533Y172050D01*
X265242Y172133D01*
X264867D01*
G01X265242D02*
X265492Y172258D01*
X265700Y172467D01*
X265783Y172717D01*
X265700Y172967D01*
X265492Y173175D01*
X265117Y173300D01*
X264742Y173258D01*
X264367Y173092D01*
G01X241378Y212217D02*
X241253Y211967D01*
X241170Y211675D01*
Y211342D01*
X241295Y210967D01*
X241503Y210675D01*
X241753Y210467D01*
X242170Y210300D01*
X242545Y210258D01*
X242920Y210342D01*
X243170Y210467D01*
X243420Y210717D01*
X243587Y211008D01*
X243670Y211300D01*
Y211592D01*
X243587Y211883D01*
X243462Y212133D01*
X243295Y212342D01*
G01X243670Y214400D02*
X241170D01*
X241670Y213900D01*
G01X243670D02*
Y214900D01*
G01Y218333D02*
Y216667D01*
X241170D01*
Y218333D01*
G01X242378Y217667D02*
Y216667D01*
G01X241587Y219808D02*
X241337Y220058D01*
X241212Y220350D01*
X241170Y220683D01*
X241253Y221100D01*
X241462Y221392D01*
X241712Y221475D01*
X241962Y221433D01*
X242170Y221267D01*
X242587Y220433D01*
X242878Y220058D01*
X243295Y219808D01*
X243670Y219725D01*
Y221475D01*
G01X243295Y222783D02*
X243503Y223033D01*
X243628Y223325D01*
X243670Y223700D01*
X243587Y224075D01*
X243420Y224367D01*
X243128Y224575D01*
X242795Y224617D01*
X242462Y224533D01*
X242253Y224325D01*
X242087Y224033D01*
X242045Y223742D01*
X242087Y223450D01*
X242253Y223075D01*
X241170Y223200D01*
Y224325D01*
G01X237587Y208442D02*
X237337Y208567D01*
X237045Y208650D01*
X236712D01*
X236337Y208525D01*
X236045Y208317D01*
X235837Y208067D01*
X235670Y207650D01*
X235628Y207275D01*
X235712Y206900D01*
X235837Y206650D01*
X236087Y206400D01*
X236378Y206233D01*
X236670Y206150D01*
X236962D01*
X237253Y206233D01*
X237503Y206358D01*
X237712Y206525D01*
G01X239770Y206150D02*
Y208650D01*
X239270Y208150D01*
G01Y206150D02*
X240270D01*
G01X243703D02*
X242037D01*
Y208650D01*
X243703D01*
G01X243037Y207442D02*
X242037D01*
G01X245970Y206150D02*
Y208650D01*
X245470Y208150D01*
G01Y206150D02*
X246470D01*
G01X249570D02*
Y208650D01*
X248028Y206858D01*
X250112D01*
G01X234578Y212217D02*
X234453Y211967D01*
X234370Y211675D01*
Y211342D01*
X234495Y210967D01*
X234703Y210675D01*
X234953Y210467D01*
X235370Y210300D01*
X235745Y210258D01*
X236120Y210342D01*
X236370Y210467D01*
X236620Y210717D01*
X236787Y211008D01*
X236870Y211300D01*
Y211592D01*
X236787Y211883D01*
X236662Y212133D01*
X236495Y212342D01*
G01X234370Y214400D02*
X236870D01*
G01X234370Y213442D02*
Y215358D01*
G01X234787Y216708D02*
X234537Y216958D01*
X234412Y217250D01*
X234370Y217583D01*
X234453Y218000D01*
X234662Y218292D01*
X234912Y218375D01*
X235162Y218333D01*
X235370Y218167D01*
X235787Y217333D01*
X236078Y216958D01*
X236495Y216708D01*
X236870Y216625D01*
Y218375D01*
G01X236495Y219683D02*
X236703Y219933D01*
X236828Y220225D01*
X236870Y220600D01*
X236787Y220975D01*
X236620Y221267D01*
X236328Y221475D01*
X235995Y221517D01*
X235662Y221433D01*
X235453Y221225D01*
X235287Y220933D01*
X235245Y220642D01*
X235287Y220350D01*
X235453Y219975D01*
X234370Y220100D01*
Y221225D01*
G01X237978Y212217D02*
X237853Y211967D01*
X237770Y211675D01*
Y211342D01*
X237895Y210967D01*
X238103Y210675D01*
X238353Y210467D01*
X238770Y210300D01*
X239145Y210258D01*
X239520Y210342D01*
X239770Y210467D01*
X240020Y210717D01*
X240187Y211008D01*
X240270Y211300D01*
Y211592D01*
X240187Y211883D01*
X240062Y212133D01*
X239895Y212342D01*
G01X240270Y214400D02*
X237770D01*
X238270Y213900D01*
G01X240270D02*
Y214900D01*
G01Y218333D02*
Y216667D01*
X237770D01*
Y218333D01*
G01X238978Y217667D02*
Y216667D01*
G01X238187Y219808D02*
X237937Y220058D01*
X237812Y220350D01*
X237770Y220683D01*
X237853Y221100D01*
X238062Y221392D01*
X238312Y221475D01*
X238562Y221433D01*
X238770Y221267D01*
X239187Y220433D01*
X239478Y220058D01*
X239895Y219808D01*
X240270Y219725D01*
Y221475D01*
G01Y224200D02*
X237770D01*
X239562Y222658D01*
Y224742D01*
G01X248178Y212217D02*
X248053Y211967D01*
X247970Y211675D01*
Y211342D01*
X248095Y210967D01*
X248303Y210675D01*
X248553Y210467D01*
X248970Y210300D01*
X249345Y210258D01*
X249720Y210342D01*
X249970Y210467D01*
X250220Y210717D01*
X250387Y211008D01*
X250470Y211300D01*
Y211592D01*
X250387Y211883D01*
X250262Y212133D01*
X250095Y212342D01*
G01X247970Y214400D02*
X250470D01*
G01X247970Y213442D02*
Y215358D01*
G01X248387Y216708D02*
X248137Y216958D01*
X248012Y217250D01*
X247970Y217583D01*
X248053Y218000D01*
X248262Y218292D01*
X248512Y218375D01*
X248762Y218333D01*
X248970Y218167D01*
X249387Y217333D01*
X249678Y216958D01*
X250095Y216708D01*
X250470Y216625D01*
Y218375D01*
G01Y220517D02*
X249928Y220600D01*
X249470Y220725D01*
X249053Y220892D01*
X248595Y221100D01*
X247970Y221433D01*
Y219767D01*
G01X275389Y172853D02*
X275121Y172801D01*
X274814Y172646D01*
X274622Y172388D01*
X274546Y172026D01*
X274622Y171665D01*
X274852Y171355D01*
X275197Y171200D01*
X275581D01*
X275811Y171096D01*
X276002Y170838D01*
X276079Y170476D01*
X275964Y170115D01*
X275696Y169856D01*
X275389Y169753D01*
X275082Y169856D01*
X274814Y170115D01*
X274699Y170476D01*
X274776Y170838D01*
X274967Y171096D01*
X275197Y171200D01*
X275581D01*
X275926Y171355D01*
X276156Y171665D01*
X276232Y172026D01*
X276156Y172388D01*
X275964Y172646D01*
X275657Y172801D01*
X275389Y172853D01*
G01X273017Y171561D02*
X272749Y171200D01*
X272519Y170993D01*
X272212Y170890D01*
X271944Y170993D01*
X271752Y171200D01*
X271599Y171510D01*
X271561Y171871D01*
X271599Y172181D01*
X271752Y172491D01*
X271982Y172750D01*
X272251Y172853D01*
X272557Y172750D01*
X272826Y172440D01*
X272979Y171975D01*
X273017Y171458D01*
X272941Y170786D01*
X272826Y170425D01*
X272634Y170063D01*
X272366Y169805D01*
X272097Y169753D01*
X271829Y169856D01*
X271637Y170115D01*
G01X278703Y176556D02*
X278435Y176504D01*
X278128Y176349D01*
X277936Y176091D01*
X277860Y175729D01*
X277936Y175368D01*
X278166Y175058D01*
X278511Y174903D01*
X278895D01*
X279125Y174799D01*
X279316Y174541D01*
X279393Y174179D01*
X279278Y173818D01*
X279010Y173559D01*
X278703Y173456D01*
X278396Y173559D01*
X278128Y173818D01*
X278013Y174179D01*
X278090Y174541D01*
X278281Y174799D01*
X278511Y174903D01*
X278895D01*
X279240Y175058D01*
X279470Y175368D01*
X279546Y175729D01*
X279470Y176091D01*
X279278Y176349D01*
X278971Y176504D01*
X278703Y176556D01*
G01X276446Y176091D02*
X276216Y176349D01*
X275948Y176504D01*
X275603Y176556D01*
X275258Y176453D01*
X274990Y176246D01*
X274798Y175884D01*
X274760Y175471D01*
X274836Y175058D01*
X275028Y174799D01*
X275296Y174593D01*
X275565Y174541D01*
X275833Y174593D01*
X276178Y174799D01*
X276063Y173456D01*
X275028D01*
G01X282148Y172853D02*
X281880Y172801D01*
X281573Y172646D01*
X281381Y172388D01*
X281305Y172026D01*
X281381Y171665D01*
X281611Y171355D01*
X281956Y171200D01*
X282340D01*
X282570Y171096D01*
X282761Y170838D01*
X282838Y170476D01*
X282723Y170115D01*
X282455Y169856D01*
X282148Y169753D01*
X281841Y169856D01*
X281573Y170115D01*
X281458Y170476D01*
X281535Y170838D01*
X281726Y171096D01*
X281956Y171200D01*
X282340D01*
X282685Y171355D01*
X282915Y171665D01*
X282991Y172026D01*
X282915Y172388D01*
X282723Y172646D01*
X282416Y172801D01*
X282148Y172853D01*
G01X278588D02*
Y169753D01*
X280006Y171975D01*
X278090D01*
G01X285463Y176556D02*
X285195Y176504D01*
X284888Y176349D01*
X284696Y176091D01*
X284620Y175729D01*
X284696Y175368D01*
X284926Y175058D01*
X285271Y174903D01*
X285655D01*
X285885Y174799D01*
X286076Y174541D01*
X286153Y174179D01*
X286038Y173818D01*
X285770Y173559D01*
X285463Y173456D01*
X285156Y173559D01*
X284888Y173818D01*
X284773Y174179D01*
X284850Y174541D01*
X285041Y174799D01*
X285271Y174903D01*
X285655D01*
X286000Y175058D01*
X286230Y175368D01*
X286306Y175729D01*
X286230Y176091D01*
X286038Y176349D01*
X285731Y176504D01*
X285463Y176556D01*
G01X283206Y175936D02*
X282976Y176298D01*
X282670Y176504D01*
X282325Y176556D01*
X282018Y176504D01*
X281711Y176246D01*
X281520Y175936D01*
X281481Y175626D01*
X281558Y175264D01*
X281826Y175006D01*
X282095Y174903D01*
X282440D01*
G01X282095D02*
X281865Y174748D01*
X281673Y174489D01*
X281596Y174179D01*
X281673Y173869D01*
X281865Y173611D01*
X282210Y173456D01*
X282555Y173508D01*
X282900Y173714D01*
G01X288908Y172853D02*
X288640Y172801D01*
X288333Y172646D01*
X288141Y172388D01*
X288065Y172026D01*
X288141Y171665D01*
X288371Y171355D01*
X288716Y171200D01*
X289100D01*
X289330Y171096D01*
X289521Y170838D01*
X289598Y170476D01*
X289483Y170115D01*
X289215Y169856D01*
X288908Y169753D01*
X288601Y169856D01*
X288333Y170115D01*
X288218Y170476D01*
X288295Y170838D01*
X288486Y171096D01*
X288716Y171200D01*
X289100D01*
X289445Y171355D01*
X289675Y171665D01*
X289751Y172026D01*
X289675Y172388D01*
X289483Y172646D01*
X289176Y172801D01*
X288908Y172853D01*
G01X286536Y170270D02*
X286306Y169960D01*
X286038Y169805D01*
X285731Y169753D01*
X285348Y169856D01*
X285080Y170115D01*
X285003Y170425D01*
X285041Y170735D01*
X285195Y170993D01*
X285961Y171510D01*
X286306Y171871D01*
X286536Y172388D01*
X286613Y172853D01*
X285003D01*
G01X292223Y176556D02*
X291955Y176504D01*
X291648Y176349D01*
X291456Y176091D01*
X291380Y175729D01*
X291456Y175368D01*
X291686Y175058D01*
X292031Y174903D01*
X292415D01*
X292645Y174799D01*
X292836Y174541D01*
X292913Y174179D01*
X292798Y173818D01*
X292530Y173559D01*
X292223Y173456D01*
X291916Y173559D01*
X291648Y173818D01*
X291533Y174179D01*
X291610Y174541D01*
X291801Y174799D01*
X292031Y174903D01*
X292415D01*
X292760Y175058D01*
X292990Y175368D01*
X293066Y175729D01*
X292990Y176091D01*
X292798Y176349D01*
X292491Y176504D01*
X292223Y176556D01*
G01X289123D02*
Y173456D01*
X289583Y174076D01*
G01Y176556D02*
X288663D01*
G01X295668Y172853D02*
X295400Y172801D01*
X295093Y172646D01*
X294901Y172388D01*
X294825Y172026D01*
X294901Y171665D01*
X295131Y171355D01*
X295476Y171200D01*
X295860D01*
X296090Y171096D01*
X296281Y170838D01*
X296358Y170476D01*
X296243Y170115D01*
X295975Y169856D01*
X295668Y169753D01*
X295361Y169856D01*
X295093Y170115D01*
X294978Y170476D01*
X295055Y170838D01*
X295246Y171096D01*
X295476Y171200D01*
X295860D01*
X296205Y171355D01*
X296435Y171665D01*
X296511Y172026D01*
X296435Y172388D01*
X296243Y172646D01*
X295936Y172801D01*
X295668Y172853D01*
G01X292568Y169753D02*
X292875Y169856D01*
X293105Y170115D01*
X293258Y170425D01*
X293373Y170838D01*
X293411Y171303D01*
X293373Y171768D01*
X293258Y172181D01*
X293105Y172491D01*
X292875Y172750D01*
X292568Y172853D01*
X292261Y172750D01*
X292031Y172491D01*
X291878Y172181D01*
X291763Y171768D01*
X291725Y171303D01*
X291763Y170838D01*
X291878Y170425D01*
X292031Y170115D01*
X292261Y169856D01*
X292568Y169753D01*
G01X279526Y413583D02*
Y423622D01*
X251967D01*
Y332874D01*
X265746Y319095D01*
Y313189D01*
X267715D01*
Y289567D01*
X265746D01*
Y283662D01*
X251967Y269882D01*
Y179134D01*
X279526D01*
Y189174D01*
X407085D01*
Y185237D01*
X411022D01*
Y262992D01*
X387951D01*
X362006Y278583D01*
Y324174D01*
X387951Y339764D01*
X413384D01*
Y413583D01*
X411022D01*
Y417520D01*
X407085D01*
Y413583D01*
X279526D01*
G01X247070Y210467D02*
X244570D01*
Y211508D01*
X244695Y211842D01*
X244862Y212050D01*
X245195Y212133D01*
X245528Y212050D01*
X245737Y211800D01*
X245862Y211508D01*
Y210467D01*
G01Y211508D02*
X247070Y212133D01*
G01X244570Y214400D02*
X247070D01*
G01X244570Y213442D02*
Y215358D01*
G01X247070Y217500D02*
X244570D01*
X245070Y217000D01*
G01X247070D02*
Y218000D01*
G01Y220600D02*
X247028Y220892D01*
X246903Y221225D01*
X246695Y221433D01*
X246403Y221517D01*
X246112Y221433D01*
X245862Y221183D01*
X245737Y220808D01*
Y220392D01*
X245653Y220142D01*
X245445Y219933D01*
X245153Y219850D01*
X244862Y219975D01*
X244653Y220267D01*
X244570Y220600D01*
X244653Y220933D01*
X244862Y221225D01*
X245153Y221350D01*
X245445Y221267D01*
X245653Y221058D01*
X245737Y220808D01*
Y220392D01*
X245862Y220017D01*
X246112Y219767D01*
X246403Y219683D01*
X246695Y219767D01*
X246903Y219975D01*
X247028Y220308D01*
X247070Y220600D01*
G01X252000Y271591D02*
Y318199D01*
X251999Y318200D01*
G01X241442Y237037D02*
X241317Y236787D01*
X241234Y236495D01*
Y236162D01*
X241359Y235787D01*
X241567Y235495D01*
X241817Y235287D01*
X242234Y235120D01*
X242609Y235078D01*
X242984Y235162D01*
X243234Y235287D01*
X243484Y235537D01*
X243651Y235828D01*
X243734Y236120D01*
Y236412D01*
X243651Y236703D01*
X243526Y236953D01*
X243359Y237162D01*
G01X243734Y239220D02*
X241234D01*
X241734Y238720D01*
G01X243734D02*
Y239720D01*
G01Y241403D02*
X241234D01*
Y242237D01*
X241359Y242570D01*
X241526Y242820D01*
X241776Y243028D01*
X242067Y243195D01*
X242484Y243237D01*
X242901Y243195D01*
X243192Y243028D01*
X243442Y242820D01*
X243609Y242570D01*
X243734Y242237D01*
Y241403D01*
G01Y245420D02*
X241234D01*
X241734Y244920D01*
G01X243734D02*
Y245920D01*
G01X242692Y247728D02*
X242401Y248020D01*
X242234Y248270D01*
X242151Y248603D01*
X242234Y248895D01*
X242401Y249103D01*
X242651Y249270D01*
X242942Y249312D01*
X243192Y249270D01*
X243442Y249103D01*
X243651Y248853D01*
X243734Y248562D01*
X243651Y248228D01*
X243401Y247937D01*
X243026Y247770D01*
X242609Y247728D01*
X242067Y247812D01*
X241776Y247937D01*
X241484Y248145D01*
X241276Y248437D01*
X241234Y248728D01*
X241317Y249020D01*
X241526Y249228D01*
G01X237918Y237037D02*
X237793Y236787D01*
X237710Y236495D01*
Y236162D01*
X237835Y235787D01*
X238043Y235495D01*
X238293Y235287D01*
X238710Y235120D01*
X239085Y235078D01*
X239460Y235162D01*
X239710Y235287D01*
X239960Y235537D01*
X240127Y235828D01*
X240210Y236120D01*
Y236412D01*
X240127Y236703D01*
X240002Y236953D01*
X239835Y237162D01*
G01X240210Y239220D02*
X237710D01*
X238210Y238720D01*
G01X240210D02*
Y239720D01*
G01Y241403D02*
X237710D01*
Y242237D01*
X237835Y242570D01*
X238002Y242820D01*
X238252Y243028D01*
X238543Y243195D01*
X238960Y243237D01*
X239377Y243195D01*
X239668Y243028D01*
X239918Y242820D01*
X240085Y242570D01*
X240210Y242237D01*
Y241403D01*
G01Y245420D02*
X237710D01*
X238210Y244920D01*
G01X240210D02*
Y245920D01*
G01Y248437D02*
X239668Y248520D01*
X239210Y248645D01*
X238793Y248812D01*
X238335Y249020D01*
X237710Y249353D01*
Y247687D01*
G01X238287Y258712D02*
X238037Y258837D01*
X237745Y258920D01*
X237412D01*
X237037Y258795D01*
X236745Y258587D01*
X236537Y258337D01*
X236370Y257920D01*
X236328Y257545D01*
X236412Y257170D01*
X236537Y256920D01*
X236787Y256670D01*
X237078Y256503D01*
X237370Y256420D01*
X237662D01*
X237953Y256503D01*
X238203Y256628D01*
X238412Y256795D01*
G01X240470Y256420D02*
Y258920D01*
X239970Y258420D01*
G01Y256420D02*
X240970D01*
G01X242653D02*
Y258920D01*
X243487D01*
X243820Y258795D01*
X244070Y258628D01*
X244278Y258378D01*
X244445Y258087D01*
X244487Y257670D01*
X244445Y257253D01*
X244278Y256962D01*
X244070Y256712D01*
X243820Y256545D01*
X243487Y256420D01*
X242653D01*
G01X245878Y258503D02*
X246128Y258753D01*
X246420Y258878D01*
X246753Y258920D01*
X247170Y258837D01*
X247462Y258628D01*
X247545Y258378D01*
X247503Y258128D01*
X247337Y257920D01*
X246503Y257503D01*
X246128Y257212D01*
X245878Y256795D01*
X245795Y256420D01*
X247545D01*
G01X249770D02*
X250062Y256462D01*
X250395Y256587D01*
X250603Y256795D01*
X250687Y257087D01*
X250603Y257378D01*
X250353Y257628D01*
X249978Y257753D01*
X249562D01*
X249312Y257837D01*
X249103Y258045D01*
X249020Y258337D01*
X249145Y258628D01*
X249437Y258837D01*
X249770Y258920D01*
X250103Y258837D01*
X250395Y258628D01*
X250520Y258337D01*
X250437Y258045D01*
X250228Y257837D01*
X249978Y257753D01*
X249562D01*
X249187Y257628D01*
X248937Y257378D01*
X248853Y257087D01*
X248937Y256795D01*
X249145Y256587D01*
X249478Y256462D01*
X249770Y256420D01*
G01X237131Y281573D02*
X236881Y281698D01*
X236589Y281781D01*
X236256D01*
X235881Y281656D01*
X235589Y281448D01*
X235381Y281198D01*
X235214Y280781D01*
X235172Y280406D01*
X235256Y280031D01*
X235381Y279781D01*
X235631Y279531D01*
X235922Y279364D01*
X236214Y279281D01*
X236506D01*
X236797Y279364D01*
X237047Y279489D01*
X237256Y279656D01*
G01X239314Y279281D02*
Y281781D01*
X238814Y281281D01*
G01Y279281D02*
X239814D01*
G01X241497D02*
Y281781D01*
X242331D01*
X242664Y281656D01*
X242914Y281489D01*
X243122Y281239D01*
X243289Y280948D01*
X243331Y280531D01*
X243289Y280114D01*
X243122Y279823D01*
X242914Y279573D01*
X242664Y279406D01*
X242331Y279281D01*
X241497D01*
G01X245514D02*
Y281781D01*
X245014Y281281D01*
G01Y279281D02*
X246014D01*
G01X247697Y279781D02*
X247947Y279489D01*
X248281Y279323D01*
X248656Y279281D01*
X248989Y279323D01*
X249322Y279531D01*
X249531Y279781D01*
X249572Y280031D01*
X249489Y280323D01*
X249197Y280531D01*
X248906Y280614D01*
X248531D01*
G01X248906D02*
X249156Y280739D01*
X249364Y280948D01*
X249447Y281198D01*
X249364Y281448D01*
X249156Y281656D01*
X248781Y281781D01*
X248406Y281739D01*
X248031Y281573D01*
G01X238150Y262167D02*
X238025Y261917D01*
X237942Y261625D01*
Y261292D01*
X238067Y260917D01*
X238275Y260625D01*
X238525Y260417D01*
X238942Y260250D01*
X239317Y260208D01*
X239692Y260292D01*
X239942Y260417D01*
X240192Y260667D01*
X240359Y260958D01*
X240442Y261250D01*
Y261542D01*
X240359Y261833D01*
X240234Y262083D01*
X240067Y262292D01*
G01X240442Y264350D02*
X237942D01*
X238442Y263850D01*
G01X240442D02*
Y264850D01*
G01Y266533D02*
X237942D01*
Y267367D01*
X238067Y267700D01*
X238234Y267950D01*
X238484Y268158D01*
X238775Y268325D01*
X239192Y268367D01*
X239609Y268325D01*
X239900Y268158D01*
X240150Y267950D01*
X240317Y267700D01*
X240442Y267367D01*
Y266533D01*
G01Y270467D02*
X239900Y270550D01*
X239442Y270675D01*
X239025Y270842D01*
X238567Y271050D01*
X237942Y271383D01*
Y269717D01*
G01X241550Y262167D02*
X241425Y261917D01*
X241342Y261625D01*
Y261292D01*
X241467Y260917D01*
X241675Y260625D01*
X241925Y260417D01*
X242342Y260250D01*
X242717Y260208D01*
X243092Y260292D01*
X243342Y260417D01*
X243592Y260667D01*
X243759Y260958D01*
X243842Y261250D01*
Y261542D01*
X243759Y261833D01*
X243634Y262083D01*
X243467Y262292D01*
G01X243842Y264350D02*
X241342D01*
X241842Y263850D01*
G01X243842D02*
Y264850D01*
G01Y266533D02*
X241342D01*
Y267367D01*
X241467Y267700D01*
X241634Y267950D01*
X241884Y268158D01*
X242175Y268325D01*
X242592Y268367D01*
X243009Y268325D01*
X243300Y268158D01*
X243550Y267950D01*
X243717Y267700D01*
X243842Y267367D01*
Y266533D01*
G01X242800Y269758D02*
X242509Y270050D01*
X242342Y270300D01*
X242259Y270633D01*
X242342Y270925D01*
X242509Y271133D01*
X242759Y271300D01*
X243050Y271342D01*
X243300Y271300D01*
X243550Y271133D01*
X243759Y270883D01*
X243842Y270592D01*
X243759Y270258D01*
X243509Y269967D01*
X243134Y269800D01*
X242717Y269758D01*
X242175Y269842D01*
X241884Y269967D01*
X241592Y270175D01*
X241384Y270467D01*
X241342Y270758D01*
X241425Y271050D01*
X241634Y271258D01*
G01X234736Y262047D02*
X234611Y261797D01*
X234528Y261505D01*
Y261172D01*
X234653Y260797D01*
X234861Y260505D01*
X235111Y260297D01*
X235528Y260130D01*
X235903Y260088D01*
X236278Y260172D01*
X236528Y260297D01*
X236778Y260547D01*
X236945Y260838D01*
X237028Y261130D01*
Y261422D01*
X236945Y261713D01*
X236820Y261963D01*
X236653Y262172D01*
G01X234528Y264230D02*
X237028D01*
G01X234528Y263272D02*
Y265188D01*
G01X234945Y266538D02*
X234695Y266788D01*
X234570Y267080D01*
X234528Y267413D01*
X234611Y267830D01*
X234820Y268122D01*
X235070Y268205D01*
X235320Y268163D01*
X235528Y267997D01*
X235945Y267163D01*
X236236Y266788D01*
X236653Y266538D01*
X237028Y266455D01*
Y268205D01*
G01Y270430D02*
X234528D01*
X235028Y269930D01*
G01X237028D02*
Y270930D01*
G01X234518Y237037D02*
X234393Y236787D01*
X234310Y236495D01*
Y236162D01*
X234435Y235787D01*
X234643Y235495D01*
X234893Y235287D01*
X235310Y235120D01*
X235685Y235078D01*
X236060Y235162D01*
X236310Y235287D01*
X236560Y235537D01*
X236727Y235828D01*
X236810Y236120D01*
Y236412D01*
X236727Y236703D01*
X236602Y236953D01*
X236435Y237162D01*
G01X234310Y239220D02*
X236810D01*
G01X234310Y238262D02*
Y240178D01*
G01X236810Y242320D02*
X234310D01*
X234810Y241820D01*
G01X236810D02*
Y242820D01*
G01X235768Y244628D02*
X235477Y244920D01*
X235310Y245170D01*
X235227Y245503D01*
X235310Y245795D01*
X235477Y246003D01*
X235727Y246170D01*
X236018Y246212D01*
X236268Y246170D01*
X236518Y246003D01*
X236727Y245753D01*
X236810Y245462D01*
X236727Y245128D01*
X236477Y244837D01*
X236102Y244670D01*
X235685Y244628D01*
X235143Y244712D01*
X234852Y244837D01*
X234560Y245045D01*
X234352Y245337D01*
X234310Y245628D01*
X234393Y245920D01*
X234602Y246128D01*
G01X237057Y233532D02*
X236807Y233657D01*
X236515Y233740D01*
X236182D01*
X235807Y233615D01*
X235515Y233407D01*
X235307Y233157D01*
X235140Y232740D01*
X235098Y232365D01*
X235182Y231990D01*
X235307Y231740D01*
X235557Y231490D01*
X235848Y231323D01*
X236140Y231240D01*
X236432D01*
X236723Y231323D01*
X236973Y231448D01*
X237182Y231615D01*
G01X239240Y231240D02*
Y233740D01*
X238740Y233240D01*
G01Y231240D02*
X239740D01*
G01X241423D02*
Y233740D01*
X242257D01*
X242590Y233615D01*
X242840Y233448D01*
X243048Y233198D01*
X243215Y232907D01*
X243257Y232490D01*
X243215Y232073D01*
X243048Y231782D01*
X242840Y231532D01*
X242590Y231365D01*
X242257Y231240D01*
X241423D01*
G01X244523Y231740D02*
X244773Y231448D01*
X245107Y231282D01*
X245482Y231240D01*
X245815Y231282D01*
X246148Y231490D01*
X246357Y231740D01*
X246398Y231990D01*
X246315Y232282D01*
X246023Y232490D01*
X245732Y232573D01*
X245357D01*
G01X245732D02*
X245982Y232698D01*
X246190Y232907D01*
X246273Y233157D01*
X246190Y233407D01*
X245982Y233615D01*
X245607Y233740D01*
X245232Y233698D01*
X244857Y233532D01*
G01X249040Y231240D02*
Y233740D01*
X247498Y231948D01*
X249582D01*
G01X248442Y237067D02*
X248317Y236817D01*
X248234Y236525D01*
Y236192D01*
X248359Y235817D01*
X248567Y235525D01*
X248817Y235317D01*
X249234Y235150D01*
X249609Y235108D01*
X249984Y235192D01*
X250234Y235317D01*
X250484Y235567D01*
X250651Y235858D01*
X250734Y236150D01*
Y236442D01*
X250651Y236733D01*
X250526Y236983D01*
X250359Y237192D01*
G01X248234Y239250D02*
X250734D01*
G01X248234Y238292D02*
Y240208D01*
G01X250734Y242350D02*
X248234D01*
X248734Y241850D01*
G01X250734D02*
Y242850D01*
G01Y245450D02*
X250692Y245742D01*
X250567Y246075D01*
X250359Y246283D01*
X250067Y246367D01*
X249776Y246283D01*
X249526Y246033D01*
X249401Y245658D01*
Y245242D01*
X249317Y244992D01*
X249109Y244783D01*
X248817Y244700D01*
X248526Y244825D01*
X248317Y245117D01*
X248234Y245450D01*
X248317Y245783D01*
X248526Y246075D01*
X248817Y246200D01*
X249109Y246117D01*
X249317Y245908D01*
X249401Y245658D01*
Y245242D01*
X249526Y244867D01*
X249776Y244617D01*
X250067Y244533D01*
X250359Y244617D01*
X250567Y244825D01*
X250692Y245158D01*
X250734Y245450D01*
G01X248450Y262267D02*
X248325Y262017D01*
X248242Y261725D01*
Y261392D01*
X248367Y261017D01*
X248575Y260725D01*
X248825Y260517D01*
X249242Y260350D01*
X249617Y260308D01*
X249992Y260392D01*
X250242Y260517D01*
X250492Y260767D01*
X250659Y261058D01*
X250742Y261350D01*
Y261642D01*
X250659Y261933D01*
X250534Y262183D01*
X250367Y262392D01*
G01X248242Y264450D02*
X250742D01*
G01X248242Y263492D02*
Y265408D01*
G01X248659Y266758D02*
X248409Y267008D01*
X248284Y267300D01*
X248242Y267633D01*
X248325Y268050D01*
X248534Y268342D01*
X248784Y268425D01*
X249034Y268383D01*
X249242Y268217D01*
X249659Y267383D01*
X249950Y267008D01*
X250367Y266758D01*
X250742Y266675D01*
Y268425D01*
G01X248242Y270650D02*
X248325Y270317D01*
X248534Y270067D01*
X248784Y269900D01*
X249117Y269775D01*
X249492Y269733D01*
X249867Y269775D01*
X250200Y269900D01*
X250450Y270067D01*
X250659Y270317D01*
X250742Y270650D01*
X250659Y270983D01*
X250450Y271233D01*
X250200Y271400D01*
X249867Y271525D01*
X249492Y271567D01*
X249117Y271525D01*
X248784Y271400D01*
X248534Y271233D01*
X248325Y270983D01*
X248242Y270650D01*
G01X247242Y260417D02*
X244742D01*
Y261458D01*
X244867Y261792D01*
X245034Y262000D01*
X245367Y262083D01*
X245700Y262000D01*
X245909Y261750D01*
X246034Y261458D01*
Y260417D01*
G01Y261458D02*
X247242Y262083D01*
G01X244742Y264350D02*
X247242D01*
G01X244742Y263392D02*
Y265308D01*
G01X247242Y267450D02*
X244742D01*
X245242Y266950D01*
G01X247242D02*
Y267950D01*
G01X246742Y269633D02*
X247034Y269883D01*
X247200Y270217D01*
X247242Y270592D01*
X247200Y270925D01*
X246992Y271258D01*
X246742Y271467D01*
X246492Y271508D01*
X246200Y271425D01*
X245992Y271133D01*
X245909Y270842D01*
Y270467D01*
G01Y270842D02*
X245784Y271092D01*
X245575Y271300D01*
X245325Y271383D01*
X245075Y271300D01*
X244867Y271092D01*
X244742Y270717D01*
X244784Y270342D01*
X244950Y269967D01*
G01X247210Y235187D02*
X244710D01*
Y236228D01*
X244835Y236562D01*
X245002Y236770D01*
X245335Y236853D01*
X245668Y236770D01*
X245877Y236520D01*
X246002Y236228D01*
Y235187D01*
G01Y236228D02*
X247210Y236853D01*
G01X244710Y239120D02*
X247210D01*
G01X244710Y238162D02*
Y240078D01*
G01X247210Y242220D02*
X244710D01*
X245210Y241720D01*
G01X247210D02*
Y242720D01*
G01X245127Y244528D02*
X244877Y244778D01*
X244752Y245070D01*
X244710Y245403D01*
X244793Y245820D01*
X245002Y246112D01*
X245252Y246195D01*
X245502Y246153D01*
X245710Y245987D01*
X246127Y245153D01*
X246418Y244778D01*
X246835Y244528D01*
X247210Y244445D01*
Y246195D01*
G01X238403Y251720D02*
X236737D01*
Y254220D01*
X238403D01*
G01X237737Y253012D02*
X236737D01*
G01X239753Y254220D02*
Y252428D01*
X239920Y252053D01*
X240253Y251803D01*
X240670Y251720D01*
X241087Y251803D01*
X241420Y252053D01*
X241587Y252428D01*
Y254220D01*
G01X243770Y251720D02*
Y254220D01*
X243270Y253720D01*
G01Y251720D02*
X244270D01*
G01X245953D02*
Y254220D01*
X246787D01*
X247120Y254095D01*
X247370Y253928D01*
X247578Y253678D01*
X247745Y253387D01*
X247787Y252970D01*
X247745Y252553D01*
X247578Y252262D01*
X247370Y252012D01*
X247120Y251845D01*
X246787Y251720D01*
X245953D01*
G01X249053Y252220D02*
X249303Y251928D01*
X249637Y251762D01*
X250012Y251720D01*
X250345Y251762D01*
X250678Y251970D01*
X250887Y252220D01*
X250928Y252470D01*
X250845Y252762D01*
X250553Y252970D01*
X250262Y253053D01*
X249887D01*
G01X250262D02*
X250512Y253178D01*
X250720Y253387D01*
X250803Y253637D01*
X250720Y253887D01*
X250512Y254095D01*
X250137Y254220D01*
X249762Y254178D01*
X249387Y254012D01*
G01X235772Y275683D02*
X234106D01*
Y278183D01*
X235772D01*
G01X235106Y276975D02*
X234106D01*
G01X237122Y278183D02*
Y276391D01*
X237289Y276016D01*
X237622Y275766D01*
X238039Y275683D01*
X238456Y275766D01*
X238789Y276016D01*
X238956Y276391D01*
Y278183D01*
G01X241139Y275683D02*
Y278183D01*
X240639Y277683D01*
G01Y275683D02*
X241639D01*
G01X243322D02*
Y278183D01*
X244156D01*
X244489Y278058D01*
X244739Y277891D01*
X244947Y277641D01*
X245114Y277350D01*
X245156Y276933D01*
X245114Y276516D01*
X244947Y276225D01*
X244739Y275975D01*
X244489Y275808D01*
X244156Y275683D01*
X243322D01*
G01X247339D02*
Y278183D01*
X246839Y277683D01*
G01Y275683D02*
X247839D01*
G01X236973Y226640D02*
X235307D01*
Y229140D01*
X236973D01*
G01X236307Y227932D02*
X235307D01*
G01X238323Y229140D02*
Y227348D01*
X238490Y226973D01*
X238823Y226723D01*
X239240Y226640D01*
X239657Y226723D01*
X239990Y226973D01*
X240157Y227348D01*
Y229140D01*
G01X242340Y226640D02*
Y229140D01*
X241840Y228640D01*
G01Y226640D02*
X242840D01*
G01X244523D02*
Y229140D01*
X245357D01*
X245690Y229015D01*
X245940Y228848D01*
X246148Y228598D01*
X246315Y228307D01*
X246357Y227890D01*
X246315Y227473D01*
X246148Y227182D01*
X245940Y226932D01*
X245690Y226765D01*
X245357Y226640D01*
X244523D01*
G01X249040D02*
Y229140D01*
X247498Y227348D01*
X249582D01*
G01X232365Y333280D02*
Y335780D01*
X233406D01*
X233740Y335655D01*
X233948Y335488D01*
X234031Y335155D01*
X233948Y334822D01*
X233698Y334613D01*
X233406Y334488D01*
X232365D01*
G01X233406D02*
X234031Y333280D01*
G01X236298D02*
Y335780D01*
X235798Y335280D01*
G01Y333280D02*
X236798D01*
G01X238481D02*
Y335780D01*
X239315D01*
X239648Y335655D01*
X239898Y335488D01*
X240106Y335238D01*
X240273Y334947D01*
X240315Y334530D01*
X240273Y334113D01*
X240106Y333822D01*
X239898Y333572D01*
X239648Y333405D01*
X239315Y333280D01*
X238481D01*
G01X241581Y333780D02*
X241831Y333488D01*
X242165Y333322D01*
X242540Y333280D01*
X242873Y333322D01*
X243206Y333530D01*
X243415Y333780D01*
X243456Y334030D01*
X243373Y334322D01*
X243081Y334530D01*
X242790Y334613D01*
X242415D01*
G01X242790D02*
X243040Y334738D01*
X243248Y334947D01*
X243331Y335197D01*
X243248Y335447D01*
X243040Y335655D01*
X242665Y335780D01*
X242290Y335738D01*
X241915Y335572D01*
G01X246098Y333280D02*
Y335780D01*
X244556Y333988D01*
X246640D01*
G01X232365Y336680D02*
Y339180D01*
X233406D01*
X233740Y339055D01*
X233948Y338888D01*
X234031Y338555D01*
X233948Y338222D01*
X233698Y338013D01*
X233406Y337888D01*
X232365D01*
G01X233406D02*
X234031Y336680D01*
G01X236298D02*
Y339180D01*
X235798Y338680D01*
G01Y336680D02*
X236798D01*
G01X238481D02*
Y339180D01*
X239315D01*
X239648Y339055D01*
X239898Y338888D01*
X240106Y338638D01*
X240273Y338347D01*
X240315Y337930D01*
X240273Y337513D01*
X240106Y337222D01*
X239898Y336972D01*
X239648Y336805D01*
X239315Y336680D01*
X238481D01*
G01X241581Y337180D02*
X241831Y336888D01*
X242165Y336722D01*
X242540Y336680D01*
X242873Y336722D01*
X243206Y336930D01*
X243415Y337180D01*
X243456Y337430D01*
X243373Y337722D01*
X243081Y337930D01*
X242790Y338013D01*
X242415D01*
G01X242790D02*
X243040Y338138D01*
X243248Y338347D01*
X243331Y338597D01*
X243248Y338847D01*
X243040Y339055D01*
X242665Y339180D01*
X242290Y339138D01*
X241915Y338972D01*
G01X244806Y338763D02*
X245056Y339013D01*
X245348Y339138D01*
X245681Y339180D01*
X246098Y339097D01*
X246390Y338888D01*
X246473Y338638D01*
X246431Y338388D01*
X246265Y338180D01*
X245431Y337763D01*
X245056Y337472D01*
X244806Y337055D01*
X244723Y336680D01*
X246473D01*
G01X232365Y326480D02*
Y328980D01*
X233406D01*
X233740Y328855D01*
X233948Y328688D01*
X234031Y328355D01*
X233948Y328022D01*
X233698Y327813D01*
X233406Y327688D01*
X232365D01*
G01X233406D02*
X234031Y326480D01*
G01X236298D02*
Y328980D01*
X235798Y328480D01*
G01Y326480D02*
X236798D01*
G01X238481D02*
Y328980D01*
X239315D01*
X239648Y328855D01*
X239898Y328688D01*
X240106Y328438D01*
X240273Y328147D01*
X240315Y327730D01*
X240273Y327313D01*
X240106Y327022D01*
X239898Y326772D01*
X239648Y326605D01*
X239315Y326480D01*
X238481D01*
G01X241581Y326980D02*
X241831Y326688D01*
X242165Y326522D01*
X242540Y326480D01*
X242873Y326522D01*
X243206Y326730D01*
X243415Y326980D01*
X243456Y327230D01*
X243373Y327522D01*
X243081Y327730D01*
X242790Y327813D01*
X242415D01*
G01X242790D02*
X243040Y327938D01*
X243248Y328147D01*
X243331Y328397D01*
X243248Y328647D01*
X243040Y328855D01*
X242665Y328980D01*
X242290Y328938D01*
X241915Y328772D01*
G01X244890Y326772D02*
X245181Y326563D01*
X245515Y326480D01*
X245848Y326563D01*
X246140Y326813D01*
X246348Y327188D01*
X246431Y327563D01*
Y328022D01*
X246348Y328397D01*
X246140Y328730D01*
X245890Y328897D01*
X245598Y328980D01*
X245265Y328897D01*
X245015Y328730D01*
X244848Y328480D01*
X244765Y328147D01*
X244848Y327855D01*
X245056Y327563D01*
X245306Y327397D01*
X245598Y327355D01*
X245931Y327438D01*
X246181Y327647D01*
X246431Y328022D01*
G01X232365Y323080D02*
Y325580D01*
X233406D01*
X233740Y325455D01*
X233948Y325288D01*
X234031Y324955D01*
X233948Y324622D01*
X233698Y324413D01*
X233406Y324288D01*
X232365D01*
G01X233406D02*
X234031Y323080D01*
G01X236298D02*
Y325580D01*
X235798Y325080D01*
G01Y323080D02*
X236798D01*
G01X238481D02*
Y325580D01*
X239315D01*
X239648Y325455D01*
X239898Y325288D01*
X240106Y325038D01*
X240273Y324747D01*
X240315Y324330D01*
X240273Y323913D01*
X240106Y323622D01*
X239898Y323372D01*
X239648Y323205D01*
X239315Y323080D01*
X238481D01*
G01X242998D02*
Y325580D01*
X241456Y323788D01*
X243540D01*
G01X245598Y325580D02*
X245265Y325497D01*
X245015Y325288D01*
X244848Y325038D01*
X244723Y324705D01*
X244681Y324330D01*
X244723Y323955D01*
X244848Y323622D01*
X245015Y323372D01*
X245265Y323163D01*
X245598Y323080D01*
X245931Y323163D01*
X246181Y323372D01*
X246348Y323622D01*
X246473Y323955D01*
X246515Y324330D01*
X246473Y324705D01*
X246348Y325038D01*
X246181Y325288D01*
X245931Y325497D01*
X245598Y325580D01*
G01X232365Y329880D02*
Y332380D01*
X233406D01*
X233740Y332255D01*
X233948Y332088D01*
X234031Y331755D01*
X233948Y331422D01*
X233698Y331213D01*
X233406Y331088D01*
X232365D01*
G01X233406D02*
X234031Y329880D01*
G01X236298D02*
Y332380D01*
X235798Y331880D01*
G01Y329880D02*
X236798D01*
G01X238481D02*
Y332380D01*
X239315D01*
X239648Y332255D01*
X239898Y332088D01*
X240106Y331838D01*
X240273Y331547D01*
X240315Y331130D01*
X240273Y330713D01*
X240106Y330422D01*
X239898Y330172D01*
X239648Y330005D01*
X239315Y329880D01*
X238481D01*
G01X241581Y330380D02*
X241831Y330088D01*
X242165Y329922D01*
X242540Y329880D01*
X242873Y329922D01*
X243206Y330130D01*
X243415Y330380D01*
X243456Y330630D01*
X243373Y330922D01*
X243081Y331130D01*
X242790Y331213D01*
X242415D01*
G01X242790D02*
X243040Y331338D01*
X243248Y331547D01*
X243331Y331797D01*
X243248Y332047D01*
X243040Y332255D01*
X242665Y332380D01*
X242290Y332338D01*
X241915Y332172D01*
G01X245515Y329880D02*
X245598Y330422D01*
X245723Y330880D01*
X245890Y331297D01*
X246098Y331755D01*
X246431Y332380D01*
X244765D01*
G01X232365Y340580D02*
Y343080D01*
X233406D01*
X233740Y342955D01*
X233948Y342788D01*
X234031Y342455D01*
X233948Y342122D01*
X233698Y341913D01*
X233406Y341788D01*
X232365D01*
G01X233406D02*
X234031Y340580D01*
G01X236298D02*
Y343080D01*
X235798Y342580D01*
G01Y340580D02*
X236798D01*
G01X238481D02*
Y343080D01*
X239315D01*
X239648Y342955D01*
X239898Y342788D01*
X240106Y342538D01*
X240273Y342247D01*
X240315Y341830D01*
X240273Y341413D01*
X240106Y341122D01*
X239898Y340872D01*
X239648Y340705D01*
X239315Y340580D01*
X238481D01*
G01X241581Y341080D02*
X241831Y340788D01*
X242165Y340622D01*
X242540Y340580D01*
X242873Y340622D01*
X243206Y340830D01*
X243415Y341080D01*
X243456Y341330D01*
X243373Y341622D01*
X243081Y341830D01*
X242790Y341913D01*
X242415D01*
G01X242790D02*
X243040Y342038D01*
X243248Y342247D01*
X243331Y342497D01*
X243248Y342747D01*
X243040Y342955D01*
X242665Y343080D01*
X242290Y343038D01*
X241915Y342872D01*
G01X245598Y343080D02*
X245265Y342997D01*
X245015Y342788D01*
X244848Y342538D01*
X244723Y342205D01*
X244681Y341830D01*
X244723Y341455D01*
X244848Y341122D01*
X245015Y340872D01*
X245265Y340663D01*
X245598Y340580D01*
X245931Y340663D01*
X246181Y340872D01*
X246348Y341122D01*
X246473Y341455D01*
X246515Y341830D01*
X246473Y342205D01*
X246348Y342538D01*
X246181Y342788D01*
X245931Y342997D01*
X245598Y343080D01*
G01X240322Y284848D02*
X240197Y284598D01*
X240114Y284306D01*
Y283973D01*
X240239Y283598D01*
X240447Y283306D01*
X240697Y283098D01*
X241114Y282931D01*
X241489Y282889D01*
X241864Y282973D01*
X242114Y283098D01*
X242364Y283348D01*
X242531Y283639D01*
X242614Y283931D01*
Y284223D01*
X242531Y284514D01*
X242406Y284764D01*
X242239Y284973D01*
G01X242614Y287031D02*
X240114D01*
X240614Y286531D01*
G01X242614D02*
Y287531D01*
G01Y289214D02*
X240114D01*
Y290048D01*
X240239Y290381D01*
X240406Y290631D01*
X240656Y290839D01*
X240947Y291006D01*
X241364Y291048D01*
X241781Y291006D01*
X242072Y290839D01*
X242322Y290631D01*
X242489Y290381D01*
X242614Y290048D01*
Y289214D01*
G01X242114Y292314D02*
X242406Y292564D01*
X242572Y292898D01*
X242614Y293273D01*
X242572Y293606D01*
X242364Y293939D01*
X242114Y294148D01*
X241864Y294189D01*
X241572Y294106D01*
X241364Y293814D01*
X241281Y293523D01*
Y293148D01*
G01Y293523D02*
X241156Y293773D01*
X240947Y293981D01*
X240697Y294064D01*
X240447Y293981D01*
X240239Y293773D01*
X240114Y293398D01*
X240156Y293023D01*
X240322Y292648D01*
G01X242114Y295414D02*
X242406Y295664D01*
X242572Y295998D01*
X242614Y296373D01*
X242572Y296706D01*
X242364Y297039D01*
X242114Y297248D01*
X241864Y297289D01*
X241572Y297206D01*
X241364Y296914D01*
X241281Y296623D01*
Y296248D01*
G01Y296623D02*
X241156Y296873D01*
X240947Y297081D01*
X240697Y297164D01*
X240447Y297081D01*
X240239Y296873D01*
X240114Y296498D01*
X240156Y296123D01*
X240322Y295748D01*
G01X236922Y284848D02*
X236797Y284598D01*
X236714Y284306D01*
Y283973D01*
X236839Y283598D01*
X237047Y283306D01*
X237297Y283098D01*
X237714Y282931D01*
X238089Y282889D01*
X238464Y282973D01*
X238714Y283098D01*
X238964Y283348D01*
X239131Y283639D01*
X239214Y283931D01*
Y284223D01*
X239131Y284514D01*
X239006Y284764D01*
X238839Y284973D01*
G01X239214Y287031D02*
X236714D01*
X237214Y286531D01*
G01X239214D02*
Y287531D01*
G01Y289214D02*
X236714D01*
Y290048D01*
X236839Y290381D01*
X237006Y290631D01*
X237256Y290839D01*
X237547Y291006D01*
X237964Y291048D01*
X238381Y291006D01*
X238672Y290839D01*
X238922Y290631D01*
X239089Y290381D01*
X239214Y290048D01*
Y289214D01*
G01X238714Y292314D02*
X239006Y292564D01*
X239172Y292898D01*
X239214Y293273D01*
X239172Y293606D01*
X238964Y293939D01*
X238714Y294148D01*
X238464Y294189D01*
X238172Y294106D01*
X237964Y293814D01*
X237881Y293523D01*
Y293148D01*
G01Y293523D02*
X237756Y293773D01*
X237547Y293981D01*
X237297Y294064D01*
X237047Y293981D01*
X236839Y293773D01*
X236714Y293398D01*
X236756Y293023D01*
X236922Y292648D01*
G01X237131Y295539D02*
X236881Y295789D01*
X236756Y296081D01*
X236714Y296414D01*
X236797Y296831D01*
X237006Y297123D01*
X237256Y297206D01*
X237506Y297164D01*
X237714Y296998D01*
X238131Y296164D01*
X238422Y295789D01*
X238839Y295539D01*
X239214Y295456D01*
Y297206D01*
G01X236368Y304166D02*
X236118Y304291D01*
X235826Y304374D01*
X235493D01*
X235118Y304249D01*
X234826Y304041D01*
X234618Y303791D01*
X234451Y303374D01*
X234409Y302999D01*
X234493Y302624D01*
X234618Y302374D01*
X234868Y302124D01*
X235159Y301957D01*
X235451Y301874D01*
X235743D01*
X236034Y301957D01*
X236284Y302082D01*
X236493Y302249D01*
G01X238551Y301874D02*
Y304374D01*
X238051Y303874D01*
G01Y301874D02*
X239051D01*
G01X242568Y304166D02*
X242318Y304291D01*
X242026Y304374D01*
X241693D01*
X241318Y304249D01*
X241026Y304041D01*
X240818Y303791D01*
X240651Y303374D01*
X240609Y302999D01*
X240693Y302624D01*
X240818Y302374D01*
X241068Y302124D01*
X241359Y301957D01*
X241651Y301874D01*
X241943D01*
X242234Y301957D01*
X242484Y302082D01*
X242693Y302249D01*
G01X243959Y303957D02*
X244209Y304207D01*
X244501Y304332D01*
X244834Y304374D01*
X245251Y304291D01*
X245543Y304082D01*
X245626Y303832D01*
X245584Y303582D01*
X245418Y303374D01*
X244584Y302957D01*
X244209Y302666D01*
X243959Y302249D01*
X243876Y301874D01*
X245626D01*
G01X246934Y302249D02*
X247184Y302041D01*
X247476Y301916D01*
X247851Y301874D01*
X248226Y301957D01*
X248518Y302124D01*
X248726Y302416D01*
X248768Y302749D01*
X248684Y303082D01*
X248476Y303291D01*
X248184Y303457D01*
X247893Y303499D01*
X247601Y303457D01*
X247226Y303291D01*
X247351Y304374D01*
X248476D01*
G01X233522Y284848D02*
X233397Y284598D01*
X233314Y284306D01*
Y283973D01*
X233439Y283598D01*
X233647Y283306D01*
X233897Y283098D01*
X234314Y282931D01*
X234689Y282889D01*
X235064Y282973D01*
X235314Y283098D01*
X235564Y283348D01*
X235731Y283639D01*
X235814Y283931D01*
Y284223D01*
X235731Y284514D01*
X235606Y284764D01*
X235439Y284973D01*
G01X233314Y287031D02*
X235814D01*
G01X233314Y286073D02*
Y287989D01*
G01X235814Y290131D02*
X233314D01*
X233814Y289631D01*
G01X235814D02*
Y290631D01*
G01X235314Y292314D02*
X235606Y292564D01*
X235772Y292898D01*
X235814Y293273D01*
X235772Y293606D01*
X235564Y293939D01*
X235314Y294148D01*
X235064Y294189D01*
X234772Y294106D01*
X234564Y293814D01*
X234481Y293523D01*
Y293148D01*
G01Y293523D02*
X234356Y293773D01*
X234147Y293981D01*
X233897Y294064D01*
X233647Y293981D01*
X233439Y293773D01*
X233314Y293398D01*
X233356Y293023D01*
X233522Y292648D01*
G01X236659Y307541D02*
X236534Y307291D01*
X236451Y306999D01*
Y306666D01*
X236576Y306291D01*
X236784Y305999D01*
X237034Y305791D01*
X237451Y305624D01*
X237826Y305582D01*
X238201Y305666D01*
X238451Y305791D01*
X238701Y306041D01*
X238868Y306332D01*
X238951Y306624D01*
Y306916D01*
X238868Y307207D01*
X238743Y307457D01*
X238576Y307666D01*
G01X238951Y309724D02*
X236451D01*
X236951Y309224D01*
G01X238951D02*
Y310224D01*
G01X236659Y313741D02*
X236534Y313491D01*
X236451Y313199D01*
Y312866D01*
X236576Y312491D01*
X236784Y312199D01*
X237034Y311991D01*
X237451Y311824D01*
X237826Y311782D01*
X238201Y311866D01*
X238451Y311991D01*
X238701Y312241D01*
X238868Y312532D01*
X238951Y312824D01*
Y313116D01*
X238868Y313407D01*
X238743Y313657D01*
X238576Y313866D01*
G01Y315007D02*
X238784Y315257D01*
X238909Y315549D01*
X238951Y315924D01*
X238868Y316299D01*
X238701Y316591D01*
X238409Y316799D01*
X238076Y316841D01*
X237743Y316757D01*
X237534Y316549D01*
X237368Y316257D01*
X237326Y315966D01*
X237368Y315674D01*
X237534Y315299D01*
X236451Y315424D01*
Y316549D01*
G01X240059Y307541D02*
X239934Y307291D01*
X239851Y306999D01*
Y306666D01*
X239976Y306291D01*
X240184Y305999D01*
X240434Y305791D01*
X240851Y305624D01*
X241226Y305582D01*
X241601Y305666D01*
X241851Y305791D01*
X242101Y306041D01*
X242268Y306332D01*
X242351Y306624D01*
Y306916D01*
X242268Y307207D01*
X242143Y307457D01*
X241976Y307666D01*
G01X242351Y309724D02*
X239851D01*
X240351Y309224D01*
G01X242351D02*
Y310224D01*
G01X240059Y313741D02*
X239934Y313491D01*
X239851Y313199D01*
Y312866D01*
X239976Y312491D01*
X240184Y312199D01*
X240434Y311991D01*
X240851Y311824D01*
X241226Y311782D01*
X241601Y311866D01*
X241851Y311991D01*
X242101Y312241D01*
X242268Y312532D01*
X242351Y312824D01*
Y313116D01*
X242268Y313407D01*
X242143Y313657D01*
X241976Y313866D01*
G01X242351Y316424D02*
X239851D01*
X241643Y314882D01*
Y316966D01*
G01X233259Y307541D02*
X233134Y307291D01*
X233051Y306999D01*
Y306666D01*
X233176Y306291D01*
X233384Y305999D01*
X233634Y305791D01*
X234051Y305624D01*
X234426Y305582D01*
X234801Y305666D01*
X235051Y305791D01*
X235301Y306041D01*
X235468Y306332D01*
X235551Y306624D01*
Y306916D01*
X235468Y307207D01*
X235343Y307457D01*
X235176Y307666D01*
G01X233051Y309724D02*
X235551D01*
G01X233051Y308766D02*
Y310682D01*
G01X235176Y311907D02*
X235384Y312157D01*
X235509Y312449D01*
X235551Y312824D01*
X235468Y313199D01*
X235301Y313491D01*
X235009Y313699D01*
X234676Y313741D01*
X234343Y313657D01*
X234134Y313449D01*
X233968Y313157D01*
X233926Y312866D01*
X233968Y312574D01*
X234134Y312199D01*
X233051Y312324D01*
Y313449D01*
G01X235551Y315841D02*
X235009Y315924D01*
X234551Y316049D01*
X234134Y316216D01*
X233676Y316424D01*
X233051Y316757D01*
Y315091D01*
G01X247331Y284848D02*
X247206Y284598D01*
X247123Y284306D01*
Y283973D01*
X247248Y283598D01*
X247456Y283306D01*
X247706Y283098D01*
X248123Y282931D01*
X248498Y282889D01*
X248873Y282973D01*
X249123Y283098D01*
X249373Y283348D01*
X249540Y283639D01*
X249623Y283931D01*
Y284223D01*
X249540Y284514D01*
X249415Y284764D01*
X249248Y284973D01*
G01X247123Y287031D02*
X249623D01*
G01X247123Y286073D02*
Y287989D01*
G01X249623Y290131D02*
X247123D01*
X247623Y289631D01*
G01X249623D02*
Y290631D01*
G01Y293731D02*
X247123D01*
X248915Y292189D01*
Y294273D01*
G01X246969Y307541D02*
X246844Y307291D01*
X246761Y306999D01*
Y306666D01*
X246886Y306291D01*
X247094Y305999D01*
X247344Y305791D01*
X247761Y305624D01*
X248136Y305582D01*
X248511Y305666D01*
X248761Y305791D01*
X249011Y306041D01*
X249178Y306332D01*
X249261Y306624D01*
Y306916D01*
X249178Y307207D01*
X249053Y307457D01*
X248886Y307666D01*
G01X246761Y309724D02*
X249261D01*
G01X246761Y308766D02*
Y310682D01*
G01X248886Y311907D02*
X249094Y312157D01*
X249219Y312449D01*
X249261Y312824D01*
X249178Y313199D01*
X249011Y313491D01*
X248719Y313699D01*
X248386Y313741D01*
X248053Y313657D01*
X247844Y313449D01*
X247678Y313157D01*
X247636Y312866D01*
X247678Y312574D01*
X247844Y312199D01*
X246761Y312324D01*
Y313449D01*
G01X248219Y315132D02*
X247928Y315424D01*
X247761Y315674D01*
X247678Y316007D01*
X247761Y316299D01*
X247928Y316507D01*
X248178Y316674D01*
X248469Y316716D01*
X248719Y316674D01*
X248969Y316507D01*
X249178Y316257D01*
X249261Y315966D01*
X249178Y315632D01*
X248928Y315341D01*
X248553Y315174D01*
X248136Y315132D01*
X247594Y315216D01*
X247303Y315341D01*
X247011Y315549D01*
X246803Y315841D01*
X246761Y316132D01*
X246844Y316424D01*
X247053Y316632D01*
G01X234058Y321859D02*
X233808Y321984D01*
X233516Y322067D01*
X233183D01*
X232808Y321942D01*
X232516Y321734D01*
X232308Y321484D01*
X232141Y321067D01*
X232099Y320692D01*
X232183Y320317D01*
X232308Y320067D01*
X232558Y319817D01*
X232849Y319650D01*
X233141Y319567D01*
X233433D01*
X233724Y319650D01*
X233974Y319775D01*
X234183Y319942D01*
G01X236241Y319567D02*
Y322067D01*
X235741Y321567D01*
G01Y319567D02*
X236741D01*
G01X238424D02*
Y322067D01*
X239258D01*
X239591Y321942D01*
X239841Y321775D01*
X240049Y321525D01*
X240216Y321234D01*
X240258Y320817D01*
X240216Y320400D01*
X240049Y320109D01*
X239841Y319859D01*
X239591Y319692D01*
X239258Y319567D01*
X238424D01*
G01X241649Y321650D02*
X241899Y321900D01*
X242191Y322025D01*
X242524Y322067D01*
X242941Y321984D01*
X243233Y321775D01*
X243316Y321525D01*
X243274Y321275D01*
X243108Y321067D01*
X242274Y320650D01*
X241899Y320359D01*
X241649Y319942D01*
X241566Y319567D01*
X243316D01*
G01X245541D02*
Y322067D01*
X245041Y321567D01*
G01Y319567D02*
X246041D01*
G01X250284Y334994D02*
X250242Y334661D01*
X250076Y334369D01*
X249826Y334119D01*
X249534Y333952D01*
X249201Y333869D01*
X248867D01*
X248534Y333952D01*
X248242Y334119D01*
X247992Y334369D01*
X247826Y334661D01*
X247784Y334994D01*
X247826Y335327D01*
X247992Y335619D01*
X248242Y335869D01*
X248534Y336036D01*
X248867Y336119D01*
X249201D01*
X249534Y336036D01*
X249826Y335869D01*
X250076Y335619D01*
X250242Y335327D01*
X250284Y334994D01*
G01X249617Y335327D02*
X250284Y335827D01*
G01Y338094D02*
X247784D01*
X248284Y337594D01*
G01X250284D02*
Y338594D01*
G01Y340277D02*
X247784D01*
Y341111D01*
X247909Y341444D01*
X248076Y341694D01*
X248326Y341902D01*
X248617Y342069D01*
X249034Y342111D01*
X249451Y342069D01*
X249742Y341902D01*
X249992Y341694D01*
X250159Y341444D01*
X250284Y341111D01*
Y340277D01*
G01X248201Y343502D02*
X247951Y343752D01*
X247826Y344044D01*
X247784Y344377D01*
X247867Y344794D01*
X248076Y345086D01*
X248326Y345169D01*
X248576Y345127D01*
X248784Y344961D01*
X249201Y344127D01*
X249492Y343752D01*
X249909Y343502D01*
X250284Y343419D01*
Y345169D01*
G01X245751Y305791D02*
X243251D01*
Y306832D01*
X243376Y307166D01*
X243543Y307374D01*
X243876Y307457D01*
X244209Y307374D01*
X244418Y307124D01*
X244543Y306832D01*
Y305791D01*
G01Y306832D02*
X245751Y307457D01*
G01X243251Y309724D02*
X245751D01*
G01X243251Y308766D02*
Y310682D01*
G01X245251Y311907D02*
X245543Y312157D01*
X245709Y312491D01*
X245751Y312866D01*
X245709Y313199D01*
X245501Y313532D01*
X245251Y313741D01*
X245001Y313782D01*
X244709Y313699D01*
X244501Y313407D01*
X244418Y313116D01*
Y312741D01*
G01Y313116D02*
X244293Y313366D01*
X244084Y313574D01*
X243834Y313657D01*
X243584Y313574D01*
X243376Y313366D01*
X243251Y312991D01*
X243293Y312616D01*
X243459Y312241D01*
G01X245751Y315924D02*
X245709Y316216D01*
X245584Y316549D01*
X245376Y316757D01*
X245084Y316841D01*
X244793Y316757D01*
X244543Y316507D01*
X244418Y316132D01*
Y315716D01*
X244334Y315466D01*
X244126Y315257D01*
X243834Y315174D01*
X243543Y315299D01*
X243334Y315591D01*
X243251Y315924D01*
X243334Y316257D01*
X243543Y316549D01*
X243834Y316674D01*
X244126Y316591D01*
X244334Y316382D01*
X244418Y316132D01*
Y315716D01*
X244543Y315341D01*
X244793Y315091D01*
X245084Y315007D01*
X245376Y315091D01*
X245584Y315299D01*
X245709Y315632D01*
X245751Y315924D01*
G01X246014Y283098D02*
X243514D01*
Y284139D01*
X243639Y284473D01*
X243806Y284681D01*
X244139Y284764D01*
X244472Y284681D01*
X244681Y284431D01*
X244806Y284139D01*
Y283098D01*
G01Y284139D02*
X246014Y284764D01*
G01X243514Y287031D02*
X246014D01*
G01X243514Y286073D02*
Y287989D01*
G01X246014Y290131D02*
X243514D01*
X244014Y289631D01*
G01X246014D02*
Y290631D01*
G01X243514Y293231D02*
X243597Y292898D01*
X243806Y292648D01*
X244056Y292481D01*
X244389Y292356D01*
X244764Y292314D01*
X245139Y292356D01*
X245472Y292481D01*
X245722Y292648D01*
X245931Y292898D01*
X246014Y293231D01*
X245931Y293564D01*
X245722Y293814D01*
X245472Y293981D01*
X245139Y294106D01*
X244764Y294148D01*
X244389Y294106D01*
X244056Y293981D01*
X243806Y293814D01*
X243597Y293564D01*
X243514Y293231D01*
G01X236284Y298474D02*
X234618D01*
Y300974D01*
X236284D01*
G01X235618Y299766D02*
X234618D01*
G01X237634Y300974D02*
Y299182D01*
X237801Y298807D01*
X238134Y298557D01*
X238551Y298474D01*
X238968Y298557D01*
X239301Y298807D01*
X239468Y299182D01*
Y300974D01*
G01X241651Y298474D02*
Y300974D01*
X241151Y300474D01*
G01Y298474D02*
X242151D01*
G01X245668Y300766D02*
X245418Y300891D01*
X245126Y300974D01*
X244793D01*
X244418Y300849D01*
X244126Y300641D01*
X243918Y300391D01*
X243751Y299974D01*
X243709Y299599D01*
X243793Y299224D01*
X243918Y298974D01*
X244168Y298724D01*
X244459Y298557D01*
X244751Y298474D01*
X245043D01*
X245334Y298557D01*
X245584Y298682D01*
X245793Y298849D01*
G01X246934Y298974D02*
X247184Y298682D01*
X247518Y298516D01*
X247893Y298474D01*
X248226Y298516D01*
X248559Y298724D01*
X248768Y298974D01*
X248809Y299224D01*
X248726Y299516D01*
X248434Y299724D01*
X248143Y299807D01*
X247768D01*
G01X248143D02*
X248393Y299932D01*
X248601Y300141D01*
X248684Y300391D01*
X248601Y300641D01*
X248393Y300849D01*
X248018Y300974D01*
X247643Y300932D01*
X247268Y300766D01*
G01X249834Y352355D02*
X247334D01*
Y353396D01*
X247459Y353730D01*
X247626Y353938D01*
X247959Y354021D01*
X248292Y353938D01*
X248501Y353688D01*
X248626Y353396D01*
Y352355D01*
G01Y353396D02*
X249834Y354021D01*
G01Y356288D02*
X247334D01*
X247834Y355788D01*
G01X249834D02*
Y356788D01*
G01Y358471D02*
X247334D01*
Y359305D01*
X247459Y359638D01*
X247626Y359888D01*
X247876Y360096D01*
X248167Y360263D01*
X248584Y360305D01*
X249001Y360263D01*
X249292Y360096D01*
X249542Y359888D01*
X249709Y359638D01*
X249834Y359305D01*
Y358471D01*
G01X247751Y361696D02*
X247501Y361946D01*
X247376Y362238D01*
X247334Y362571D01*
X247417Y362988D01*
X247626Y363280D01*
X247876Y363363D01*
X248126Y363321D01*
X248334Y363155D01*
X248751Y362321D01*
X249042Y361946D01*
X249459Y361696D01*
X249834Y361613D01*
Y363363D01*
G01X247751Y364796D02*
X247501Y365046D01*
X247376Y365338D01*
X247334Y365671D01*
X247417Y366088D01*
X247626Y366380D01*
X247876Y366463D01*
X248126Y366421D01*
X248334Y366255D01*
X248751Y365421D01*
X249042Y365046D01*
X249459Y364796D01*
X249834Y364713D01*
Y366463D01*
G01X246334Y352355D02*
X243834D01*
Y353396D01*
X243959Y353730D01*
X244126Y353938D01*
X244459Y354021D01*
X244792Y353938D01*
X245001Y353688D01*
X245126Y353396D01*
Y352355D01*
G01Y353396D02*
X246334Y354021D01*
G01Y356288D02*
X243834D01*
X244334Y355788D01*
G01X246334D02*
Y356788D01*
G01Y358471D02*
X243834D01*
Y359305D01*
X243959Y359638D01*
X244126Y359888D01*
X244376Y360096D01*
X244667Y360263D01*
X245084Y360305D01*
X245501Y360263D01*
X245792Y360096D01*
X246042Y359888D01*
X246209Y359638D01*
X246334Y359305D01*
Y358471D01*
G01X244251Y361696D02*
X244001Y361946D01*
X243876Y362238D01*
X243834Y362571D01*
X243917Y362988D01*
X244126Y363280D01*
X244376Y363363D01*
X244626Y363321D01*
X244834Y363155D01*
X245251Y362321D01*
X245542Y361946D01*
X245959Y361696D01*
X246334Y361613D01*
Y363363D01*
G01Y365588D02*
X243834D01*
X244334Y365088D01*
G01X246334D02*
Y366088D01*
G01X233236Y394035D02*
Y396535D01*
X234277D01*
X234611Y396410D01*
X234819Y396243D01*
X234902Y395910D01*
X234819Y395577D01*
X234569Y395368D01*
X234277Y395243D01*
X233236D01*
G01X234277D02*
X234902Y394035D01*
G01X237169D02*
Y396535D01*
X236669Y396035D01*
G01Y394035D02*
X237669D01*
G01X239352D02*
Y396535D01*
X240186D01*
X240519Y396410D01*
X240769Y396243D01*
X240977Y395993D01*
X241144Y395702D01*
X241186Y395285D01*
X241144Y394868D01*
X240977Y394577D01*
X240769Y394327D01*
X240519Y394160D01*
X240186Y394035D01*
X239352D01*
G01X243869D02*
Y396535D01*
X242327Y394743D01*
X244411D01*
G01X245414Y373527D02*
X242914D01*
Y374568D01*
X243039Y374902D01*
X243206Y375110D01*
X243539Y375193D01*
X243872Y375110D01*
X244081Y374860D01*
X244206Y374568D01*
Y373527D01*
G01Y374568D02*
X245414Y375193D01*
G01Y377460D02*
X242914D01*
X243414Y376960D01*
G01X245414D02*
Y377960D01*
G01Y379643D02*
X242914D01*
Y380477D01*
X243039Y380810D01*
X243206Y381060D01*
X243456Y381268D01*
X243747Y381435D01*
X244164Y381477D01*
X244581Y381435D01*
X244872Y381268D01*
X245122Y381060D01*
X245289Y380810D01*
X245414Y380477D01*
Y379643D01*
G01Y383660D02*
X242914D01*
X243414Y383160D01*
G01X245414D02*
Y384160D01*
G01X243331Y385968D02*
X243081Y386218D01*
X242956Y386510D01*
X242914Y386843D01*
X242997Y387260D01*
X243206Y387552D01*
X243456Y387635D01*
X243706Y387593D01*
X243914Y387427D01*
X244331Y386593D01*
X244622Y386218D01*
X245039Y385968D01*
X245414Y385885D01*
Y387635D01*
G01X241510Y373589D02*
X239010D01*
Y374630D01*
X239135Y374964D01*
X239302Y375172D01*
X239635Y375255D01*
X239968Y375172D01*
X240177Y374922D01*
X240302Y374630D01*
Y373589D01*
G01Y374630D02*
X241510Y375255D01*
G01Y377522D02*
X239010D01*
X239510Y377022D01*
G01X241510D02*
Y378022D01*
G01Y379705D02*
X239010D01*
Y380539D01*
X239135Y380872D01*
X239302Y381122D01*
X239552Y381330D01*
X239843Y381497D01*
X240260Y381539D01*
X240677Y381497D01*
X240968Y381330D01*
X241218Y381122D01*
X241385Y380872D01*
X241510Y380539D01*
Y379705D01*
G01Y383722D02*
X239010D01*
X239510Y383222D01*
G01X241510D02*
Y384222D01*
G01Y387322D02*
X239010D01*
X240802Y385780D01*
Y387864D01*
G01X239535Y402613D02*
X237035D01*
Y403654D01*
X237160Y403988D01*
X237327Y404196D01*
X237660Y404279D01*
X237993Y404196D01*
X238202Y403946D01*
X238327Y403654D01*
Y402613D01*
G01Y403654D02*
X239535Y404279D01*
G01Y405754D02*
X237035D01*
Y407338D01*
G01X238243Y406754D02*
Y405754D01*
G01X239535Y409563D02*
X238993Y409646D01*
X238535Y409771D01*
X238118Y409938D01*
X237660Y410146D01*
X237035Y410479D01*
Y408813D01*
G01X238734Y352355D02*
X236234D01*
Y353396D01*
X236359Y353730D01*
X236526Y353938D01*
X236859Y354021D01*
X237192Y353938D01*
X237401Y353688D01*
X237526Y353396D01*
Y352355D01*
G01Y353396D02*
X238734Y354021D01*
G01Y356288D02*
X236234D01*
X236734Y355788D01*
G01X238734D02*
Y356788D01*
G01Y358471D02*
X236234D01*
Y359305D01*
X236359Y359638D01*
X236526Y359888D01*
X236776Y360096D01*
X237067Y360263D01*
X237484Y360305D01*
X237901Y360263D01*
X238192Y360096D01*
X238442Y359888D01*
X238609Y359638D01*
X238734Y359305D01*
Y358471D01*
G01Y362488D02*
X236234D01*
X236734Y361988D01*
G01X238734D02*
Y362988D01*
G01X238442Y364880D02*
X238651Y365171D01*
X238734Y365505D01*
X238651Y365838D01*
X238401Y366130D01*
X238026Y366338D01*
X237651Y366421D01*
X237192D01*
X236817Y366338D01*
X236484Y366130D01*
X236317Y365880D01*
X236234Y365588D01*
X236317Y365255D01*
X236484Y365005D01*
X236734Y364838D01*
X237067Y364755D01*
X237359Y364838D01*
X237651Y365046D01*
X237817Y365296D01*
X237859Y365588D01*
X237776Y365921D01*
X237567Y366171D01*
X237192Y366421D01*
G01X242134Y352355D02*
X239634D01*
Y353396D01*
X239759Y353730D01*
X239926Y353938D01*
X240259Y354021D01*
X240592Y353938D01*
X240801Y353688D01*
X240926Y353396D01*
Y352355D01*
G01Y353396D02*
X242134Y354021D01*
G01Y356288D02*
X239634D01*
X240134Y355788D01*
G01X242134D02*
Y356788D01*
G01Y358471D02*
X239634D01*
Y359305D01*
X239759Y359638D01*
X239926Y359888D01*
X240176Y360096D01*
X240467Y360263D01*
X240884Y360305D01*
X241301Y360263D01*
X241592Y360096D01*
X241842Y359888D01*
X242009Y359638D01*
X242134Y359305D01*
Y358471D01*
G01X240051Y361696D02*
X239801Y361946D01*
X239676Y362238D01*
X239634Y362571D01*
X239717Y362988D01*
X239926Y363280D01*
X240176Y363363D01*
X240426Y363321D01*
X240634Y363155D01*
X241051Y362321D01*
X241342Y361946D01*
X241759Y361696D01*
X242134Y361613D01*
Y363363D01*
G01X239634Y365588D02*
X239717Y365255D01*
X239926Y365005D01*
X240176Y364838D01*
X240509Y364713D01*
X240884Y364671D01*
X241259Y364713D01*
X241592Y364838D01*
X241842Y365005D01*
X242051Y365255D01*
X242134Y365588D01*
X242051Y365921D01*
X241842Y366171D01*
X241592Y366338D01*
X241259Y366463D01*
X240884Y366505D01*
X240509Y366463D01*
X240176Y366338D01*
X239926Y366171D01*
X239717Y365921D01*
X239634Y365588D01*
G01X232465Y347380D02*
Y349880D01*
X233506D01*
X233840Y349755D01*
X234048Y349588D01*
X234131Y349255D01*
X234048Y348922D01*
X233798Y348713D01*
X233506Y348588D01*
X232465D01*
G01X233506D02*
X234131Y347380D01*
G01X236398D02*
Y349880D01*
X235898Y349380D01*
G01Y347380D02*
X236898D01*
G01X238581D02*
Y349880D01*
X239415D01*
X239748Y349755D01*
X239998Y349588D01*
X240206Y349338D01*
X240373Y349047D01*
X240415Y348630D01*
X240373Y348213D01*
X240206Y347922D01*
X239998Y347672D01*
X239748Y347505D01*
X239415Y347380D01*
X238581D01*
G01X241806Y349463D02*
X242056Y349713D01*
X242348Y349838D01*
X242681Y349880D01*
X243098Y349797D01*
X243390Y349588D01*
X243473Y349338D01*
X243431Y349088D01*
X243265Y348880D01*
X242431Y348463D01*
X242056Y348172D01*
X241806Y347755D01*
X241723Y347380D01*
X243473D01*
G01X245615D02*
X245698Y347922D01*
X245823Y348380D01*
X245990Y348797D01*
X246198Y349255D01*
X246531Y349880D01*
X244865D01*
G01X232465Y343980D02*
Y346480D01*
X233506D01*
X233840Y346355D01*
X234048Y346188D01*
X234131Y345855D01*
X234048Y345522D01*
X233798Y345313D01*
X233506Y345188D01*
X232465D01*
G01X233506D02*
X234131Y343980D01*
G01X236398D02*
Y346480D01*
X235898Y345980D01*
G01Y343980D02*
X236898D01*
G01X238581D02*
Y346480D01*
X239415D01*
X239748Y346355D01*
X239998Y346188D01*
X240206Y345938D01*
X240373Y345647D01*
X240415Y345230D01*
X240373Y344813D01*
X240206Y344522D01*
X239998Y344272D01*
X239748Y344105D01*
X239415Y343980D01*
X238581D01*
G01X241806Y346063D02*
X242056Y346313D01*
X242348Y346438D01*
X242681Y346480D01*
X243098Y346397D01*
X243390Y346188D01*
X243473Y345938D01*
X243431Y345688D01*
X243265Y345480D01*
X242431Y345063D01*
X242056Y344772D01*
X241806Y344355D01*
X241723Y343980D01*
X243473D01*
G01X244990Y344272D02*
X245281Y344063D01*
X245615Y343980D01*
X245948Y344063D01*
X246240Y344313D01*
X246448Y344688D01*
X246531Y345063D01*
Y345522D01*
X246448Y345897D01*
X246240Y346230D01*
X245990Y346397D01*
X245698Y346480D01*
X245365Y346397D01*
X245115Y346230D01*
X244948Y345980D01*
X244865Y345647D01*
X244948Y345355D01*
X245156Y345063D01*
X245406Y344897D01*
X245698Y344855D01*
X246031Y344938D01*
X246281Y345147D01*
X246531Y345522D01*
G01X233236Y390535D02*
Y393035D01*
X234277D01*
X234611Y392910D01*
X234819Y392743D01*
X234902Y392410D01*
X234819Y392077D01*
X234569Y391868D01*
X234277Y391743D01*
X233236D01*
G01X234277D02*
X234902Y390535D01*
G01X237169D02*
Y393035D01*
X236669Y392535D01*
G01Y390535D02*
X237669D01*
G01X239352D02*
Y393035D01*
X240186D01*
X240519Y392910D01*
X240769Y392743D01*
X240977Y392493D01*
X241144Y392202D01*
X241186Y391785D01*
X241144Y391368D01*
X240977Y391077D01*
X240769Y390827D01*
X240519Y390660D01*
X240186Y390535D01*
X239352D01*
G01X243369D02*
Y393035D01*
X242869Y392535D01*
G01Y390535D02*
X243869D01*
G01X246469Y393035D02*
X246136Y392952D01*
X245886Y392743D01*
X245719Y392493D01*
X245594Y392160D01*
X245552Y391785D01*
X245594Y391410D01*
X245719Y391077D01*
X245886Y390827D01*
X246136Y390618D01*
X246469Y390535D01*
X246802Y390618D01*
X247052Y390827D01*
X247219Y391077D01*
X247344Y391410D01*
X247386Y391785D01*
X247344Y392160D01*
X247219Y392493D01*
X247052Y392743D01*
X246802Y392952D01*
X246469Y393035D01*
G01X246489Y373737D02*
X248281D01*
X248656Y373904D01*
X248906Y374237D01*
X248989Y374654D01*
X248906Y375071D01*
X248656Y375404D01*
X248281Y375571D01*
X246489D01*
G01X248989Y377754D02*
X246489D01*
X246989Y377254D01*
G01X248989D02*
Y378254D01*
G01Y379937D02*
X246489D01*
Y380771D01*
X246614Y381104D01*
X246781Y381354D01*
X247031Y381562D01*
X247322Y381729D01*
X247739Y381771D01*
X248156Y381729D01*
X248447Y381562D01*
X248697Y381354D01*
X248864Y381104D01*
X248989Y380771D01*
Y379937D01*
G01Y383954D02*
X246489D01*
X246989Y383454D01*
G01X248989D02*
Y384454D01*
G01X232942Y354105D02*
X232817Y353855D01*
X232734Y353563D01*
Y353230D01*
X232859Y352855D01*
X233067Y352563D01*
X233317Y352355D01*
X233734Y352188D01*
X234109Y352146D01*
X234484Y352230D01*
X234734Y352355D01*
X234984Y352605D01*
X235151Y352896D01*
X235234Y353188D01*
Y353480D01*
X235151Y353771D01*
X235026Y354021D01*
X234859Y354230D01*
G01X235234Y356288D02*
X232734D01*
X233234Y355788D01*
G01X235234D02*
Y356788D01*
G01Y358471D02*
X232734D01*
Y359305D01*
X232859Y359638D01*
X233026Y359888D01*
X233276Y360096D01*
X233567Y360263D01*
X233984Y360305D01*
X234401Y360263D01*
X234692Y360096D01*
X234942Y359888D01*
X235109Y359638D01*
X235234Y359305D01*
Y358471D01*
G01X234942Y361780D02*
X235151Y362071D01*
X235234Y362405D01*
X235151Y362738D01*
X234901Y363030D01*
X234526Y363238D01*
X234151Y363321D01*
X233692D01*
X233317Y363238D01*
X232984Y363030D01*
X232817Y362780D01*
X232734Y362488D01*
X232817Y362155D01*
X232984Y361905D01*
X233234Y361738D01*
X233567Y361655D01*
X233859Y361738D01*
X234151Y361946D01*
X234317Y362196D01*
X234359Y362488D01*
X234276Y362821D01*
X234067Y363071D01*
X233692Y363321D01*
G01X234986Y399827D02*
X234736Y399952D01*
X234444Y400035D01*
X234111D01*
X233736Y399910D01*
X233444Y399702D01*
X233236Y399452D01*
X233069Y399035D01*
X233027Y398660D01*
X233111Y398285D01*
X233236Y398035D01*
X233486Y397785D01*
X233777Y397618D01*
X234069Y397535D01*
X234361D01*
X234652Y397618D01*
X234902Y397743D01*
X235111Y397910D01*
G01X237169Y397535D02*
Y400035D01*
X236669Y399535D01*
G01Y397535D02*
X237669D01*
G01X239352D02*
Y400035D01*
X240186D01*
X240519Y399910D01*
X240769Y399743D01*
X240977Y399493D01*
X241144Y399202D01*
X241186Y398785D01*
X241144Y398368D01*
X240977Y398077D01*
X240769Y397827D01*
X240519Y397660D01*
X240186Y397535D01*
X239352D01*
G01X243369D02*
Y400035D01*
X242869Y399535D01*
G01Y397535D02*
X243869D01*
G01X234920Y373439D02*
X236712D01*
X237087Y373606D01*
X237337Y373939D01*
X237420Y374356D01*
X237337Y374773D01*
X237087Y375106D01*
X236712Y375273D01*
X234920D01*
G01X237420Y377456D02*
X234920D01*
X235420Y376956D01*
G01X237420D02*
Y377956D01*
G01Y379639D02*
X234920D01*
Y380473D01*
X235045Y380806D01*
X235212Y381056D01*
X235462Y381264D01*
X235753Y381431D01*
X236170Y381473D01*
X236587Y381431D01*
X236878Y381264D01*
X237128Y381056D01*
X237295Y380806D01*
X237420Y380473D01*
Y379639D01*
G01X235337Y382864D02*
X235087Y383114D01*
X234962Y383406D01*
X234920Y383739D01*
X235003Y384156D01*
X235212Y384448D01*
X235462Y384531D01*
X235712Y384489D01*
X235920Y384323D01*
X236337Y383489D01*
X236628Y383114D01*
X237045Y382864D01*
X237420Y382781D01*
Y384531D01*
G01X240573Y404053D02*
X240448Y403803D01*
X240365Y403511D01*
Y403178D01*
X240490Y402803D01*
X240698Y402511D01*
X240948Y402303D01*
X241365Y402136D01*
X241740Y402094D01*
X242115Y402178D01*
X242365Y402303D01*
X242615Y402553D01*
X242782Y402844D01*
X242865Y403136D01*
Y403428D01*
X242782Y403719D01*
X242657Y403969D01*
X242490Y404178D01*
G01X242865Y405444D02*
X240365D01*
Y407028D01*
G01X241573Y406444D02*
Y405444D01*
G01X242865Y409253D02*
X242323Y409336D01*
X241865Y409461D01*
X241448Y409628D01*
X240990Y409836D01*
X240365Y410169D01*
Y408503D01*
G01X256400Y434258D02*
Y437358D01*
X255940Y436738D01*
G01Y434258D02*
X256860D01*
G01X259002Y435291D02*
X259998D01*
G01X261872Y436841D02*
X262102Y437151D01*
X262370Y437306D01*
X262677Y437358D01*
X263060Y437255D01*
X263328Y436996D01*
X263405Y436686D01*
X263367Y436376D01*
X263213Y436118D01*
X262447Y435601D01*
X262102Y435240D01*
X261872Y434723D01*
X261795Y434258D01*
X263405D01*
G01X265700Y434155D02*
X265623Y434206D01*
Y434310D01*
X265700Y434361D01*
X265777Y434310D01*
Y434206D01*
X265700Y434155D01*
G01Y435550D02*
X265623Y435601D01*
Y435705D01*
X265700Y435756D01*
X265777Y435705D01*
Y435601D01*
X265700Y435550D01*
G01X269260Y434258D02*
Y437358D01*
X267842Y435136D01*
X269758D01*
G01X271900Y434258D02*
X272168Y434310D01*
X272475Y434465D01*
X272667Y434723D01*
X272743Y435085D01*
X272667Y435446D01*
X272437Y435756D01*
X272092Y435911D01*
X271708D01*
X271478Y436015D01*
X271287Y436273D01*
X271210Y436635D01*
X271325Y436996D01*
X271593Y437255D01*
X271900Y437358D01*
X272207Y437255D01*
X272475Y436996D01*
X272590Y436635D01*
X272513Y436273D01*
X272322Y436015D01*
X272092Y435911D01*
X271708D01*
X271363Y435756D01*
X271133Y435446D01*
X271057Y435085D01*
X271133Y434723D01*
X271325Y434465D01*
X271632Y434310D01*
X271900Y434258D01*
G01X275000Y434155D02*
X274923Y434206D01*
Y434310D01*
X275000Y434361D01*
X275077Y434310D01*
Y434206D01*
X275000Y434155D01*
G01X278100Y434258D02*
X278368Y434310D01*
X278675Y434465D01*
X278867Y434723D01*
X278943Y435085D01*
X278867Y435446D01*
X278637Y435756D01*
X278292Y435911D01*
X277908D01*
X277678Y436015D01*
X277487Y436273D01*
X277410Y436635D01*
X277525Y436996D01*
X277793Y437255D01*
X278100Y437358D01*
X278407Y437255D01*
X278675Y436996D01*
X278790Y436635D01*
X278713Y436273D01*
X278522Y436015D01*
X278292Y435911D01*
X277908D01*
X277563Y435756D01*
X277333Y435446D01*
X277257Y435085D01*
X277333Y434723D01*
X277525Y434465D01*
X277832Y434310D01*
X278100Y434258D01*
G01X280242D02*
X281200Y437358D01*
X282158Y434258D01*
G01X281813Y435343D02*
X280587D01*
G01X284108Y433225D02*
X283725Y433741D01*
X283533Y434258D01*
Y436325D01*
X283725Y436841D01*
X284108Y437358D01*
G01X288090D02*
Y434258D01*
G01Y434723D02*
X287937Y434465D01*
X287707Y434310D01*
X287438Y434258D01*
X287132Y434361D01*
X286902Y434620D01*
X286748Y434930D01*
X286710Y435291D01*
X286748Y435653D01*
X286902Y435963D01*
X287132Y436221D01*
X287438Y436325D01*
X287707Y436273D01*
X287898Y436170D01*
X288090Y435963D01*
G01X289925Y435653D02*
X291152D01*
X291037Y436015D01*
X290845Y436221D01*
X290577Y436325D01*
X290308Y436273D01*
X290078Y436118D01*
X289925Y435756D01*
X289848Y435446D01*
Y435136D01*
X289925Y434826D01*
X290117Y434516D01*
X290347Y434310D01*
X290615Y434258D01*
X290883Y434361D01*
X291152Y434671D01*
G01X293370Y434258D02*
Y436893D01*
X293447Y437151D01*
X293600Y437306D01*
X293830Y437358D01*
X294060Y437255D01*
X294175Y436996D01*
G01X293715Y436118D02*
X292948D01*
G01X297390Y434258D02*
Y436325D01*
G01Y435963D02*
X297237Y436170D01*
X297007Y436273D01*
X296738Y436325D01*
X296470Y436221D01*
X296240Y436015D01*
X296087Y435705D01*
X296010Y435291D01*
X296087Y434878D01*
X296240Y434568D01*
X296470Y434361D01*
X296738Y434258D01*
X297007Y434310D01*
X297237Y434465D01*
X297390Y434671D01*
G01X299148Y436325D02*
Y434878D01*
X299302Y434516D01*
X299532Y434310D01*
X299800Y434258D01*
X300068Y434310D01*
X300298Y434516D01*
X300452Y434878D01*
G01Y434258D02*
Y436325D01*
G01X302900Y434258D02*
Y437358D01*
G01X306000D02*
Y434258D01*
G01X305463Y436325D02*
X306537D01*
G01X309292Y433225D02*
X309675Y433741D01*
X309867Y434258D01*
Y436325D01*
X309675Y436841D01*
X309292Y437358D01*
G01X256172Y430287D02*
X256402Y430597D01*
X256670Y430752D01*
X256977Y430804D01*
X257360Y430701D01*
X257628Y430442D01*
X257705Y430132D01*
X257667Y429822D01*
X257513Y429564D01*
X256747Y429047D01*
X256402Y428686D01*
X256172Y428169D01*
X256095Y427704D01*
X257705D01*
G01X259502Y428737D02*
X260498D01*
G01X262257Y428324D02*
X262487Y427962D01*
X262793Y427756D01*
X263138Y427704D01*
X263445Y427756D01*
X263752Y428014D01*
X263943Y428324D01*
X263982Y428634D01*
X263905Y428996D01*
X263637Y429254D01*
X263368Y429357D01*
X263023D01*
G01X263368D02*
X263598Y429512D01*
X263790Y429771D01*
X263867Y430081D01*
X263790Y430391D01*
X263598Y430649D01*
X263253Y430804D01*
X262908Y430752D01*
X262563Y430546D01*
G01X266200Y427601D02*
X266123Y427652D01*
Y427756D01*
X266200Y427807D01*
X266277Y427756D01*
Y427652D01*
X266200Y427601D01*
G01Y428996D02*
X266123Y429047D01*
Y429151D01*
X266200Y429202D01*
X266277Y429151D01*
Y429047D01*
X266200Y428996D01*
G01X269760Y427704D02*
Y430804D01*
X268342Y428582D01*
X270258D01*
G01X272400Y427704D02*
Y430804D01*
X271940Y430184D01*
G01Y427704D02*
X272860D01*
G01X275500Y427601D02*
X275423Y427652D01*
Y427756D01*
X275500Y427807D01*
X275577Y427756D01*
Y427652D01*
X275500Y427601D01*
G01X279060Y427704D02*
Y430804D01*
X277642Y428582D01*
X279558D01*
G01X280742Y427704D02*
X281700Y430804D01*
X282658Y427704D01*
G01X282313Y428789D02*
X281087D01*
G01X267032Y440678D02*
X267224Y440368D01*
X267454Y440161D01*
X267722Y440058D01*
X268029Y440161D01*
X268259Y440368D01*
X268489Y440678D01*
X268566Y441091D01*
Y443158D01*
G01X270899Y440058D02*
Y443158D01*
X270439Y442538D01*
G01Y440058D02*
X271359D01*
G01X274306Y441711D02*
X274459Y441866D01*
X274574Y442125D01*
X274651Y442486D01*
X274574Y442796D01*
X274421Y443003D01*
X274152Y443158D01*
X273117D01*
Y440058D01*
X274382D01*
X274651Y440265D01*
X274804Y440575D01*
X274881Y440936D01*
X274804Y441298D01*
X274574Y441608D01*
X274306Y441711D01*
X273117D01*
G01X276256Y440678D02*
X276486Y440316D01*
X276792Y440110D01*
X277137Y440058D01*
X277444Y440110D01*
X277751Y440368D01*
X277942Y440678D01*
X277981Y440988D01*
X277904Y441350D01*
X277636Y441608D01*
X277367Y441711D01*
X277022D01*
G01X277367D02*
X277597Y441866D01*
X277789Y442125D01*
X277866Y442435D01*
X277789Y442745D01*
X277597Y443003D01*
X277252Y443158D01*
X276907Y443106D01*
X276562Y442900D01*
G01X283299Y440058D02*
X283069Y440110D01*
X282839Y440316D01*
X282686Y440678D01*
X282609Y441091D01*
X282686Y441505D01*
X282839Y441866D01*
X283069Y442073D01*
X283299Y442125D01*
X283529Y442073D01*
X283759Y441866D01*
X283912Y441505D01*
X283951Y441091D01*
X283912Y440678D01*
X283759Y440316D01*
X283529Y440110D01*
X283299Y440058D01*
G01X285862D02*
Y442125D01*
G01Y441711D02*
X286054Y441918D01*
X286246Y442073D01*
X286514Y442125D01*
X286706Y442073D01*
X286936Y441918D01*
G01X291832Y440678D02*
X292024Y440368D01*
X292254Y440161D01*
X292522Y440058D01*
X292829Y440161D01*
X293059Y440368D01*
X293289Y440678D01*
X293366Y441091D01*
Y443158D01*
G01X295699Y440058D02*
Y443158D01*
X295239Y442538D01*
G01Y440058D02*
X296159D01*
G01X299106Y441711D02*
X299259Y441866D01*
X299374Y442125D01*
X299451Y442486D01*
X299374Y442796D01*
X299221Y443003D01*
X298952Y443158D01*
X297917D01*
Y440058D01*
X299182D01*
X299451Y440265D01*
X299604Y440575D01*
X299681Y440936D01*
X299604Y441298D01*
X299374Y441608D01*
X299106Y441711D01*
X297917D01*
G01X302359Y440058D02*
Y443158D01*
X300941Y440936D01*
X302857D01*
G01X251967Y423622D02*
Y461700D01*
X233400D01*
G01X254272Y438251D02*
Y426251D01*
X315272D01*
Y438751D01*
X254272D01*
Y438251D01*
G01Y432251D02*
X315272D01*
G01X246971Y423699D02*
X244471D01*
Y424740D01*
X244596Y425074D01*
X244763Y425282D01*
X245096Y425365D01*
X245429Y425282D01*
X245638Y425032D01*
X245763Y424740D01*
Y423699D01*
G01Y424740D02*
X246971Y425365D01*
G01Y426840D02*
X244471D01*
Y428424D01*
G01X245679Y427840D02*
Y426840D01*
G01X246971Y430732D02*
X244471D01*
X244971Y430232D01*
G01X246971D02*
Y431232D01*
G01X244471Y433832D02*
X244554Y433499D01*
X244763Y433249D01*
X245013Y433082D01*
X245346Y432957D01*
X245721Y432915D01*
X246096Y432957D01*
X246429Y433082D01*
X246679Y433249D01*
X246888Y433499D01*
X246971Y433832D01*
X246888Y434165D01*
X246679Y434415D01*
X246429Y434582D01*
X246096Y434707D01*
X245721Y434749D01*
X245346Y434707D01*
X245013Y434582D01*
X244763Y434415D01*
X244554Y434165D01*
X244471Y433832D01*
G01X246826Y409834D02*
X244326D01*
Y410875D01*
X244451Y411209D01*
X244618Y411417D01*
X244951Y411500D01*
X245284Y411417D01*
X245493Y411167D01*
X245618Y410875D01*
Y409834D01*
G01Y410875D02*
X246826Y411500D01*
G01Y412975D02*
X244326D01*
Y414559D01*
G01X245534Y413975D02*
Y412975D01*
G01X246826Y416867D02*
X246784Y417159D01*
X246659Y417492D01*
X246451Y417700D01*
X246159Y417784D01*
X245868Y417700D01*
X245618Y417450D01*
X245493Y417075D01*
Y416659D01*
X245409Y416409D01*
X245201Y416200D01*
X244909Y416117D01*
X244618Y416242D01*
X244409Y416534D01*
X244326Y416867D01*
X244409Y417200D01*
X244618Y417492D01*
X244909Y417617D01*
X245201Y417534D01*
X245409Y417325D01*
X245493Y417075D01*
Y416659D01*
X245618Y416284D01*
X245868Y416034D01*
X246159Y415950D01*
X246451Y416034D01*
X246659Y416242D01*
X246784Y416575D01*
X246826Y416867D01*
G01X238982Y415807D02*
X236482D01*
Y416848D01*
X236607Y417182D01*
X236774Y417390D01*
X237107Y417473D01*
X237440Y417390D01*
X237649Y417140D01*
X237774Y416848D01*
Y415807D01*
G01Y416848D02*
X238982Y417473D01*
G01Y418948D02*
X236482D01*
Y420532D01*
G01X237690Y419948D02*
Y418948D01*
G01X238690Y422132D02*
X238899Y422423D01*
X238982Y422757D01*
X238899Y423090D01*
X238649Y423382D01*
X238274Y423590D01*
X237899Y423673D01*
X237440D01*
X237065Y423590D01*
X236732Y423382D01*
X236565Y423132D01*
X236482Y422840D01*
X236565Y422507D01*
X236732Y422257D01*
X236982Y422090D01*
X237315Y422007D01*
X237607Y422090D01*
X237899Y422298D01*
X238065Y422548D01*
X238107Y422840D01*
X238024Y423173D01*
X237815Y423423D01*
X237440Y423673D01*
G01X238721Y432028D02*
X236221D01*
Y433069D01*
X236346Y433403D01*
X236513Y433611D01*
X236846Y433694D01*
X237179Y433611D01*
X237388Y433361D01*
X237513Y433069D01*
Y432028D01*
G01Y433069D02*
X238721Y433694D01*
G01Y435169D02*
X236221D01*
Y436753D01*
G01X237429Y436169D02*
Y435169D01*
G01X238721Y439061D02*
X236221D01*
X236721Y438561D01*
G01X238721D02*
Y439561D01*
G01Y442161D02*
X236221D01*
X236721Y441661D01*
G01X238721D02*
Y442661D01*
G01X282895Y417870D02*
Y416078D01*
X283062Y415703D01*
X283395Y415453D01*
X283812Y415370D01*
X284229Y415453D01*
X284562Y415703D01*
X284729Y416078D01*
Y417870D01*
G01X286120Y417453D02*
X286370Y417703D01*
X286662Y417828D01*
X286995Y417870D01*
X287412Y417787D01*
X287704Y417578D01*
X287787Y417328D01*
X287745Y417078D01*
X287579Y416870D01*
X286745Y416453D01*
X286370Y416162D01*
X286120Y415745D01*
X286037Y415370D01*
X287787D01*
G01X289095D02*
Y417870D01*
X289929D01*
X290262Y417745D01*
X290512Y417578D01*
X290720Y417328D01*
X290887Y417037D01*
X290929Y416620D01*
X290887Y416203D01*
X290720Y415912D01*
X290512Y415662D01*
X290262Y415495D01*
X289929Y415370D01*
X289095D01*
G01X293112D02*
Y417870D01*
X292612Y417370D01*
G01Y415370D02*
X293612D01*
G01X240309Y433764D02*
X240184Y433514D01*
X240101Y433222D01*
Y432889D01*
X240226Y432514D01*
X240434Y432222D01*
X240684Y432014D01*
X241101Y431847D01*
X241476Y431805D01*
X241851Y431889D01*
X242101Y432014D01*
X242351Y432264D01*
X242518Y432555D01*
X242601Y432847D01*
Y433139D01*
X242518Y433430D01*
X242393Y433680D01*
X242226Y433889D01*
G01X242601Y435155D02*
X240101D01*
Y436739D01*
G01X241309Y436155D02*
Y435155D01*
G01X242601Y439047D02*
X240101D01*
X240601Y438547D01*
G01X242601D02*
Y439547D01*
G01Y442147D02*
X240101D01*
X240601Y441647D01*
G01X242601D02*
Y442647D01*
G01X240423Y417497D02*
X240298Y417247D01*
X240215Y416955D01*
Y416622D01*
X240340Y416247D01*
X240548Y415955D01*
X240798Y415747D01*
X241215Y415580D01*
X241590Y415538D01*
X241965Y415622D01*
X242215Y415747D01*
X242465Y415997D01*
X242632Y416288D01*
X242715Y416580D01*
Y416872D01*
X242632Y417163D01*
X242507Y417413D01*
X242340Y417622D01*
G01X242715Y418888D02*
X240215D01*
Y420472D01*
G01X241423Y419888D02*
Y418888D01*
G01X242423Y422072D02*
X242632Y422363D01*
X242715Y422697D01*
X242632Y423030D01*
X242382Y423322D01*
X242007Y423530D01*
X241632Y423613D01*
X241173D01*
X240798Y423530D01*
X240465Y423322D01*
X240298Y423072D01*
X240215Y422780D01*
X240298Y422447D01*
X240465Y422197D01*
X240715Y422030D01*
X241048Y421947D01*
X241340Y422030D01*
X241632Y422238D01*
X241798Y422488D01*
X241840Y422780D01*
X241757Y423113D01*
X241548Y423363D01*
X241173Y423613D01*
G01X248034Y411584D02*
X247909Y411334D01*
X247826Y411042D01*
Y410709D01*
X247951Y410334D01*
X248159Y410042D01*
X248409Y409834D01*
X248826Y409667D01*
X249201Y409625D01*
X249576Y409709D01*
X249826Y409834D01*
X250076Y410084D01*
X250243Y410375D01*
X250326Y410667D01*
Y410959D01*
X250243Y411250D01*
X250118Y411500D01*
X249951Y411709D01*
G01X250326Y412975D02*
X247826D01*
Y414559D01*
G01X249034Y413975D02*
Y412975D01*
G01X250326Y416867D02*
X250284Y417159D01*
X250159Y417492D01*
X249951Y417700D01*
X249659Y417784D01*
X249368Y417700D01*
X249118Y417450D01*
X248993Y417075D01*
Y416659D01*
X248909Y416409D01*
X248701Y416200D01*
X248409Y416117D01*
X248118Y416242D01*
X247909Y416534D01*
X247826Y416867D01*
X247909Y417200D01*
X248118Y417492D01*
X248409Y417617D01*
X248701Y417534D01*
X248909Y417325D01*
X248993Y417075D01*
Y416659D01*
X249118Y416284D01*
X249368Y416034D01*
X249659Y415950D01*
X249951Y416034D01*
X250159Y416242D01*
X250284Y416575D01*
X250326Y416867D01*
G01X248523Y425406D02*
X248398Y425156D01*
X248315Y424864D01*
Y424531D01*
X248440Y424156D01*
X248648Y423864D01*
X248898Y423656D01*
X249315Y423489D01*
X249690Y423447D01*
X250065Y423531D01*
X250315Y423656D01*
X250565Y423906D01*
X250732Y424197D01*
X250815Y424489D01*
Y424781D01*
X250732Y425072D01*
X250607Y425322D01*
X250440Y425531D01*
G01X250815Y426797D02*
X248315D01*
Y428381D01*
G01X249523Y427797D02*
Y426797D01*
G01X250815Y430689D02*
X248315D01*
X248815Y430189D01*
G01X250815D02*
Y431189D01*
G01X248315Y433789D02*
X248398Y433456D01*
X248607Y433206D01*
X248857Y433039D01*
X249190Y432914D01*
X249565Y432872D01*
X249940Y432914D01*
X250273Y433039D01*
X250523Y433206D01*
X250732Y433456D01*
X250815Y433789D01*
X250732Y434122D01*
X250523Y434372D01*
X250273Y434539D01*
X249940Y434664D01*
X249565Y434706D01*
X249190Y434664D01*
X248857Y434539D01*
X248607Y434372D01*
X248398Y434122D01*
X248315Y433789D01*
G01X283854Y548967D02*
X283604Y549092D01*
X283312Y549175D01*
X282979D01*
X282604Y549050D01*
X282312Y548842D01*
X282104Y548592D01*
X281937Y548175D01*
X281895Y547800D01*
X281979Y547425D01*
X282104Y547175D01*
X282354Y546925D01*
X282645Y546758D01*
X282937Y546675D01*
X283229D01*
X283520Y546758D01*
X283770Y546883D01*
X283979Y547050D01*
G01X285245Y548758D02*
X285495Y549008D01*
X285787Y549133D01*
X286120Y549175D01*
X286537Y549092D01*
X286829Y548883D01*
X286912Y548633D01*
X286870Y548383D01*
X286704Y548175D01*
X285870Y547758D01*
X285495Y547467D01*
X285245Y547050D01*
X285162Y546675D01*
X286912D01*
G01X288095D02*
X289137Y549175D01*
X290179Y546675D01*
G01X289804Y547550D02*
X288470D01*
G01X292237Y546675D02*
Y549175D01*
X291737Y548675D01*
G01Y546675D02*
X292737D01*
G01X294545Y548758D02*
X294795Y549008D01*
X295087Y549133D01*
X295420Y549175D01*
X295837Y549092D01*
X296129Y548883D01*
X296212Y548633D01*
X296170Y548383D01*
X296004Y548175D01*
X295170Y547758D01*
X294795Y547467D01*
X294545Y547050D01*
X294462Y546675D01*
X296212D01*
G01X279750Y553103D02*
X279500Y553228D01*
X279208Y553311D01*
X278875D01*
X278500Y553186D01*
X278208Y552978D01*
X278000Y552728D01*
X277833Y552311D01*
X277791Y551936D01*
X277875Y551561D01*
X278000Y551311D01*
X278250Y551061D01*
X278541Y550894D01*
X278833Y550811D01*
X279125D01*
X279416Y550894D01*
X279666Y551019D01*
X279875Y551186D01*
G01X281141Y552894D02*
X281391Y553144D01*
X281683Y553269D01*
X282016Y553311D01*
X282433Y553228D01*
X282725Y553019D01*
X282808Y552769D01*
X282766Y552519D01*
X282600Y552311D01*
X281766Y551894D01*
X281391Y551603D01*
X281141Y551186D01*
X281058Y550811D01*
X282808D01*
G01X283991D02*
X285033Y553311D01*
X286075Y550811D01*
G01X285700Y551686D02*
X284366D01*
G01X288133Y550811D02*
Y553311D01*
X287633Y552811D01*
G01Y550811D02*
X288633D01*
G01X291233D02*
Y553311D01*
X290733Y552811D01*
G01Y550811D02*
X291733D01*
G01X280154Y556866D02*
X279904Y556991D01*
X279612Y557074D01*
X279279D01*
X278904Y556949D01*
X278612Y556741D01*
X278404Y556491D01*
X278237Y556074D01*
X278195Y555699D01*
X278279Y555324D01*
X278404Y555074D01*
X278654Y554824D01*
X278945Y554657D01*
X279237Y554574D01*
X279529D01*
X279820Y554657D01*
X280070Y554782D01*
X280279Y554949D01*
G01X281545Y556657D02*
X281795Y556907D01*
X282087Y557032D01*
X282420Y557074D01*
X282837Y556991D01*
X283129Y556782D01*
X283212Y556532D01*
X283170Y556282D01*
X283004Y556074D01*
X282170Y555657D01*
X281795Y555366D01*
X281545Y554949D01*
X281462Y554574D01*
X283212D01*
G01X284395D02*
X285437Y557074D01*
X286479Y554574D01*
G01X286104Y555449D02*
X284770D01*
G01X288537Y554574D02*
Y557074D01*
X288037Y556574D01*
G01Y554574D02*
X289037D01*
G01X291637Y557074D02*
X291304Y556991D01*
X291054Y556782D01*
X290887Y556532D01*
X290762Y556199D01*
X290720Y555824D01*
X290762Y555449D01*
X290887Y555116D01*
X291054Y554866D01*
X291304Y554657D01*
X291637Y554574D01*
X291970Y554657D01*
X292220Y554866D01*
X292387Y555116D01*
X292512Y555449D01*
X292554Y555824D01*
X292512Y556199D01*
X292387Y556532D01*
X292220Y556782D01*
X291970Y556991D01*
X291637Y557074D01*
G01X274563Y548353D02*
X274438Y548103D01*
X274355Y547811D01*
Y547478D01*
X274480Y547103D01*
X274688Y546811D01*
X274938Y546603D01*
X275355Y546436D01*
X275730Y546394D01*
X276105Y546478D01*
X276355Y546603D01*
X276605Y546853D01*
X276772Y547144D01*
X276855Y547436D01*
Y547728D01*
X276772Y548019D01*
X276647Y548269D01*
X276480Y548478D01*
G01X274772Y549744D02*
X274522Y549994D01*
X274397Y550286D01*
X274355Y550619D01*
X274438Y551036D01*
X274647Y551328D01*
X274897Y551411D01*
X275147Y551369D01*
X275355Y551203D01*
X275772Y550369D01*
X276063Y549994D01*
X276480Y549744D01*
X276855Y549661D01*
Y551411D01*
G01Y552594D02*
X274355Y553636D01*
X276855Y554678D01*
G01X275980Y554303D02*
Y552969D01*
G01X276563Y556028D02*
X276772Y556319D01*
X276855Y556653D01*
X276772Y556986D01*
X276522Y557278D01*
X276147Y557486D01*
X275772Y557569D01*
X275313D01*
X274938Y557486D01*
X274605Y557278D01*
X274438Y557028D01*
X274355Y556736D01*
X274438Y556403D01*
X274605Y556153D01*
X274855Y555986D01*
X275188Y555903D01*
X275480Y555986D01*
X275772Y556194D01*
X275938Y556444D01*
X275980Y556736D01*
X275897Y557069D01*
X275688Y557319D01*
X275313Y557569D01*
G01X291198Y585947D02*
X291073Y585697D01*
X290990Y585405D01*
Y585072D01*
X291115Y584697D01*
X291323Y584405D01*
X291573Y584197D01*
X291990Y584030D01*
X292365Y583988D01*
X292740Y584072D01*
X292990Y584197D01*
X293240Y584447D01*
X293407Y584738D01*
X293490Y585030D01*
Y585322D01*
X293407Y585613D01*
X293282Y585863D01*
X293115Y586072D01*
G01X291407Y587338D02*
X291157Y587588D01*
X291032Y587880D01*
X290990Y588213D01*
X291073Y588630D01*
X291282Y588922D01*
X291532Y589005D01*
X291782Y588963D01*
X291990Y588797D01*
X292407Y587963D01*
X292698Y587588D01*
X293115Y587338D01*
X293490Y587255D01*
Y589005D01*
G01Y590188D02*
X290990Y591230D01*
X293490Y592272D01*
G01X292615Y591897D02*
Y590563D01*
G01X292990Y593413D02*
X293282Y593663D01*
X293448Y593997D01*
X293490Y594372D01*
X293448Y594705D01*
X293240Y595038D01*
X292990Y595247D01*
X292740Y595288D01*
X292448Y595205D01*
X292240Y594913D01*
X292157Y594622D01*
Y594247D01*
G01Y594622D02*
X292032Y594872D01*
X291823Y595080D01*
X291573Y595163D01*
X291323Y595080D01*
X291115Y594872D01*
X290990Y594497D01*
X291032Y594122D01*
X291198Y593747D01*
G01X285430Y586191D02*
X285305Y585941D01*
X285222Y585649D01*
Y585316D01*
X285347Y584941D01*
X285555Y584649D01*
X285805Y584441D01*
X286222Y584274D01*
X286597Y584232D01*
X286972Y584316D01*
X287222Y584441D01*
X287472Y584691D01*
X287639Y584982D01*
X287722Y585274D01*
Y585566D01*
X287639Y585857D01*
X287514Y586107D01*
X287347Y586316D01*
G01X285639Y587582D02*
X285389Y587832D01*
X285264Y588124D01*
X285222Y588457D01*
X285305Y588874D01*
X285514Y589166D01*
X285764Y589249D01*
X286014Y589207D01*
X286222Y589041D01*
X286639Y588207D01*
X286930Y587832D01*
X287347Y587582D01*
X287722Y587499D01*
Y589249D01*
G01Y590432D02*
X285222Y591474D01*
X287722Y592516D01*
G01X286847Y592141D02*
Y590807D01*
G01X285639Y593782D02*
X285389Y594032D01*
X285264Y594324D01*
X285222Y594657D01*
X285305Y595074D01*
X285514Y595366D01*
X285764Y595449D01*
X286014Y595407D01*
X286222Y595241D01*
X286639Y594407D01*
X286930Y594032D01*
X287347Y593782D01*
X287722Y593699D01*
Y595449D01*
G01X280937Y586506D02*
X280812Y586256D01*
X280729Y585964D01*
Y585631D01*
X280854Y585256D01*
X281062Y584964D01*
X281312Y584756D01*
X281729Y584589D01*
X282104Y584547D01*
X282479Y584631D01*
X282729Y584756D01*
X282979Y585006D01*
X283146Y585297D01*
X283229Y585589D01*
Y585881D01*
X283146Y586172D01*
X283021Y586422D01*
X282854Y586631D01*
G01X281146Y587897D02*
X280896Y588147D01*
X280771Y588439D01*
X280729Y588772D01*
X280812Y589189D01*
X281021Y589481D01*
X281271Y589564D01*
X281521Y589522D01*
X281729Y589356D01*
X282146Y588522D01*
X282437Y588147D01*
X282854Y587897D01*
X283229Y587814D01*
Y589564D01*
G01Y590747D02*
X280729Y591789D01*
X283229Y592831D01*
G01X282354Y592456D02*
Y591122D01*
G01X283229Y594889D02*
X280729D01*
X281229Y594389D01*
G01X283229D02*
Y595389D01*
G01X297017Y12458D02*
X296767Y12583D01*
X296475Y12666D01*
X296142D01*
X295767Y12541D01*
X295475Y12333D01*
X295267Y12083D01*
X295100Y11666D01*
X295058Y11291D01*
X295142Y10916D01*
X295267Y10666D01*
X295517Y10416D01*
X295808Y10249D01*
X296100Y10166D01*
X296392D01*
X296683Y10249D01*
X296933Y10374D01*
X297142Y10541D01*
G01X298408Y12249D02*
X298658Y12499D01*
X298950Y12624D01*
X299283Y12666D01*
X299700Y12583D01*
X299992Y12374D01*
X300075Y12124D01*
X300033Y11874D01*
X299867Y11666D01*
X299033Y11249D01*
X298658Y10958D01*
X298408Y10541D01*
X298325Y10166D01*
X300075D01*
G01X302550Y11416D02*
X303383D01*
Y10666D01*
X303133Y10416D01*
X302842Y10249D01*
X302425Y10166D01*
X302008Y10249D01*
X301717Y10416D01*
X301467Y10666D01*
X301300Y10958D01*
X301217Y11291D01*
Y11583D01*
X301300Y11833D01*
X301467Y12124D01*
X301717Y12374D01*
X301967Y12541D01*
X302300Y12666D01*
X302592D01*
X302925Y12583D01*
X303175Y12416D01*
G01X305400Y10166D02*
Y12666D01*
X304900Y12166D01*
G01Y10166D02*
X305900D01*
G01X307708Y11208D02*
X308000Y11499D01*
X308250Y11666D01*
X308583Y11749D01*
X308875Y11666D01*
X309083Y11499D01*
X309250Y11249D01*
X309292Y10958D01*
X309250Y10708D01*
X309083Y10458D01*
X308833Y10249D01*
X308542Y10166D01*
X308208Y10249D01*
X307917Y10499D01*
X307750Y10874D01*
X307708Y11291D01*
X307792Y11833D01*
X307917Y12124D01*
X308125Y12416D01*
X308417Y12624D01*
X308708Y12666D01*
X309000Y12583D01*
X309208Y12374D01*
G01X300515Y48181D02*
X300265Y48306D01*
X299973Y48389D01*
X299640D01*
X299265Y48264D01*
X298973Y48056D01*
X298765Y47806D01*
X298598Y47389D01*
X298556Y47014D01*
X298640Y46639D01*
X298765Y46389D01*
X299015Y46139D01*
X299306Y45972D01*
X299598Y45889D01*
X299890D01*
X300181Y45972D01*
X300431Y46097D01*
X300640Y46264D01*
G01X301906Y47972D02*
X302156Y48222D01*
X302448Y48347D01*
X302781Y48389D01*
X303198Y48306D01*
X303490Y48097D01*
X303573Y47847D01*
X303531Y47597D01*
X303365Y47389D01*
X302531Y46972D01*
X302156Y46681D01*
X301906Y46264D01*
X301823Y45889D01*
X303573D01*
G01X306048Y47139D02*
X306881D01*
Y46389D01*
X306631Y46139D01*
X306340Y45972D01*
X305923Y45889D01*
X305506Y45972D01*
X305215Y46139D01*
X304965Y46389D01*
X304798Y46681D01*
X304715Y47014D01*
Y47306D01*
X304798Y47556D01*
X304965Y47847D01*
X305215Y48097D01*
X305465Y48264D01*
X305798Y48389D01*
X306090D01*
X306423Y48306D01*
X306673Y48139D01*
G01X308815Y45889D02*
X308898Y46431D01*
X309023Y46889D01*
X309190Y47306D01*
X309398Y47764D01*
X309731Y48389D01*
X308065D01*
G01X308934Y98279D02*
X308668Y98191D01*
X308403Y98044D01*
X308168Y97808D01*
X307991Y97454D01*
X307932Y97101D01*
X307961Y96777D01*
X308138Y96364D01*
X308374Y96070D01*
X308698Y95864D01*
X308963Y95775D01*
X309317D01*
X309641Y95864D01*
X309906Y96011D01*
X310112Y96217D01*
X310259Y96482D01*
X310348Y96747D01*
X310377Y97013D01*
G01X310065Y99116D02*
Y99470D01*
X310183Y99764D01*
X310389Y100030D01*
X310743Y100265D01*
X311096Y100324D01*
X311332Y100206D01*
X311479Y100000D01*
X311509Y99735D01*
X311214Y98851D01*
X311155Y98380D01*
X311273Y97908D01*
X311479Y97584D01*
X312717Y98822D01*
G01X313730Y99835D02*
X311962Y101603D01*
X313082Y102722D01*
G01X313524Y101456D02*
X312817Y100748D01*
G01X316482Y102587D02*
X314714Y104355D01*
Y103648D01*
G01X316128Y102233D02*
X316835Y102940D01*
G01X331367Y116667D02*
X334700Y123667D01*
X338033Y116667D01*
G01X336833Y119117D02*
X332567D01*
G01X339967Y116667D02*
X343300Y123667D01*
X346633Y116667D01*
G01X345433Y119117D02*
X341167D01*
G01X303000Y107000D02*
X299000D01*
G01X308474D02*
X305500D01*
G01X322500D02*
X311607D01*
G01X362000D02*
X330500D01*
G01X328500D02*
X324500D01*
G01X334951Y146771D02*
X334701Y146896D01*
X334409Y146979D01*
X334076D01*
X333701Y146854D01*
X333409Y146646D01*
X333201Y146396D01*
X333034Y145979D01*
X332992Y145604D01*
X333076Y145229D01*
X333201Y144979D01*
X333451Y144729D01*
X333742Y144562D01*
X334034Y144479D01*
X334326D01*
X334617Y144562D01*
X334867Y144687D01*
X335076Y144854D01*
G01X337134Y144479D02*
Y146979D01*
X336634Y146479D01*
G01Y144479D02*
X337634D01*
G01X340484Y145729D02*
X341317D01*
Y144979D01*
X341067Y144729D01*
X340776Y144562D01*
X340359Y144479D01*
X339942Y144562D01*
X339651Y144729D01*
X339401Y144979D01*
X339234Y145271D01*
X339151Y145604D01*
Y145896D01*
X339234Y146146D01*
X339401Y146437D01*
X339651Y146687D01*
X339901Y146854D01*
X340234Y146979D01*
X340526D01*
X340859Y146896D01*
X341109Y146729D01*
G01X343334Y144479D02*
Y146979D01*
X342834Y146479D01*
G01Y144479D02*
X343834D01*
G01X346351D02*
X346434Y145021D01*
X346559Y145479D01*
X346726Y145896D01*
X346934Y146354D01*
X347267Y146979D01*
X345601D01*
G01X335050Y143670D02*
X334800Y143795D01*
X334508Y143878D01*
X334175D01*
X333800Y143753D01*
X333508Y143545D01*
X333300Y143295D01*
X333133Y142878D01*
X333091Y142503D01*
X333175Y142128D01*
X333300Y141878D01*
X333550Y141628D01*
X333841Y141461D01*
X334133Y141378D01*
X334425D01*
X334716Y141461D01*
X334966Y141586D01*
X335175Y141753D01*
G01X337233Y141378D02*
Y143878D01*
X336733Y143378D01*
G01Y141378D02*
X337733D01*
G01X340583Y142628D02*
X341416D01*
Y141878D01*
X341166Y141628D01*
X340875Y141461D01*
X340458Y141378D01*
X340041Y141461D01*
X339750Y141628D01*
X339500Y141878D01*
X339333Y142170D01*
X339250Y142503D01*
Y142795D01*
X339333Y143045D01*
X339500Y143336D01*
X339750Y143586D01*
X340000Y143753D01*
X340333Y143878D01*
X340625D01*
X340958Y143795D01*
X341208Y143628D01*
G01X342641Y143461D02*
X342891Y143711D01*
X343183Y143836D01*
X343516Y143878D01*
X343933Y143795D01*
X344225Y143586D01*
X344308Y143336D01*
X344266Y143086D01*
X344100Y142878D01*
X343266Y142461D01*
X342891Y142170D01*
X342641Y141753D01*
X342558Y141378D01*
X344308D01*
G01X346533Y143878D02*
X346200Y143795D01*
X345950Y143586D01*
X345783Y143336D01*
X345658Y143003D01*
X345616Y142628D01*
X345658Y142253D01*
X345783Y141920D01*
X345950Y141670D01*
X346200Y141461D01*
X346533Y141378D01*
X346866Y141461D01*
X347116Y141670D01*
X347283Y141920D01*
X347408Y142253D01*
X347450Y142628D01*
X347408Y143003D01*
X347283Y143336D01*
X347116Y143586D01*
X346866Y143795D01*
X346533Y143878D01*
G01X353670Y121694D02*
X351170D01*
Y122735D01*
X351295Y123069D01*
X351462Y123277D01*
X351795Y123360D01*
X352128Y123277D01*
X352337Y123027D01*
X352462Y122735D01*
Y121694D01*
G01Y122735D02*
X353670Y123360D01*
G01Y125627D02*
X351170D01*
X351670Y125127D01*
G01X353670D02*
Y126127D01*
G01X352420Y128977D02*
Y129810D01*
X353170D01*
X353420Y129560D01*
X353587Y129269D01*
X353670Y128852D01*
X353587Y128435D01*
X353420Y128144D01*
X353170Y127894D01*
X352878Y127727D01*
X352545Y127644D01*
X352253D01*
X352003Y127727D01*
X351712Y127894D01*
X351462Y128144D01*
X351295Y128394D01*
X351170Y128727D01*
Y129019D01*
X351253Y129352D01*
X351420Y129602D01*
G01X353670Y131827D02*
X351170D01*
X351670Y131327D01*
G01X353670D02*
Y132327D01*
G01Y135427D02*
X351170D01*
X352962Y133885D01*
Y135969D01*
G01X357170Y121694D02*
X354670D01*
Y122735D01*
X354795Y123069D01*
X354962Y123277D01*
X355295Y123360D01*
X355628Y123277D01*
X355837Y123027D01*
X355962Y122735D01*
Y121694D01*
G01Y122735D02*
X357170Y123360D01*
G01Y125627D02*
X354670D01*
X355170Y125127D01*
G01X357170D02*
Y126127D01*
G01X355920Y128977D02*
Y129810D01*
X356670D01*
X356920Y129560D01*
X357087Y129269D01*
X357170Y128852D01*
X357087Y128435D01*
X356920Y128144D01*
X356670Y127894D01*
X356378Y127727D01*
X356045Y127644D01*
X355753D01*
X355503Y127727D01*
X355212Y127894D01*
X354962Y128144D01*
X354795Y128394D01*
X354670Y128727D01*
Y129019D01*
X354753Y129352D01*
X354920Y129602D01*
G01X357170Y131827D02*
X354670D01*
X355170Y131327D01*
G01X357170D02*
Y132327D01*
G01X356795Y134010D02*
X357003Y134260D01*
X357128Y134552D01*
X357170Y134927D01*
X357087Y135302D01*
X356920Y135594D01*
X356628Y135802D01*
X356295Y135844D01*
X355962Y135760D01*
X355753Y135552D01*
X355587Y135260D01*
X355545Y134969D01*
X355587Y134677D01*
X355753Y134302D01*
X354670Y134427D01*
Y135552D01*
G01X316174Y140636D02*
Y143136D01*
X317215D01*
X317549Y143011D01*
X317757Y142844D01*
X317840Y142511D01*
X317757Y142178D01*
X317507Y141969D01*
X317215Y141844D01*
X316174D01*
G01X317215D02*
X317840Y140636D01*
G01X320107D02*
Y143136D01*
X319607Y142636D01*
G01Y140636D02*
X320607D01*
G01X323457Y141886D02*
X324290D01*
Y141136D01*
X324040Y140886D01*
X323749Y140719D01*
X323332Y140636D01*
X322915Y140719D01*
X322624Y140886D01*
X322374Y141136D01*
X322207Y141428D01*
X322124Y141761D01*
Y142053D01*
X322207Y142303D01*
X322374Y142594D01*
X322624Y142844D01*
X322874Y143011D01*
X323207Y143136D01*
X323499D01*
X323832Y143053D01*
X324082Y142886D01*
G01X326307Y140636D02*
Y143136D01*
X325807Y142636D01*
G01Y140636D02*
X326807D01*
G01X328615Y141678D02*
X328907Y141969D01*
X329157Y142136D01*
X329490Y142219D01*
X329782Y142136D01*
X329990Y141969D01*
X330157Y141719D01*
X330199Y141428D01*
X330157Y141178D01*
X329990Y140928D01*
X329740Y140719D01*
X329449Y140636D01*
X329115Y140719D01*
X328824Y140969D01*
X328657Y141344D01*
X328615Y141761D01*
X328699Y142303D01*
X328824Y142594D01*
X329032Y142886D01*
X329324Y143094D01*
X329615Y143136D01*
X329907Y143053D01*
X330115Y142844D01*
G01X311661Y150713D02*
Y153213D01*
X312702D01*
X313036Y153088D01*
X313244Y152921D01*
X313327Y152588D01*
X313244Y152255D01*
X312994Y152046D01*
X312702Y151921D01*
X311661D01*
G01X312702D02*
X313327Y150713D01*
G01X315594D02*
Y153213D01*
X315094Y152713D01*
G01Y150713D02*
X316094D01*
G01X318944Y151963D02*
X319777D01*
Y151213D01*
X319527Y150963D01*
X319236Y150796D01*
X318819Y150713D01*
X318402Y150796D01*
X318111Y150963D01*
X317861Y151213D01*
X317694Y151505D01*
X317611Y151838D01*
Y152130D01*
X317694Y152380D01*
X317861Y152671D01*
X318111Y152921D01*
X318361Y153088D01*
X318694Y153213D01*
X318986D01*
X319319Y153130D01*
X319569Y152963D01*
G01X321002Y151755D02*
X321294Y152046D01*
X321544Y152213D01*
X321877Y152296D01*
X322169Y152213D01*
X322377Y152046D01*
X322544Y151796D01*
X322586Y151505D01*
X322544Y151255D01*
X322377Y151005D01*
X322127Y150796D01*
X321836Y150713D01*
X321502Y150796D01*
X321211Y151046D01*
X321044Y151421D01*
X321002Y151838D01*
X321086Y152380D01*
X321211Y152671D01*
X321419Y152963D01*
X321711Y153171D01*
X322002Y153213D01*
X322294Y153130D01*
X322502Y152921D01*
G01X328830Y133166D02*
Y135666D01*
X329871D01*
X330205Y135541D01*
X330413Y135374D01*
X330496Y135041D01*
X330413Y134708D01*
X330163Y134499D01*
X329871Y134374D01*
X328830D01*
G01X329871D02*
X330496Y133166D01*
G01X332763D02*
Y135666D01*
X332263Y135166D01*
G01Y133166D02*
X333263D01*
G01X336113Y134416D02*
X336946D01*
Y133666D01*
X336696Y133416D01*
X336405Y133249D01*
X335988Y133166D01*
X335571Y133249D01*
X335280Y133416D01*
X335030Y133666D01*
X334863Y133958D01*
X334780Y134291D01*
Y134583D01*
X334863Y134833D01*
X335030Y135124D01*
X335280Y135374D01*
X335530Y135541D01*
X335863Y135666D01*
X336155D01*
X336488Y135583D01*
X336738Y135416D01*
G01X338963Y133166D02*
Y135666D01*
X338463Y135166D01*
G01Y133166D02*
X339463D01*
G01X341271Y135249D02*
X341521Y135499D01*
X341813Y135624D01*
X342146Y135666D01*
X342563Y135583D01*
X342855Y135374D01*
X342938Y135124D01*
X342896Y134874D01*
X342730Y134666D01*
X341896Y134249D01*
X341521Y133958D01*
X341271Y133541D01*
X341188Y133166D01*
X342938D01*
G01X298214Y136694D02*
X295714D01*
Y137735D01*
X295839Y138069D01*
X296006Y138277D01*
X296339Y138360D01*
X296672Y138277D01*
X296881Y138027D01*
X297006Y137735D01*
Y136694D01*
G01Y137735D02*
X298214Y138360D01*
G01Y140627D02*
X295714D01*
X296214Y140127D01*
G01X298214D02*
Y141127D01*
G01X296964Y143977D02*
Y144810D01*
X297714D01*
X297964Y144560D01*
X298131Y144269D01*
X298214Y143852D01*
X298131Y143435D01*
X297964Y143144D01*
X297714Y142894D01*
X297422Y142727D01*
X297089Y142644D01*
X296797D01*
X296547Y142727D01*
X296256Y142894D01*
X296006Y143144D01*
X295839Y143394D01*
X295714Y143727D01*
Y144019D01*
X295797Y144352D01*
X295964Y144602D01*
G01X298214Y146744D02*
X297672Y146827D01*
X297214Y146952D01*
X296797Y147119D01*
X296339Y147327D01*
X295714Y147660D01*
Y145994D01*
G01X310234Y136417D02*
X307734D01*
Y137458D01*
X307859Y137792D01*
X308026Y138000D01*
X308359Y138083D01*
X308692Y138000D01*
X308901Y137750D01*
X309026Y137458D01*
Y136417D01*
G01Y137458D02*
X310234Y138083D01*
G01Y140350D02*
X307734D01*
X308234Y139850D01*
G01X310234D02*
Y140850D01*
G01X308984Y143700D02*
Y144533D01*
X309734D01*
X309984Y144283D01*
X310151Y143992D01*
X310234Y143575D01*
X310151Y143158D01*
X309984Y142867D01*
X309734Y142617D01*
X309442Y142450D01*
X309109Y142367D01*
X308817D01*
X308567Y142450D01*
X308276Y142617D01*
X308026Y142867D01*
X307859Y143117D01*
X307734Y143450D01*
Y143742D01*
X307817Y144075D01*
X307984Y144325D01*
G01X310234Y146550D02*
X307734D01*
X308234Y146050D01*
G01X310234D02*
Y147050D01*
G01Y149650D02*
X307734D01*
X308234Y149150D01*
G01X310234D02*
Y150150D01*
G01X314034Y136267D02*
X311534D01*
Y137308D01*
X311659Y137642D01*
X311826Y137850D01*
X312159Y137933D01*
X312492Y137850D01*
X312701Y137600D01*
X312826Y137308D01*
Y136267D01*
G01Y137308D02*
X314034Y137933D01*
G01Y140200D02*
X311534D01*
X312034Y139700D01*
G01X314034D02*
Y140700D01*
G01X312784Y143550D02*
Y144383D01*
X313534D01*
X313784Y144133D01*
X313951Y143842D01*
X314034Y143425D01*
X313951Y143008D01*
X313784Y142717D01*
X313534Y142467D01*
X313242Y142300D01*
X312909Y142217D01*
X312617D01*
X312367Y142300D01*
X312076Y142467D01*
X311826Y142717D01*
X311659Y142967D01*
X311534Y143300D01*
Y143592D01*
X311617Y143925D01*
X311784Y144175D01*
G01X314034Y146400D02*
X313992Y146692D01*
X313867Y147025D01*
X313659Y147233D01*
X313367Y147317D01*
X313076Y147233D01*
X312826Y146983D01*
X312701Y146608D01*
Y146192D01*
X312617Y145942D01*
X312409Y145733D01*
X312117Y145650D01*
X311826Y145775D01*
X311617Y146067D01*
X311534Y146400D01*
X311617Y146733D01*
X311826Y147025D01*
X312117Y147150D01*
X312409Y147067D01*
X312617Y146858D01*
X312701Y146608D01*
Y146192D01*
X312826Y145817D01*
X313076Y145567D01*
X313367Y145483D01*
X313659Y145567D01*
X313867Y145775D01*
X313992Y146108D01*
X314034Y146400D01*
G01X306197Y136680D02*
X303697D01*
Y137721D01*
X303822Y138055D01*
X303989Y138263D01*
X304322Y138346D01*
X304655Y138263D01*
X304864Y138013D01*
X304989Y137721D01*
Y136680D01*
G01Y137721D02*
X306197Y138346D01*
G01Y140613D02*
X303697D01*
X304197Y140113D01*
G01X306197D02*
Y141113D01*
G01X304114Y142921D02*
X303864Y143171D01*
X303739Y143463D01*
X303697Y143796D01*
X303780Y144213D01*
X303989Y144505D01*
X304239Y144588D01*
X304489Y144546D01*
X304697Y144380D01*
X305114Y143546D01*
X305405Y143171D01*
X305822Y142921D01*
X306197Y142838D01*
Y144588D01*
G01X303697Y145563D02*
X306197Y146146D01*
X303697Y146813D01*
X306197Y147480D01*
X303697Y148063D01*
G01X305697Y148996D02*
X305989Y149246D01*
X306155Y149580D01*
X306197Y149955D01*
X306155Y150288D01*
X305947Y150621D01*
X305697Y150830D01*
X305447Y150871D01*
X305155Y150788D01*
X304947Y150496D01*
X304864Y150205D01*
Y149830D01*
G01Y150205D02*
X304739Y150455D01*
X304530Y150663D01*
X304280Y150746D01*
X304030Y150663D01*
X303822Y150455D01*
X303697Y150080D01*
X303739Y149705D01*
X303905Y149330D01*
G01X306197Y153013D02*
X303697D01*
X304197Y152513D01*
G01X306197D02*
Y153513D01*
G01X302286Y136513D02*
X299786D01*
Y137554D01*
X299911Y137888D01*
X300078Y138096D01*
X300411Y138179D01*
X300744Y138096D01*
X300953Y137846D01*
X301078Y137554D01*
Y136513D01*
G01Y137554D02*
X302286Y138179D01*
G01Y140446D02*
X299786D01*
X300286Y139946D01*
G01X302286D02*
Y140946D01*
G01X300203Y142754D02*
X299953Y143004D01*
X299828Y143296D01*
X299786Y143629D01*
X299869Y144046D01*
X300078Y144338D01*
X300328Y144421D01*
X300578Y144379D01*
X300786Y144213D01*
X301203Y143379D01*
X301494Y143004D01*
X301911Y142754D01*
X302286Y142671D01*
Y144421D01*
G01X299786Y145396D02*
X302286Y145979D01*
X299786Y146646D01*
X302286Y147313D01*
X299786Y147896D01*
G01X301786Y148829D02*
X302078Y149079D01*
X302244Y149413D01*
X302286Y149788D01*
X302244Y150121D01*
X302036Y150454D01*
X301786Y150663D01*
X301536Y150704D01*
X301244Y150621D01*
X301036Y150329D01*
X300953Y150038D01*
Y149663D01*
G01Y150038D02*
X300828Y150288D01*
X300619Y150496D01*
X300369Y150579D01*
X300119Y150496D01*
X299911Y150288D01*
X299786Y149913D01*
X299828Y149538D01*
X299994Y149163D01*
G01X300203Y152054D02*
X299953Y152304D01*
X299828Y152596D01*
X299786Y152929D01*
X299869Y153346D01*
X300078Y153638D01*
X300328Y153721D01*
X300578Y153679D01*
X300786Y153513D01*
X301203Y152679D01*
X301494Y152304D01*
X301911Y152054D01*
X302286Y151971D01*
Y153721D01*
G01X333330Y136599D02*
Y139099D01*
X334371D01*
X334705Y138974D01*
X334913Y138807D01*
X334996Y138474D01*
X334913Y138141D01*
X334663Y137932D01*
X334371Y137807D01*
X333330D01*
G01X334371D02*
X334996Y136599D01*
G01X337263D02*
Y139099D01*
X336763Y138599D01*
G01Y136599D02*
X337763D01*
G01X340613Y137849D02*
X341446D01*
Y137099D01*
X341196Y136849D01*
X340905Y136682D01*
X340488Y136599D01*
X340071Y136682D01*
X339780Y136849D01*
X339530Y137099D01*
X339363Y137391D01*
X339280Y137724D01*
Y138016D01*
X339363Y138266D01*
X339530Y138557D01*
X339780Y138807D01*
X340030Y138974D01*
X340363Y139099D01*
X340655D01*
X340988Y139016D01*
X341238Y138849D01*
G01X342671Y138682D02*
X342921Y138932D01*
X343213Y139057D01*
X343546Y139099D01*
X343963Y139016D01*
X344255Y138807D01*
X344338Y138557D01*
X344296Y138307D01*
X344130Y138099D01*
X343296Y137682D01*
X342921Y137391D01*
X342671Y136974D01*
X342588Y136599D01*
X344338D01*
G01X346563Y139099D02*
X346230Y139016D01*
X345980Y138807D01*
X345813Y138557D01*
X345688Y138224D01*
X345646Y137849D01*
X345688Y137474D01*
X345813Y137141D01*
X345980Y136891D01*
X346230Y136682D01*
X346563Y136599D01*
X346896Y136682D01*
X347146Y136891D01*
X347313Y137141D01*
X347438Y137474D01*
X347480Y137849D01*
X347438Y138224D01*
X347313Y138557D01*
X347146Y138807D01*
X346896Y139016D01*
X346563Y139099D01*
G01X347878Y123444D02*
X347753Y123194D01*
X347670Y122902D01*
Y122569D01*
X347795Y122194D01*
X348003Y121902D01*
X348253Y121694D01*
X348670Y121527D01*
X349045Y121485D01*
X349420Y121569D01*
X349670Y121694D01*
X349920Y121944D01*
X350087Y122235D01*
X350170Y122527D01*
Y122819D01*
X350087Y123110D01*
X349962Y123360D01*
X349795Y123569D01*
G01X350170Y125627D02*
X347670D01*
X348170Y125127D01*
G01X350170D02*
Y126127D01*
G01X348920Y128977D02*
Y129810D01*
X349670D01*
X349920Y129560D01*
X350087Y129269D01*
X350170Y128852D01*
X350087Y128435D01*
X349920Y128144D01*
X349670Y127894D01*
X349378Y127727D01*
X349045Y127644D01*
X348753D01*
X348503Y127727D01*
X348212Y127894D01*
X347962Y128144D01*
X347795Y128394D01*
X347670Y128727D01*
Y129019D01*
X347753Y129352D01*
X347920Y129602D01*
G01X350170Y131827D02*
X347670D01*
X348170Y131327D01*
G01X350170D02*
Y132327D01*
G01Y134927D02*
X350128Y135219D01*
X350003Y135552D01*
X349795Y135760D01*
X349503Y135844D01*
X349212Y135760D01*
X348962Y135510D01*
X348837Y135135D01*
Y134719D01*
X348753Y134469D01*
X348545Y134260D01*
X348253Y134177D01*
X347962Y134302D01*
X347753Y134594D01*
X347670Y134927D01*
X347753Y135260D01*
X347962Y135552D01*
X348253Y135677D01*
X348545Y135594D01*
X348753Y135385D01*
X348837Y135135D01*
Y134719D01*
X348962Y134344D01*
X349212Y134094D01*
X349503Y134010D01*
X349795Y134094D01*
X350003Y134302D01*
X350128Y134635D01*
X350170Y134927D01*
G01X317924Y139428D02*
X317674Y139553D01*
X317382Y139636D01*
X317049D01*
X316674Y139511D01*
X316382Y139303D01*
X316174Y139053D01*
X316007Y138636D01*
X315965Y138261D01*
X316049Y137886D01*
X316174Y137636D01*
X316424Y137386D01*
X316715Y137219D01*
X317007Y137136D01*
X317299D01*
X317590Y137219D01*
X317840Y137344D01*
X318049Y137511D01*
G01X320107Y137136D02*
Y139636D01*
X319607Y139136D01*
G01Y137136D02*
X320607D01*
G01X323457Y138386D02*
X324290D01*
Y137636D01*
X324040Y137386D01*
X323749Y137219D01*
X323332Y137136D01*
X322915Y137219D01*
X322624Y137386D01*
X322374Y137636D01*
X322207Y137928D01*
X322124Y138261D01*
Y138553D01*
X322207Y138803D01*
X322374Y139094D01*
X322624Y139344D01*
X322874Y139511D01*
X323207Y139636D01*
X323499D01*
X323832Y139553D01*
X324082Y139386D01*
G01X325515Y139219D02*
X325765Y139469D01*
X326057Y139594D01*
X326390Y139636D01*
X326807Y139553D01*
X327099Y139344D01*
X327182Y139094D01*
X327140Y138844D01*
X326974Y138636D01*
X326140Y138219D01*
X325765Y137928D01*
X325515Y137511D01*
X325432Y137136D01*
X327182D01*
G01X329407D02*
Y139636D01*
X328907Y139136D01*
G01Y137136D02*
X329907D01*
G01X318217Y126688D02*
X317967Y126813D01*
X317675Y126896D01*
X317342D01*
X316967Y126771D01*
X316675Y126563D01*
X316467Y126313D01*
X316300Y125896D01*
X316258Y125521D01*
X316342Y125146D01*
X316467Y124896D01*
X316717Y124646D01*
X317008Y124479D01*
X317300Y124396D01*
X317592D01*
X317883Y124479D01*
X318133Y124604D01*
X318342Y124771D01*
G01X320400Y124396D02*
Y126896D01*
X319900Y126396D01*
G01Y124396D02*
X320900D01*
G01X323750Y125646D02*
X324583D01*
Y124896D01*
X324333Y124646D01*
X324042Y124479D01*
X323625Y124396D01*
X323208Y124479D01*
X322917Y124646D01*
X322667Y124896D01*
X322500Y125188D01*
X322417Y125521D01*
Y125813D01*
X322500Y126063D01*
X322667Y126354D01*
X322917Y126604D01*
X323167Y126771D01*
X323500Y126896D01*
X323792D01*
X324125Y126813D01*
X324375Y126646D01*
G01X325808Y126479D02*
X326058Y126729D01*
X326350Y126854D01*
X326683Y126896D01*
X327100Y126813D01*
X327392Y126604D01*
X327475Y126354D01*
X327433Y126104D01*
X327267Y125896D01*
X326433Y125479D01*
X326058Y125188D01*
X325808Y124771D01*
X325725Y124396D01*
X327475D01*
G01X328783Y124896D02*
X329033Y124604D01*
X329367Y124438D01*
X329742Y124396D01*
X330075Y124438D01*
X330408Y124646D01*
X330617Y124896D01*
X330658Y125146D01*
X330575Y125438D01*
X330283Y125646D01*
X329992Y125729D01*
X329617D01*
G01X329992D02*
X330242Y125854D01*
X330450Y126063D01*
X330533Y126313D01*
X330450Y126563D01*
X330242Y126771D01*
X329867Y126896D01*
X329492Y126854D01*
X329117Y126688D01*
G01X318746Y131211D02*
X318496Y131336D01*
X318204Y131419D01*
X317871D01*
X317496Y131294D01*
X317204Y131086D01*
X316996Y130836D01*
X316829Y130419D01*
X316787Y130044D01*
X316871Y129669D01*
X316996Y129419D01*
X317246Y129169D01*
X317537Y129002D01*
X317829Y128919D01*
X318121D01*
X318412Y129002D01*
X318662Y129127D01*
X318871Y129294D01*
G01X320929Y128919D02*
Y131419D01*
X320429Y130919D01*
G01Y128919D02*
X321429D01*
G01X324279Y130169D02*
X325112D01*
Y129419D01*
X324862Y129169D01*
X324571Y129002D01*
X324154Y128919D01*
X323737Y129002D01*
X323446Y129169D01*
X323196Y129419D01*
X323029Y129711D01*
X322946Y130044D01*
Y130336D01*
X323029Y130586D01*
X323196Y130877D01*
X323446Y131127D01*
X323696Y131294D01*
X324029Y131419D01*
X324321D01*
X324654Y131336D01*
X324904Y131169D01*
G01X326337Y131002D02*
X326587Y131252D01*
X326879Y131377D01*
X327212Y131419D01*
X327629Y131336D01*
X327921Y131127D01*
X328004Y130877D01*
X327962Y130627D01*
X327796Y130419D01*
X326962Y130002D01*
X326587Y129711D01*
X326337Y129294D01*
X326254Y128919D01*
X328004D01*
G01X329437Y131002D02*
X329687Y131252D01*
X329979Y131377D01*
X330312Y131419D01*
X330729Y131336D01*
X331021Y131127D01*
X331104Y130877D01*
X331062Y130627D01*
X330896Y130419D01*
X330062Y130002D01*
X329687Y129711D01*
X329437Y129294D01*
X329354Y128919D01*
X331104D01*
G01X326493Y110258D02*
X326368Y110008D01*
X326285Y109716D01*
Y109383D01*
X326410Y109008D01*
X326618Y108716D01*
X326868Y108508D01*
X327285Y108341D01*
X327660Y108299D01*
X328035Y108383D01*
X328285Y108508D01*
X328535Y108758D01*
X328702Y109049D01*
X328785Y109341D01*
Y109633D01*
X328702Y109924D01*
X328577Y110174D01*
X328410Y110383D01*
G01X328785Y112441D02*
X326285D01*
X326785Y111941D01*
G01X328785D02*
Y112941D01*
G01X327535Y115791D02*
Y116624D01*
X328285D01*
X328535Y116374D01*
X328702Y116083D01*
X328785Y115666D01*
X328702Y115249D01*
X328535Y114958D01*
X328285Y114708D01*
X327993Y114541D01*
X327660Y114458D01*
X327368D01*
X327118Y114541D01*
X326827Y114708D01*
X326577Y114958D01*
X326410Y115208D01*
X326285Y115541D01*
Y115833D01*
X326368Y116166D01*
X326535Y116416D01*
G01X326702Y117849D02*
X326452Y118099D01*
X326327Y118391D01*
X326285Y118724D01*
X326368Y119141D01*
X326577Y119433D01*
X326827Y119516D01*
X327077Y119474D01*
X327285Y119308D01*
X327702Y118474D01*
X327993Y118099D01*
X328410Y117849D01*
X328785Y117766D01*
Y119516D01*
G01Y121658D02*
X328243Y121741D01*
X327785Y121866D01*
X327368Y122033D01*
X326910Y122241D01*
X326285Y122574D01*
Y120908D01*
G01X320293Y110270D02*
X320168Y110020D01*
X320085Y109728D01*
Y109395D01*
X320210Y109020D01*
X320418Y108728D01*
X320668Y108520D01*
X321085Y108353D01*
X321460Y108311D01*
X321835Y108395D01*
X322085Y108520D01*
X322335Y108770D01*
X322502Y109061D01*
X322585Y109353D01*
Y109645D01*
X322502Y109936D01*
X322377Y110186D01*
X322210Y110395D01*
G01X322585Y112453D02*
X320085D01*
X320585Y111953D01*
G01X322585D02*
Y112953D01*
G01X321335Y115803D02*
Y116636D01*
X322085D01*
X322335Y116386D01*
X322502Y116095D01*
X322585Y115678D01*
X322502Y115261D01*
X322335Y114970D01*
X322085Y114720D01*
X321793Y114553D01*
X321460Y114470D01*
X321168D01*
X320918Y114553D01*
X320627Y114720D01*
X320377Y114970D01*
X320210Y115220D01*
X320085Y115553D01*
Y115845D01*
X320168Y116178D01*
X320335Y116428D01*
G01X320502Y117861D02*
X320252Y118111D01*
X320127Y118403D01*
X320085Y118736D01*
X320168Y119153D01*
X320377Y119445D01*
X320627Y119528D01*
X320877Y119486D01*
X321085Y119320D01*
X321502Y118486D01*
X321793Y118111D01*
X322210Y117861D01*
X322585Y117778D01*
Y119528D01*
G01X322210Y120836D02*
X322418Y121086D01*
X322543Y121378D01*
X322585Y121753D01*
X322502Y122128D01*
X322335Y122420D01*
X322043Y122628D01*
X321710Y122670D01*
X321377Y122586D01*
X321168Y122378D01*
X321002Y122086D01*
X320960Y121795D01*
X321002Y121503D01*
X321168Y121128D01*
X320085Y121253D01*
Y122378D01*
G01X301831Y123406D02*
X301581Y123531D01*
X301289Y123614D01*
X300956D01*
X300581Y123489D01*
X300289Y123281D01*
X300081Y123031D01*
X299914Y122614D01*
X299872Y122239D01*
X299956Y121864D01*
X300081Y121614D01*
X300331Y121364D01*
X300622Y121197D01*
X300914Y121114D01*
X301206D01*
X301497Y121197D01*
X301747Y121322D01*
X301956Y121489D01*
G01X304014Y121114D02*
Y123614D01*
X303514Y123114D01*
G01Y121114D02*
X304514D01*
G01X306322Y123197D02*
X306572Y123447D01*
X306864Y123572D01*
X307197Y123614D01*
X307614Y123531D01*
X307906Y123322D01*
X307989Y123072D01*
X307947Y122822D01*
X307781Y122614D01*
X306947Y122197D01*
X306572Y121906D01*
X306322Y121489D01*
X306239Y121114D01*
X307989D01*
G01X308964Y123614D02*
X309547Y121114D01*
X310214Y123614D01*
X310881Y121114D01*
X311464Y123614D01*
G01X312397Y121614D02*
X312647Y121322D01*
X312981Y121156D01*
X313356Y121114D01*
X313689Y121156D01*
X314022Y121364D01*
X314231Y121614D01*
X314272Y121864D01*
X314189Y122156D01*
X313897Y122364D01*
X313606Y122447D01*
X313231D01*
G01X313606D02*
X313856Y122572D01*
X314064Y122781D01*
X314147Y123031D01*
X314064Y123281D01*
X313856Y123489D01*
X313481Y123614D01*
X313106Y123572D01*
X312731Y123406D01*
G01X299769Y117500D02*
Y120000D01*
X300810D01*
X301144Y119875D01*
X301352Y119708D01*
X301435Y119375D01*
X301352Y119042D01*
X301102Y118833D01*
X300810Y118708D01*
X299769D01*
G01X300810D02*
X301435Y117500D01*
G01X303702D02*
Y120000D01*
X303202Y119500D01*
G01Y117500D02*
X304202D01*
G01X306010Y119583D02*
X306260Y119833D01*
X306552Y119958D01*
X306885Y120000D01*
X307302Y119917D01*
X307594Y119708D01*
X307677Y119458D01*
X307635Y119208D01*
X307469Y119000D01*
X306635Y118583D01*
X306260Y118292D01*
X306010Y117875D01*
X305927Y117500D01*
X307677D01*
G01X308652Y120000D02*
X309235Y117500D01*
X309902Y120000D01*
X310569Y117500D01*
X311152Y120000D01*
G01X313002Y117500D02*
Y120000D01*
X312502Y119500D01*
G01Y117500D02*
X313502D01*
G01X315185Y117875D02*
X315435Y117667D01*
X315727Y117542D01*
X316102Y117500D01*
X316477Y117583D01*
X316769Y117750D01*
X316977Y118042D01*
X317019Y118375D01*
X316935Y118708D01*
X316727Y118917D01*
X316435Y119083D01*
X316144Y119125D01*
X315852Y119083D01*
X315477Y118917D01*
X315602Y120000D01*
X316727D01*
G01X298360Y179056D02*
X298283Y178384D01*
X298168Y177816D01*
X298015Y177299D01*
X297823Y176731D01*
X297516Y175956D01*
X299050D01*
G01X295835Y178694D02*
X295566Y178953D01*
X295260Y179056D01*
X294953Y178953D01*
X294685Y178643D01*
X294493Y178178D01*
X294416Y177713D01*
Y177144D01*
X294493Y176679D01*
X294685Y176266D01*
X294915Y176059D01*
X295183Y175956D01*
X295490Y176059D01*
X295720Y176266D01*
X295873Y176576D01*
X295950Y176989D01*
X295873Y177351D01*
X295681Y177713D01*
X295451Y177919D01*
X295183Y177971D01*
X294876Y177868D01*
X294646Y177609D01*
X294416Y177144D01*
G01X301805Y175353D02*
X301728Y174681D01*
X301613Y174113D01*
X301460Y173596D01*
X301268Y173028D01*
X300961Y172253D01*
X302495D01*
G01X298628Y175353D02*
X298360Y175301D01*
X298053Y175146D01*
X297861Y174888D01*
X297785Y174526D01*
X297861Y174165D01*
X298091Y173855D01*
X298436Y173700D01*
X298820D01*
X299050Y173596D01*
X299241Y173338D01*
X299318Y172976D01*
X299203Y172615D01*
X298935Y172356D01*
X298628Y172253D01*
X298321Y172356D01*
X298053Y172615D01*
X297938Y172976D01*
X298015Y173338D01*
X298206Y173596D01*
X298436Y173700D01*
X298820D01*
X299165Y173855D01*
X299395Y174165D01*
X299471Y174526D01*
X299395Y174888D01*
X299203Y175146D01*
X298896Y175301D01*
X298628Y175353D01*
G01X305119Y179056D02*
X305042Y178384D01*
X304927Y177816D01*
X304774Y177299D01*
X304582Y176731D01*
X304275Y175956D01*
X305809D01*
G01X302019Y179056D02*
X301942Y178384D01*
X301827Y177816D01*
X301674Y177299D01*
X301482Y176731D01*
X301175Y175956D01*
X302709D01*
G01X308565Y175353D02*
X308488Y174681D01*
X308373Y174113D01*
X308220Y173596D01*
X308028Y173028D01*
X307721Y172253D01*
X309255D01*
G01X306116Y174061D02*
X305848Y173700D01*
X305618Y173493D01*
X305311Y173390D01*
X305043Y173493D01*
X304851Y173700D01*
X304698Y174010D01*
X304660Y174371D01*
X304698Y174681D01*
X304851Y174991D01*
X305081Y175250D01*
X305350Y175353D01*
X305656Y175250D01*
X305925Y174940D01*
X306078Y174475D01*
X306116Y173958D01*
X306040Y173286D01*
X305925Y172925D01*
X305733Y172563D01*
X305465Y172305D01*
X305196Y172253D01*
X304928Y172356D01*
X304736Y172615D01*
G01X311879Y179056D02*
X311802Y178384D01*
X311687Y177816D01*
X311534Y177299D01*
X311342Y176731D01*
X311035Y175956D01*
X312569D01*
G01X309545Y178591D02*
X309315Y178849D01*
X309047Y179004D01*
X308702Y179056D01*
X308357Y178953D01*
X308089Y178746D01*
X307897Y178384D01*
X307859Y177971D01*
X307935Y177558D01*
X308127Y177299D01*
X308395Y177093D01*
X308664Y177041D01*
X308932Y177093D01*
X309277Y177299D01*
X309162Y175956D01*
X308127D01*
G01X315325Y175353D02*
X315248Y174681D01*
X315133Y174113D01*
X314980Y173596D01*
X314788Y173028D01*
X314481Y172253D01*
X316015D01*
G01X311688Y175353D02*
Y172253D01*
X313106Y174475D01*
X311190D01*
G01X318639Y179056D02*
X318562Y178384D01*
X318447Y177816D01*
X318294Y177299D01*
X318102Y176731D01*
X317795Y175956D01*
X319329D01*
G01X316305Y178436D02*
X316075Y178798D01*
X315769Y179004D01*
X315424Y179056D01*
X315117Y179004D01*
X314810Y178746D01*
X314619Y178436D01*
X314580Y178126D01*
X314657Y177764D01*
X314925Y177506D01*
X315194Y177403D01*
X315539D01*
G01X315194D02*
X314964Y177248D01*
X314772Y176989D01*
X314695Y176679D01*
X314772Y176369D01*
X314964Y176111D01*
X315309Y175956D01*
X315654Y176008D01*
X315999Y176214D01*
G01X322084Y175353D02*
X322007Y174681D01*
X321892Y174113D01*
X321739Y173596D01*
X321547Y173028D01*
X321240Y172253D01*
X322774D01*
G01X319635Y172770D02*
X319405Y172460D01*
X319137Y172305D01*
X318830Y172253D01*
X318447Y172356D01*
X318179Y172615D01*
X318102Y172925D01*
X318140Y173235D01*
X318294Y173493D01*
X319060Y174010D01*
X319405Y174371D01*
X319635Y174888D01*
X319712Y175353D01*
X318102D01*
G01X325399Y179056D02*
X325322Y178384D01*
X325207Y177816D01*
X325054Y177299D01*
X324862Y176731D01*
X324555Y175956D01*
X326089D01*
G01X322222Y179056D02*
Y175956D01*
X322682Y176576D01*
G01Y179056D02*
X321762D01*
G01X328844Y175353D02*
X328767Y174681D01*
X328652Y174113D01*
X328499Y173596D01*
X328307Y173028D01*
X328000Y172253D01*
X329534D01*
G01X325667D02*
X325974Y172356D01*
X326204Y172615D01*
X326357Y172925D01*
X326472Y173338D01*
X326510Y173803D01*
X326472Y174268D01*
X326357Y174681D01*
X326204Y174991D01*
X325974Y175250D01*
X325667Y175353D01*
X325360Y175250D01*
X325130Y174991D01*
X324977Y174681D01*
X324862Y174268D01*
X324824Y173803D01*
X324862Y173338D01*
X324977Y172925D01*
X325130Y172615D01*
X325360Y172356D01*
X325667Y172253D01*
G01X332810Y177764D02*
X332542Y177403D01*
X332312Y177196D01*
X332005Y177093D01*
X331737Y177196D01*
X331545Y177403D01*
X331392Y177713D01*
X331354Y178074D01*
X331392Y178384D01*
X331545Y178694D01*
X331775Y178953D01*
X332044Y179056D01*
X332350Y178953D01*
X332619Y178643D01*
X332772Y178178D01*
X332810Y177661D01*
X332734Y176989D01*
X332619Y176628D01*
X332427Y176266D01*
X332159Y176008D01*
X331890Y175956D01*
X331622Y176059D01*
X331430Y176318D01*
G01X329634Y178694D02*
X329365Y178953D01*
X329059Y179056D01*
X328752Y178953D01*
X328484Y178643D01*
X328292Y178178D01*
X328215Y177713D01*
Y177144D01*
X328292Y176679D01*
X328484Y176266D01*
X328714Y176059D01*
X328982Y175956D01*
X329289Y176059D01*
X329519Y176266D01*
X329672Y176576D01*
X329749Y176989D01*
X329672Y177351D01*
X329480Y177713D01*
X329250Y177919D01*
X328982Y177971D01*
X328675Y177868D01*
X328445Y177609D01*
X328215Y177144D01*
G01X336255Y174061D02*
X335987Y173700D01*
X335757Y173493D01*
X335450Y173390D01*
X335182Y173493D01*
X334990Y173700D01*
X334837Y174010D01*
X334799Y174371D01*
X334837Y174681D01*
X334990Y174991D01*
X335220Y175250D01*
X335489Y175353D01*
X335795Y175250D01*
X336064Y174940D01*
X336217Y174475D01*
X336255Y173958D01*
X336179Y173286D01*
X336064Y172925D01*
X335872Y172563D01*
X335604Y172305D01*
X335335Y172253D01*
X335067Y172356D01*
X334875Y172615D01*
G01X332427Y175353D02*
X332159Y175301D01*
X331852Y175146D01*
X331660Y174888D01*
X331584Y174526D01*
X331660Y174165D01*
X331890Y173855D01*
X332235Y173700D01*
X332619D01*
X332849Y173596D01*
X333040Y173338D01*
X333117Y172976D01*
X333002Y172615D01*
X332734Y172356D01*
X332427Y172253D01*
X332120Y172356D01*
X331852Y172615D01*
X331737Y172976D01*
X331814Y173338D01*
X332005Y173596D01*
X332235Y173700D01*
X332619D01*
X332964Y173855D01*
X333194Y174165D01*
X333270Y174526D01*
X333194Y174888D01*
X333002Y175146D01*
X332695Y175301D01*
X332427Y175353D01*
G01X339570Y177764D02*
X339302Y177403D01*
X339072Y177196D01*
X338765Y177093D01*
X338497Y177196D01*
X338305Y177403D01*
X338152Y177713D01*
X338114Y178074D01*
X338152Y178384D01*
X338305Y178694D01*
X338535Y178953D01*
X338804Y179056D01*
X339110Y178953D01*
X339379Y178643D01*
X339532Y178178D01*
X339570Y177661D01*
X339494Y176989D01*
X339379Y176628D01*
X339187Y176266D01*
X338919Y176008D01*
X338650Y175956D01*
X338382Y176059D01*
X338190Y176318D01*
G01X335819Y179056D02*
X335742Y178384D01*
X335627Y177816D01*
X335474Y177299D01*
X335282Y176731D01*
X334975Y175956D01*
X336509D01*
G01X343015Y174061D02*
X342747Y173700D01*
X342517Y173493D01*
X342210Y173390D01*
X341942Y173493D01*
X341750Y173700D01*
X341597Y174010D01*
X341559Y174371D01*
X341597Y174681D01*
X341750Y174991D01*
X341980Y175250D01*
X342249Y175353D01*
X342555Y175250D01*
X342824Y174940D01*
X342977Y174475D01*
X343015Y173958D01*
X342939Y173286D01*
X342824Y172925D01*
X342632Y172563D01*
X342364Y172305D01*
X342095Y172253D01*
X341827Y172356D01*
X341635Y172615D01*
G01X339915Y174061D02*
X339647Y173700D01*
X339417Y173493D01*
X339110Y173390D01*
X338842Y173493D01*
X338650Y173700D01*
X338497Y174010D01*
X338459Y174371D01*
X338497Y174681D01*
X338650Y174991D01*
X338880Y175250D01*
X339149Y175353D01*
X339455Y175250D01*
X339724Y174940D01*
X339877Y174475D01*
X339915Y173958D01*
X339839Y173286D01*
X339724Y172925D01*
X339532Y172563D01*
X339264Y172305D01*
X338995Y172253D01*
X338727Y172356D01*
X338535Y172615D01*
G01X346330Y177764D02*
X346062Y177403D01*
X345832Y177196D01*
X345525Y177093D01*
X345257Y177196D01*
X345065Y177403D01*
X344912Y177713D01*
X344874Y178074D01*
X344912Y178384D01*
X345065Y178694D01*
X345295Y178953D01*
X345564Y179056D01*
X345870Y178953D01*
X346139Y178643D01*
X346292Y178178D01*
X346330Y177661D01*
X346254Y176989D01*
X346139Y176628D01*
X345947Y176266D01*
X345679Y176008D01*
X345410Y175956D01*
X345142Y176059D01*
X344950Y176318D01*
G01X343345Y178591D02*
X343115Y178849D01*
X342847Y179004D01*
X342502Y179056D01*
X342157Y178953D01*
X341889Y178746D01*
X341697Y178384D01*
X341659Y177971D01*
X341735Y177558D01*
X341927Y177299D01*
X342195Y177093D01*
X342464Y177041D01*
X342732Y177093D01*
X343077Y177299D01*
X342962Y175956D01*
X341927D01*
G01X349775Y174061D02*
X349507Y173700D01*
X349277Y173493D01*
X348970Y173390D01*
X348702Y173493D01*
X348510Y173700D01*
X348357Y174010D01*
X348319Y174371D01*
X348357Y174681D01*
X348510Y174991D01*
X348740Y175250D01*
X349009Y175353D01*
X349315Y175250D01*
X349584Y174940D01*
X349737Y174475D01*
X349775Y173958D01*
X349699Y173286D01*
X349584Y172925D01*
X349392Y172563D01*
X349124Y172305D01*
X348855Y172253D01*
X348587Y172356D01*
X348395Y172615D01*
G01X345487Y175353D02*
Y172253D01*
X346905Y174475D01*
X344989D01*
G01X353089Y177764D02*
X352821Y177403D01*
X352591Y177196D01*
X352284Y177093D01*
X352016Y177196D01*
X351824Y177403D01*
X351671Y177713D01*
X351633Y178074D01*
X351671Y178384D01*
X351824Y178694D01*
X352054Y178953D01*
X352323Y179056D01*
X352629Y178953D01*
X352898Y178643D01*
X353051Y178178D01*
X353089Y177661D01*
X353013Y176989D01*
X352898Y176628D01*
X352706Y176266D01*
X352438Y176008D01*
X352169Y175956D01*
X351901Y176059D01*
X351709Y176318D01*
G01X350104Y178436D02*
X349874Y178798D01*
X349568Y179004D01*
X349223Y179056D01*
X348916Y179004D01*
X348609Y178746D01*
X348418Y178436D01*
X348379Y178126D01*
X348456Y177764D01*
X348724Y177506D01*
X348993Y177403D01*
X349338D01*
G01X348993D02*
X348763Y177248D01*
X348571Y176989D01*
X348494Y176679D01*
X348571Y176369D01*
X348763Y176111D01*
X349108Y175956D01*
X349453Y176008D01*
X349798Y176214D01*
G01X356535Y174061D02*
X356267Y173700D01*
X356037Y173493D01*
X355730Y173390D01*
X355462Y173493D01*
X355270Y173700D01*
X355117Y174010D01*
X355079Y174371D01*
X355117Y174681D01*
X355270Y174991D01*
X355500Y175250D01*
X355769Y175353D01*
X356075Y175250D01*
X356344Y174940D01*
X356497Y174475D01*
X356535Y173958D01*
X356459Y173286D01*
X356344Y172925D01*
X356152Y172563D01*
X355884Y172305D01*
X355615Y172253D01*
X355347Y172356D01*
X355155Y172615D01*
G01X353435Y172770D02*
X353205Y172460D01*
X352937Y172305D01*
X352630Y172253D01*
X352247Y172356D01*
X351979Y172615D01*
X351902Y172925D01*
X351940Y173235D01*
X352094Y173493D01*
X352860Y174010D01*
X353205Y174371D01*
X353435Y174888D01*
X353512Y175353D01*
X351902D01*
G01X306234Y491984D02*
X305984Y492109D01*
X305692Y492192D01*
X305359D01*
X304984Y492067D01*
X304692Y491859D01*
X304484Y491609D01*
X304317Y491192D01*
X304275Y490817D01*
X304359Y490442D01*
X304484Y490192D01*
X304734Y489942D01*
X305025Y489775D01*
X305317Y489692D01*
X305609D01*
X305900Y489775D01*
X306150Y489900D01*
X306359Y490067D01*
G01X307625Y491775D02*
X307875Y492025D01*
X308167Y492150D01*
X308500Y492192D01*
X308917Y492109D01*
X309209Y491900D01*
X309292Y491650D01*
X309250Y491400D01*
X309084Y491192D01*
X308250Y490775D01*
X307875Y490484D01*
X307625Y490067D01*
X307542Y489692D01*
X309292D01*
G01X311850Y491025D02*
X312017Y491150D01*
X312142Y491359D01*
X312225Y491650D01*
X312142Y491900D01*
X311975Y492067D01*
X311684Y492192D01*
X310559D01*
Y489692D01*
X311934D01*
X312225Y489859D01*
X312392Y490109D01*
X312475Y490400D01*
X312392Y490692D01*
X312142Y490942D01*
X311850Y491025D01*
X310559D01*
G01X313825Y491775D02*
X314075Y492025D01*
X314367Y492150D01*
X314700Y492192D01*
X315117Y492109D01*
X315409Y491900D01*
X315492Y491650D01*
X315450Y491400D01*
X315284Y491192D01*
X314450Y490775D01*
X314075Y490484D01*
X313825Y490067D01*
X313742Y489692D01*
X315492D01*
G01X304880Y586165D02*
X304755Y585915D01*
X304672Y585623D01*
Y585290D01*
X304797Y584915D01*
X305005Y584623D01*
X305255Y584415D01*
X305672Y584248D01*
X306047Y584206D01*
X306422Y584290D01*
X306672Y584415D01*
X306922Y584665D01*
X307089Y584956D01*
X307172Y585248D01*
Y585540D01*
X307089Y585831D01*
X306964Y586081D01*
X306797Y586290D01*
G01X305089Y587556D02*
X304839Y587806D01*
X304714Y588098D01*
X304672Y588431D01*
X304755Y588848D01*
X304964Y589140D01*
X305214Y589223D01*
X305464Y589181D01*
X305672Y589015D01*
X306089Y588181D01*
X306380Y587806D01*
X306797Y587556D01*
X307172Y587473D01*
Y589223D01*
G01Y590406D02*
X304672Y591448D01*
X307172Y592490D01*
G01X306297Y592115D02*
Y590781D01*
G01X307172Y594548D02*
X307130Y594840D01*
X307005Y595173D01*
X306797Y595381D01*
X306505Y595465D01*
X306214Y595381D01*
X305964Y595131D01*
X305839Y594756D01*
Y594340D01*
X305755Y594090D01*
X305547Y593881D01*
X305255Y593798D01*
X304964Y593923D01*
X304755Y594215D01*
X304672Y594548D01*
X304755Y594881D01*
X304964Y595173D01*
X305255Y595298D01*
X305547Y595215D01*
X305755Y595006D01*
X305839Y594756D01*
Y594340D01*
X305964Y593965D01*
X306214Y593715D01*
X306505Y593631D01*
X306797Y593715D01*
X307005Y593923D01*
X307130Y594256D01*
X307172Y594548D01*
G01X299718Y586071D02*
X299593Y585821D01*
X299510Y585529D01*
Y585196D01*
X299635Y584821D01*
X299843Y584529D01*
X300093Y584321D01*
X300510Y584154D01*
X300885Y584112D01*
X301260Y584196D01*
X301510Y584321D01*
X301760Y584571D01*
X301927Y584862D01*
X302010Y585154D01*
Y585446D01*
X301927Y585737D01*
X301802Y585987D01*
X301635Y586196D01*
G01X299927Y587462D02*
X299677Y587712D01*
X299552Y588004D01*
X299510Y588337D01*
X299593Y588754D01*
X299802Y589046D01*
X300052Y589129D01*
X300302Y589087D01*
X300510Y588921D01*
X300927Y588087D01*
X301218Y587712D01*
X301635Y587462D01*
X302010Y587379D01*
Y589129D01*
G01Y590312D02*
X299510Y591354D01*
X302010Y592396D01*
G01X301135Y592021D02*
Y590687D01*
G01X301635Y593537D02*
X301843Y593787D01*
X301968Y594079D01*
X302010Y594454D01*
X301927Y594829D01*
X301760Y595121D01*
X301468Y595329D01*
X301135Y595371D01*
X300802Y595287D01*
X300593Y595079D01*
X300427Y594787D01*
X300385Y594496D01*
X300427Y594204D01*
X300593Y593829D01*
X299510Y593954D01*
Y595079D01*
G01X297007Y553414D02*
X296757Y553539D01*
X296465Y553622D01*
X296132D01*
X295757Y553497D01*
X295465Y553289D01*
X295257Y553039D01*
X295090Y552622D01*
X295048Y552247D01*
X295132Y551872D01*
X295257Y551622D01*
X295507Y551372D01*
X295798Y551205D01*
X296090Y551122D01*
X296382D01*
X296673Y551205D01*
X296923Y551330D01*
X297132Y551497D01*
G01X298398Y553205D02*
X298648Y553455D01*
X298940Y553580D01*
X299273Y553622D01*
X299690Y553539D01*
X299982Y553330D01*
X300065Y553080D01*
X300023Y552830D01*
X299857Y552622D01*
X299023Y552205D01*
X298648Y551914D01*
X298398Y551497D01*
X298315Y551122D01*
X300065D01*
G01X301248D02*
X302290Y553622D01*
X303332Y551122D01*
G01X302957Y551997D02*
X301623D01*
G01X305390Y551122D02*
Y553622D01*
X304890Y553122D01*
G01Y551122D02*
X305890D01*
G01X307573Y551622D02*
X307823Y551330D01*
X308157Y551164D01*
X308532Y551122D01*
X308865Y551164D01*
X309198Y551372D01*
X309407Y551622D01*
X309448Y551872D01*
X309365Y552164D01*
X309073Y552372D01*
X308782Y552455D01*
X308407D01*
G01X308782D02*
X309032Y552580D01*
X309240Y552789D01*
X309323Y553039D01*
X309240Y553289D01*
X309032Y553497D01*
X308657Y553622D01*
X308282Y553580D01*
X307907Y553414D01*
G01X295396Y586133D02*
X295271Y585883D01*
X295188Y585591D01*
Y585258D01*
X295313Y584883D01*
X295521Y584591D01*
X295771Y584383D01*
X296188Y584216D01*
X296563Y584174D01*
X296938Y584258D01*
X297188Y584383D01*
X297438Y584633D01*
X297605Y584924D01*
X297688Y585216D01*
Y585508D01*
X297605Y585799D01*
X297480Y586049D01*
X297313Y586258D01*
G01X295605Y587524D02*
X295355Y587774D01*
X295230Y588066D01*
X295188Y588399D01*
X295271Y588816D01*
X295480Y589108D01*
X295730Y589191D01*
X295980Y589149D01*
X296188Y588983D01*
X296605Y588149D01*
X296896Y587774D01*
X297313Y587524D01*
X297688Y587441D01*
Y589191D01*
G01Y590374D02*
X295188Y591416D01*
X297688Y592458D01*
G01X296813Y592083D02*
Y590749D01*
G01X297688Y595016D02*
X295188D01*
X296980Y593474D01*
Y595558D01*
G01X300400Y658000D02*
Y661000D01*
X301400D01*
X301800Y660850D01*
X302100Y660650D01*
X302350Y660350D01*
X302550Y660000D01*
X302600Y659500D01*
X302550Y659000D01*
X302350Y658650D01*
X302100Y658350D01*
X301800Y658150D01*
X301400Y658000D01*
X300400D01*
G01X304350Y659350D02*
X305950D01*
X305800Y659700D01*
X305550Y659900D01*
X305200Y660000D01*
X304850Y659950D01*
X304550Y659800D01*
X304350Y659450D01*
X304250Y659150D01*
Y658850D01*
X304350Y658550D01*
X304600Y658250D01*
X304900Y658050D01*
X305250Y658000D01*
X305600Y658100D01*
X305950Y658400D01*
G01X308700Y658000D02*
Y661000D01*
G01X312300D02*
Y658000D01*
G01X311600Y660000D02*
X313000D01*
G01X316800Y658000D02*
Y660000D01*
G01Y659650D02*
X316600Y659850D01*
X316300Y659950D01*
X315950Y660000D01*
X315600Y659900D01*
X315300Y659700D01*
X315100Y659400D01*
X315000Y659000D01*
X315100Y658600D01*
X315300Y658300D01*
X315600Y658100D01*
X315950Y658000D01*
X316300Y658050D01*
X316600Y658200D01*
X316800Y658400D01*
G01X318000Y657000D02*
X321000D01*
G01X322100Y661000D02*
Y658000D01*
X324100D01*
G01X326700D02*
Y661000D01*
X326100Y660400D01*
G01Y658000D02*
X327300D01*
G01X329350Y660500D02*
X329650Y660800D01*
X330000Y660950D01*
X330400Y661000D01*
X330900Y660900D01*
X331250Y660650D01*
X331350Y660350D01*
X331300Y660050D01*
X331100Y659800D01*
X330100Y659300D01*
X329650Y658950D01*
X329350Y658450D01*
X329250Y658000D01*
X331350D01*
G01X332400Y657000D02*
X335400D01*
G01X336400Y658450D02*
X336700Y658200D01*
X337050Y658050D01*
X337500Y658000D01*
X337950Y658100D01*
X338300Y658300D01*
X338550Y658650D01*
X338600Y659050D01*
X338500Y659450D01*
X338250Y659700D01*
X337900Y659900D01*
X337550Y659950D01*
X337200Y659900D01*
X336750Y659700D01*
X336900Y661000D01*
X338250D01*
G01X341100Y660000D02*
Y658000D01*
G01Y660800D02*
X341000Y660850D01*
Y660950D01*
X341100Y661000D01*
X341200Y660950D01*
Y660850D01*
X341100Y660800D01*
G01X343850Y658000D02*
Y660000D01*
G01Y659500D02*
X344050Y659750D01*
X344350Y659950D01*
X344750Y660000D01*
X345100Y659950D01*
X345400Y659750D01*
X345550Y659400D01*
Y658000D01*
G01X349100Y659750D02*
X348750Y659950D01*
X348450Y660000D01*
X348050Y659900D01*
X347750Y659700D01*
X347550Y659350D01*
X347500Y659000D01*
X347550Y658650D01*
X347750Y658350D01*
X348050Y658100D01*
X348450Y658000D01*
X348800Y658100D01*
X349100Y658300D01*
G01X351050Y658000D02*
Y661000D01*
G01Y659550D02*
X351300Y659800D01*
X351550Y659950D01*
X351950Y660000D01*
X352250Y659950D01*
X352600Y659750D01*
X352750Y659450D01*
Y658000D01*
G01X392373Y-22900D02*
X392450Y-22228D01*
X392565Y-21660D01*
X392718Y-21143D01*
X392910Y-20575D01*
X393217Y-19800D01*
X391683D01*
G01X395550Y-22900D02*
X395818Y-22848D01*
X396125Y-22693D01*
X396317Y-22435D01*
X396393Y-22073D01*
X396317Y-21712D01*
X396087Y-21402D01*
X395742Y-21247D01*
X395358D01*
X395128Y-21143D01*
X394937Y-20885D01*
X394860Y-20523D01*
X394975Y-20162D01*
X395243Y-19903D01*
X395550Y-19800D01*
X395857Y-19903D01*
X396125Y-20162D01*
X396240Y-20523D01*
X396163Y-20885D01*
X395972Y-21143D01*
X395742Y-21247D01*
X395358D01*
X395013Y-21402D01*
X394783Y-21712D01*
X394707Y-22073D01*
X394783Y-22435D01*
X394975Y-22693D01*
X395282Y-22848D01*
X395550Y-22900D01*
G01X374860Y-22693D02*
X374937Y-22021D01*
X375052Y-21453D01*
X375205Y-20936D01*
X375397Y-20368D01*
X375704Y-19593D01*
X374170D01*
G01X377960Y-22693D02*
X378037Y-22021D01*
X378152Y-21453D01*
X378305Y-20936D01*
X378497Y-20368D01*
X378804Y-19593D01*
X377270D01*
G01X393812Y10163D02*
X394042Y10473D01*
X394310Y10628D01*
X394617Y10680D01*
X395000Y10577D01*
X395268Y10318D01*
X395345Y10008D01*
X395307Y9698D01*
X395153Y9440D01*
X394387Y8923D01*
X394042Y8562D01*
X393812Y8045D01*
X393735Y7580D01*
X395345D01*
G01X396912Y10163D02*
X397142Y10473D01*
X397410Y10628D01*
X397717Y10680D01*
X398100Y10577D01*
X398368Y10318D01*
X398445Y10008D01*
X398407Y9698D01*
X398253Y9440D01*
X397487Y8923D01*
X397142Y8562D01*
X396912Y8045D01*
X396835Y7580D01*
X398445D01*
G01X400012Y10163D02*
X400242Y10473D01*
X400510Y10628D01*
X400817Y10680D01*
X401200Y10577D01*
X401468Y10318D01*
X401545Y10008D01*
X401507Y9698D01*
X401353Y9440D01*
X400587Y8923D01*
X400242Y8562D01*
X400012Y8045D01*
X399935Y7580D01*
X401545D01*
G01X373249Y8584D02*
X373479Y8894D01*
X373747Y9049D01*
X374054Y9101D01*
X374437Y8998D01*
X374705Y8739D01*
X374782Y8429D01*
X374744Y8119D01*
X374590Y7861D01*
X373824Y7344D01*
X373479Y6983D01*
X373249Y6466D01*
X373172Y6001D01*
X374782D01*
G01X376349Y8584D02*
X376579Y8894D01*
X376847Y9049D01*
X377154Y9101D01*
X377537Y8998D01*
X377805Y8739D01*
X377882Y8429D01*
X377844Y8119D01*
X377690Y7861D01*
X376924Y7344D01*
X376579Y6983D01*
X376349Y6466D01*
X376272Y6001D01*
X377882D01*
G01X380177D02*
Y9101D01*
X379717Y8481D01*
G01Y6001D02*
X380637D01*
G01X392621Y13493D02*
X392698Y14165D01*
X392813Y14733D01*
X392966Y15250D01*
X393158Y15818D01*
X393465Y16593D01*
X391931D01*
G01X395798Y13493D02*
X396066Y13545D01*
X396373Y13700D01*
X396565Y13958D01*
X396641Y14320D01*
X396565Y14681D01*
X396335Y14991D01*
X395990Y15146D01*
X395606D01*
X395376Y15250D01*
X395185Y15508D01*
X395108Y15870D01*
X395223Y16231D01*
X395491Y16490D01*
X395798Y16593D01*
X396105Y16490D01*
X396373Y16231D01*
X396488Y15870D01*
X396411Y15508D01*
X396220Y15250D01*
X395990Y15146D01*
X395606D01*
X395261Y14991D01*
X395031Y14681D01*
X394955Y14320D01*
X395031Y13958D01*
X395223Y13700D01*
X395530Y13545D01*
X395798Y13493D01*
G01X376873Y17200D02*
X376950Y17872D01*
X377065Y18440D01*
X377218Y18957D01*
X377410Y19525D01*
X377717Y20300D01*
X376183D01*
G01X379973Y17200D02*
X380050Y17872D01*
X380165Y18440D01*
X380318Y18957D01*
X380510Y19525D01*
X380817Y20300D01*
X379283D01*
G01X393133Y53000D02*
X393210Y53672D01*
X393325Y54240D01*
X393478Y54757D01*
X393670Y55325D01*
X393977Y56100D01*
X392443D01*
G01X396310Y53000D02*
X396578Y53052D01*
X396885Y53207D01*
X397077Y53465D01*
X397153Y53827D01*
X397077Y54188D01*
X396847Y54498D01*
X396502Y54653D01*
X396118D01*
X395888Y54757D01*
X395697Y55015D01*
X395620Y55377D01*
X395735Y55738D01*
X396003Y55997D01*
X396310Y56100D01*
X396617Y55997D01*
X396885Y55738D01*
X397000Y55377D01*
X396923Y55015D01*
X396732Y54757D01*
X396502Y54653D01*
X396118D01*
X395773Y54498D01*
X395543Y54188D01*
X395467Y53827D01*
X395543Y53465D01*
X395735Y53207D01*
X396042Y53052D01*
X396310Y53000D01*
G01X373623Y55280D02*
X373700Y55952D01*
X373815Y56520D01*
X373968Y57037D01*
X374160Y57605D01*
X374467Y58380D01*
X372933D01*
G01X376723Y55280D02*
X376800Y55952D01*
X376915Y56520D01*
X377068Y57037D01*
X377260Y57605D01*
X377567Y58380D01*
X376033D01*
G01X392632Y88343D02*
X392862Y88653D01*
X393130Y88808D01*
X393437Y88860D01*
X393820Y88757D01*
X394088Y88498D01*
X394165Y88188D01*
X394127Y87878D01*
X393973Y87620D01*
X393207Y87103D01*
X392862Y86742D01*
X392632Y86225D01*
X392555Y85760D01*
X394165D01*
G01X395732Y88343D02*
X395962Y88653D01*
X396230Y88808D01*
X396537Y88860D01*
X396920Y88757D01*
X397188Y88498D01*
X397265Y88188D01*
X397227Y87878D01*
X397073Y87620D01*
X396307Y87103D01*
X395962Y86742D01*
X395732Y86225D01*
X395655Y85760D01*
X397265D01*
G01X398832Y88343D02*
X399062Y88653D01*
X399330Y88808D01*
X399637Y88860D01*
X400020Y88757D01*
X400288Y88498D01*
X400365Y88188D01*
X400327Y87878D01*
X400173Y87620D01*
X399407Y87103D01*
X399062Y86742D01*
X398832Y86225D01*
X398755Y85760D01*
X400365D01*
G01X372992Y87293D02*
X373222Y87603D01*
X373490Y87758D01*
X373797Y87810D01*
X374180Y87707D01*
X374448Y87448D01*
X374525Y87138D01*
X374487Y86828D01*
X374333Y86570D01*
X373567Y86053D01*
X373222Y85692D01*
X372992Y85175D01*
X372915Y84710D01*
X374525D01*
G01X376092Y87293D02*
X376322Y87603D01*
X376590Y87758D01*
X376897Y87810D01*
X377280Y87707D01*
X377548Y87448D01*
X377625Y87138D01*
X377587Y86828D01*
X377433Y86570D01*
X376667Y86053D01*
X376322Y85692D01*
X376092Y85175D01*
X376015Y84710D01*
X377625D01*
G01X379920D02*
Y87810D01*
X379460Y87190D01*
G01Y84710D02*
X380380D01*
G01X393646Y48072D02*
X393876Y48382D01*
X394144Y48537D01*
X394451Y48589D01*
X394834Y48486D01*
X395102Y48227D01*
X395179Y47917D01*
X395141Y47607D01*
X394987Y47349D01*
X394221Y46832D01*
X393876Y46471D01*
X393646Y45954D01*
X393569Y45489D01*
X395179D01*
G01X396746Y48072D02*
X396976Y48382D01*
X397244Y48537D01*
X397551Y48589D01*
X397934Y48486D01*
X398202Y48227D01*
X398279Y47917D01*
X398241Y47607D01*
X398087Y47349D01*
X397321Y46832D01*
X396976Y46471D01*
X396746Y45954D01*
X396669Y45489D01*
X398279D01*
G01X399846Y48072D02*
X400076Y48382D01*
X400344Y48537D01*
X400651Y48589D01*
X401034Y48486D01*
X401302Y48227D01*
X401379Y47917D01*
X401341Y47607D01*
X401187Y47349D01*
X400421Y46832D01*
X400076Y46471D01*
X399846Y45954D01*
X399769Y45489D01*
X401379D01*
G01X375223Y92209D02*
X375098Y91959D01*
X375015Y91667D01*
Y91334D01*
X375140Y90959D01*
X375348Y90667D01*
X375598Y90459D01*
X376015Y90292D01*
X376390Y90250D01*
X376765Y90334D01*
X377015Y90459D01*
X377265Y90709D01*
X377432Y91000D01*
X377515Y91292D01*
Y91584D01*
X377432Y91875D01*
X377307Y92125D01*
X377140Y92334D01*
G01X375432Y93600D02*
X375182Y93850D01*
X375057Y94142D01*
X375015Y94475D01*
X375098Y94892D01*
X375307Y95184D01*
X375557Y95267D01*
X375807Y95225D01*
X376015Y95059D01*
X376432Y94225D01*
X376723Y93850D01*
X377140Y93600D01*
X377515Y93517D01*
Y95267D01*
G01Y96700D02*
X375015D01*
Y98284D01*
G01X376223Y97700D02*
Y96700D01*
G01X375432Y99800D02*
X375182Y100050D01*
X375057Y100342D01*
X375015Y100675D01*
X375098Y101092D01*
X375307Y101384D01*
X375557Y101467D01*
X375807Y101425D01*
X376015Y101259D01*
X376432Y100425D01*
X376723Y100050D01*
X377140Y99800D01*
X377515Y99717D01*
Y101467D01*
G01X406094Y152223D02*
X408761D01*
Y150123D01*
X407961Y149423D01*
X407027Y148956D01*
X405694Y148723D01*
X404361Y148956D01*
X403427Y149423D01*
X402627Y150123D01*
X402094Y150940D01*
X401827Y151873D01*
Y152690D01*
X402094Y153390D01*
X402627Y154206D01*
X403427Y154906D01*
X404227Y155373D01*
X405294Y155723D01*
X406227D01*
X407294Y155490D01*
X408094Y155023D01*
G01X377500Y107000D02*
X364500D01*
G01X403700Y111819D02*
Y96501D01*
X403699Y96500D01*
X385100D01*
Y102540D01*
G01X403700Y114912D02*
Y122600D01*
X428500D01*
G01Y170000D02*
X385100D01*
Y104421D01*
G01X414448Y131814D02*
Y134314D01*
X415489D01*
X415823Y134189D01*
X416031Y134022D01*
X416114Y133689D01*
X416031Y133356D01*
X415781Y133147D01*
X415489Y133022D01*
X414448D01*
G01X415489D02*
X416114Y131814D01*
G01X418381D02*
Y134314D01*
X417881Y133814D01*
G01Y131814D02*
X418881D01*
G01X420689D02*
Y134314D01*
X422273D01*
G01X421689Y133106D02*
X420689D01*
G01X423789Y133897D02*
X424039Y134147D01*
X424331Y134272D01*
X424664Y134314D01*
X425081Y134231D01*
X425373Y134022D01*
X425456Y133772D01*
X425414Y133522D01*
X425248Y133314D01*
X424414Y132897D01*
X424039Y132606D01*
X423789Y132189D01*
X423706Y131814D01*
X425456D01*
G01X414448Y135214D02*
Y137714D01*
X415489D01*
X415823Y137589D01*
X416031Y137422D01*
X416114Y137089D01*
X416031Y136756D01*
X415781Y136547D01*
X415489Y136422D01*
X414448D01*
G01X415489D02*
X416114Y135214D01*
G01X418381D02*
Y137714D01*
X417881Y137214D01*
G01Y135214D02*
X418881D01*
G01X420689D02*
Y137714D01*
X422273D01*
G01X421689Y136506D02*
X420689D01*
G01X424581Y135214D02*
Y137714D01*
X424081Y137214D01*
G01Y135214D02*
X425081D01*
G01X360670Y121694D02*
X358170D01*
Y122735D01*
X358295Y123069D01*
X358462Y123277D01*
X358795Y123360D01*
X359128Y123277D01*
X359337Y123027D01*
X359462Y122735D01*
Y121694D01*
G01Y122735D02*
X360670Y123360D01*
G01Y125627D02*
X358170D01*
X358670Y125127D01*
G01X360670D02*
Y126127D01*
G01X359420Y128977D02*
Y129810D01*
X360170D01*
X360420Y129560D01*
X360587Y129269D01*
X360670Y128852D01*
X360587Y128435D01*
X360420Y128144D01*
X360170Y127894D01*
X359878Y127727D01*
X359545Y127644D01*
X359253D01*
X359003Y127727D01*
X358712Y127894D01*
X358462Y128144D01*
X358295Y128394D01*
X358170Y128727D01*
Y129019D01*
X358253Y129352D01*
X358420Y129602D01*
G01X360670Y131827D02*
X358170D01*
X358670Y131327D01*
G01X360670D02*
Y132327D01*
G01Y134844D02*
X360128Y134927D01*
X359670Y135052D01*
X359253Y135219D01*
X358795Y135427D01*
X358170Y135760D01*
Y134094D01*
G01X364444Y124122D02*
X364194Y124247D01*
X363902Y124330D01*
X363569D01*
X363194Y124205D01*
X362902Y123997D01*
X362694Y123747D01*
X362527Y123330D01*
X362485Y122955D01*
X362569Y122580D01*
X362694Y122330D01*
X362944Y122080D01*
X363235Y121913D01*
X363527Y121830D01*
X363819D01*
X364110Y121913D01*
X364360Y122038D01*
X364569Y122205D01*
G01X366627Y121830D02*
Y124330D01*
X366127Y123830D01*
G01Y121830D02*
X367127D01*
G01X369977Y123080D02*
X370810D01*
Y122330D01*
X370560Y122080D01*
X370269Y121913D01*
X369852Y121830D01*
X369435Y121913D01*
X369144Y122080D01*
X368894Y122330D01*
X368727Y122622D01*
X368644Y122955D01*
Y123247D01*
X368727Y123497D01*
X368894Y123788D01*
X369144Y124038D01*
X369394Y124205D01*
X369727Y124330D01*
X370019D01*
X370352Y124247D01*
X370602Y124080D01*
G01X372827Y121830D02*
Y124330D01*
X372327Y123830D01*
G01Y121830D02*
X373327D01*
G01X375219Y122122D02*
X375510Y121913D01*
X375844Y121830D01*
X376177Y121913D01*
X376469Y122163D01*
X376677Y122538D01*
X376760Y122913D01*
Y123372D01*
X376677Y123747D01*
X376469Y124080D01*
X376219Y124247D01*
X375927Y124330D01*
X375594Y124247D01*
X375344Y124080D01*
X375177Y123830D01*
X375094Y123497D01*
X375177Y123205D01*
X375385Y122913D01*
X375635Y122747D01*
X375927Y122705D01*
X376260Y122788D01*
X376510Y122997D01*
X376760Y123372D01*
G01X416086Y141625D02*
X415836Y141750D01*
X415544Y141833D01*
X415211D01*
X414836Y141708D01*
X414544Y141500D01*
X414336Y141250D01*
X414169Y140833D01*
X414127Y140458D01*
X414211Y140083D01*
X414336Y139833D01*
X414586Y139583D01*
X414877Y139416D01*
X415169Y139333D01*
X415461D01*
X415752Y139416D01*
X416002Y139541D01*
X416211Y139708D01*
G01X418269Y139333D02*
Y141833D01*
X417769Y141333D01*
G01Y139333D02*
X418769D01*
G01X420577D02*
Y141833D01*
X422161D01*
G01X421577Y140625D02*
X420577D01*
G01X423761Y139625D02*
X424052Y139416D01*
X424386Y139333D01*
X424719Y139416D01*
X425011Y139666D01*
X425219Y140041D01*
X425302Y140416D01*
Y140875D01*
X425219Y141250D01*
X425011Y141583D01*
X424761Y141750D01*
X424469Y141833D01*
X424136Y141750D01*
X423886Y141583D01*
X423719Y141333D01*
X423636Y141000D01*
X423719Y140708D01*
X423927Y140416D01*
X424177Y140250D01*
X424469Y140208D01*
X424802Y140291D01*
X425052Y140500D01*
X425302Y140875D01*
G01X388598Y123006D02*
X388348Y123131D01*
X388056Y123214D01*
X387723D01*
X387348Y123089D01*
X387056Y122881D01*
X386848Y122631D01*
X386681Y122214D01*
X386639Y121839D01*
X386723Y121464D01*
X386848Y121214D01*
X387098Y120964D01*
X387389Y120797D01*
X387681Y120714D01*
X387973D01*
X388264Y120797D01*
X388514Y120922D01*
X388723Y121089D01*
G01X390781Y120714D02*
Y123214D01*
X390281Y122714D01*
G01Y120714D02*
X391281D01*
G01X393089D02*
Y123214D01*
X394673D01*
G01X394089Y122006D02*
X393089D01*
G01X396981Y120714D02*
Y123214D01*
X396481Y122714D01*
G01Y120714D02*
X397481D01*
G01X399164Y121089D02*
X399414Y120881D01*
X399706Y120756D01*
X400081Y120714D01*
X400456Y120797D01*
X400748Y120964D01*
X400956Y121256D01*
X400998Y121589D01*
X400914Y121922D01*
X400706Y122131D01*
X400414Y122297D01*
X400123Y122339D01*
X399831Y122297D01*
X399456Y122131D01*
X399581Y123214D01*
X400706D01*
G01X388198Y130606D02*
X387948Y130731D01*
X387656Y130814D01*
X387323D01*
X386948Y130689D01*
X386656Y130481D01*
X386448Y130231D01*
X386281Y129814D01*
X386239Y129439D01*
X386323Y129064D01*
X386448Y128814D01*
X386698Y128564D01*
X386989Y128397D01*
X387281Y128314D01*
X387573D01*
X387864Y128397D01*
X388114Y128522D01*
X388323Y128689D01*
G01X390381Y128314D02*
Y130814D01*
X389881Y130314D01*
G01Y128314D02*
X390881D01*
G01X392689D02*
Y130814D01*
X394273D01*
G01X393689Y129606D02*
X392689D01*
G01X396581Y128314D02*
Y130814D01*
X396081Y130314D01*
G01Y128314D02*
X397081D01*
G01X398764Y128814D02*
X399014Y128522D01*
X399348Y128356D01*
X399723Y128314D01*
X400056Y128356D01*
X400389Y128564D01*
X400598Y128814D01*
X400639Y129064D01*
X400556Y129356D01*
X400264Y129564D01*
X399973Y129647D01*
X399598D01*
G01X399973D02*
X400223Y129772D01*
X400431Y129981D01*
X400514Y130231D01*
X400431Y130481D01*
X400223Y130689D01*
X399848Y130814D01*
X399473Y130772D01*
X399098Y130606D01*
G01X388298Y134406D02*
X388048Y134531D01*
X387756Y134614D01*
X387423D01*
X387048Y134489D01*
X386756Y134281D01*
X386548Y134031D01*
X386381Y133614D01*
X386339Y133239D01*
X386423Y132864D01*
X386548Y132614D01*
X386798Y132364D01*
X387089Y132197D01*
X387381Y132114D01*
X387673D01*
X387964Y132197D01*
X388214Y132322D01*
X388423Y132489D01*
G01X390481Y132114D02*
Y134614D01*
X389981Y134114D01*
G01Y132114D02*
X390981D01*
G01X392789D02*
Y134614D01*
X394373D01*
G01X393789Y133406D02*
X392789D01*
G01X396681Y132114D02*
Y134614D01*
X396181Y134114D01*
G01Y132114D02*
X397181D01*
G01X398989Y134197D02*
X399239Y134447D01*
X399531Y134572D01*
X399864Y134614D01*
X400281Y134531D01*
X400573Y134322D01*
X400656Y134072D01*
X400614Y133822D01*
X400448Y133614D01*
X399614Y133197D01*
X399239Y132906D01*
X398989Y132489D01*
X398906Y132114D01*
X400656D01*
G01X388298Y158206D02*
X388048Y158331D01*
X387756Y158414D01*
X387423D01*
X387048Y158289D01*
X386756Y158081D01*
X386548Y157831D01*
X386381Y157414D01*
X386339Y157039D01*
X386423Y156664D01*
X386548Y156414D01*
X386798Y156164D01*
X387089Y155997D01*
X387381Y155914D01*
X387673D01*
X387964Y155997D01*
X388214Y156122D01*
X388423Y156289D01*
G01X390481Y155914D02*
Y158414D01*
X389981Y157914D01*
G01Y155914D02*
X390981D01*
G01X392789D02*
Y158414D01*
X394373D01*
G01X393789Y157206D02*
X392789D01*
G01X395764Y156414D02*
X396014Y156122D01*
X396348Y155956D01*
X396723Y155914D01*
X397056Y155956D01*
X397389Y156164D01*
X397598Y156414D01*
X397639Y156664D01*
X397556Y156956D01*
X397264Y157164D01*
X396973Y157247D01*
X396598D01*
G01X396973D02*
X397223Y157372D01*
X397431Y157581D01*
X397514Y157831D01*
X397431Y158081D01*
X397223Y158289D01*
X396848Y158414D01*
X396473Y158372D01*
X396098Y158206D01*
G01X388298Y151406D02*
X388048Y151531D01*
X387756Y151614D01*
X387423D01*
X387048Y151489D01*
X386756Y151281D01*
X386548Y151031D01*
X386381Y150614D01*
X386339Y150239D01*
X386423Y149864D01*
X386548Y149614D01*
X386798Y149364D01*
X387089Y149197D01*
X387381Y149114D01*
X387673D01*
X387964Y149197D01*
X388214Y149322D01*
X388423Y149489D01*
G01X390481Y149114D02*
Y151614D01*
X389981Y151114D01*
G01Y149114D02*
X390981D01*
G01X392789D02*
Y151614D01*
X394373D01*
G01X393789Y150406D02*
X392789D01*
G01X395764Y149489D02*
X396014Y149281D01*
X396306Y149156D01*
X396681Y149114D01*
X397056Y149197D01*
X397348Y149364D01*
X397556Y149656D01*
X397598Y149989D01*
X397514Y150322D01*
X397306Y150531D01*
X397014Y150697D01*
X396723Y150739D01*
X396431Y150697D01*
X396056Y150531D01*
X396181Y151614D01*
X397306D01*
G01X388298Y154806D02*
X388048Y154931D01*
X387756Y155014D01*
X387423D01*
X387048Y154889D01*
X386756Y154681D01*
X386548Y154431D01*
X386381Y154014D01*
X386339Y153639D01*
X386423Y153264D01*
X386548Y153014D01*
X386798Y152764D01*
X387089Y152597D01*
X387381Y152514D01*
X387673D01*
X387964Y152597D01*
X388214Y152722D01*
X388423Y152889D01*
G01X390481Y152514D02*
Y155014D01*
X389981Y154514D01*
G01Y152514D02*
X390981D01*
G01X392789D02*
Y155014D01*
X394373D01*
G01X393789Y153806D02*
X392789D01*
G01X397181Y152514D02*
Y155014D01*
X395639Y153222D01*
X397723D01*
G01X388298Y144606D02*
X388048Y144731D01*
X387756Y144814D01*
X387423D01*
X387048Y144689D01*
X386756Y144481D01*
X386548Y144231D01*
X386381Y143814D01*
X386339Y143439D01*
X386423Y143064D01*
X386548Y142814D01*
X386798Y142564D01*
X387089Y142397D01*
X387381Y142314D01*
X387673D01*
X387964Y142397D01*
X388214Y142522D01*
X388423Y142689D01*
G01X390481Y142314D02*
Y144814D01*
X389981Y144314D01*
G01Y142314D02*
X390981D01*
G01X392789D02*
Y144814D01*
X394373D01*
G01X393789Y143606D02*
X392789D01*
G01X396681Y142314D02*
X396973Y142356D01*
X397306Y142481D01*
X397514Y142689D01*
X397598Y142981D01*
X397514Y143272D01*
X397264Y143522D01*
X396889Y143647D01*
X396473D01*
X396223Y143731D01*
X396014Y143939D01*
X395931Y144231D01*
X396056Y144522D01*
X396348Y144731D01*
X396681Y144814D01*
X397014Y144731D01*
X397306Y144522D01*
X397431Y144231D01*
X397348Y143939D01*
X397139Y143731D01*
X396889Y143647D01*
X396473D01*
X396098Y143522D01*
X395848Y143272D01*
X395764Y142981D01*
X395848Y142689D01*
X396056Y142481D01*
X396389Y142356D01*
X396681Y142314D01*
G01X388298Y141206D02*
X388048Y141331D01*
X387756Y141414D01*
X387423D01*
X387048Y141289D01*
X386756Y141081D01*
X386548Y140831D01*
X386381Y140414D01*
X386339Y140039D01*
X386423Y139664D01*
X386548Y139414D01*
X386798Y139164D01*
X387089Y138997D01*
X387381Y138914D01*
X387673D01*
X387964Y138997D01*
X388214Y139122D01*
X388423Y139289D01*
G01X390481Y138914D02*
Y141414D01*
X389981Y140914D01*
G01Y138914D02*
X390981D01*
G01X392789D02*
Y141414D01*
X394373D01*
G01X393789Y140206D02*
X392789D01*
G01X396681Y138914D02*
Y141414D01*
X396181Y140914D01*
G01Y138914D02*
X397181D01*
G01X399781Y141414D02*
X399448Y141331D01*
X399198Y141122D01*
X399031Y140872D01*
X398906Y140539D01*
X398864Y140164D01*
X398906Y139789D01*
X399031Y139456D01*
X399198Y139206D01*
X399448Y138997D01*
X399781Y138914D01*
X400114Y138997D01*
X400364Y139206D01*
X400531Y139456D01*
X400656Y139789D01*
X400698Y140164D01*
X400656Y140539D01*
X400531Y140872D01*
X400364Y141122D01*
X400114Y141331D01*
X399781Y141414D01*
G01X388298Y148006D02*
X388048Y148131D01*
X387756Y148214D01*
X387423D01*
X387048Y148089D01*
X386756Y147881D01*
X386548Y147631D01*
X386381Y147214D01*
X386339Y146839D01*
X386423Y146464D01*
X386548Y146214D01*
X386798Y145964D01*
X387089Y145797D01*
X387381Y145714D01*
X387673D01*
X387964Y145797D01*
X388214Y145922D01*
X388423Y146089D01*
G01X390481Y145714D02*
Y148214D01*
X389981Y147714D01*
G01Y145714D02*
X390981D01*
G01X392789D02*
Y148214D01*
X394373D01*
G01X393789Y147006D02*
X392789D01*
G01X395889Y146756D02*
X396181Y147047D01*
X396431Y147214D01*
X396764Y147297D01*
X397056Y147214D01*
X397264Y147047D01*
X397431Y146797D01*
X397473Y146506D01*
X397431Y146256D01*
X397264Y146006D01*
X397014Y145797D01*
X396723Y145714D01*
X396389Y145797D01*
X396098Y146047D01*
X395931Y146422D01*
X395889Y146839D01*
X395973Y147381D01*
X396098Y147672D01*
X396306Y147964D01*
X396598Y148172D01*
X396889Y148214D01*
X397181Y148131D01*
X397389Y147922D01*
G01X388298Y137806D02*
X388048Y137931D01*
X387756Y138014D01*
X387423D01*
X387048Y137889D01*
X386756Y137681D01*
X386548Y137431D01*
X386381Y137014D01*
X386339Y136639D01*
X386423Y136264D01*
X386548Y136014D01*
X386798Y135764D01*
X387089Y135597D01*
X387381Y135514D01*
X387673D01*
X387964Y135597D01*
X388214Y135722D01*
X388423Y135889D01*
G01X390481Y135514D02*
Y138014D01*
X389981Y137514D01*
G01Y135514D02*
X390981D01*
G01X392789D02*
Y138014D01*
X394373D01*
G01X393789Y136806D02*
X392789D01*
G01X396681Y135514D02*
Y138014D01*
X396181Y137514D01*
G01Y135514D02*
X397181D01*
G01X399781D02*
Y138014D01*
X399281Y137514D01*
G01Y135514D02*
X400281D01*
G01X388098Y126906D02*
X387848Y127031D01*
X387556Y127114D01*
X387223D01*
X386848Y126989D01*
X386556Y126781D01*
X386348Y126531D01*
X386181Y126114D01*
X386139Y125739D01*
X386223Y125364D01*
X386348Y125114D01*
X386598Y124864D01*
X386889Y124697D01*
X387181Y124614D01*
X387473D01*
X387764Y124697D01*
X388014Y124822D01*
X388223Y124989D01*
G01X390281Y124614D02*
Y127114D01*
X389781Y126614D01*
G01Y124614D02*
X390781D01*
G01X392589D02*
Y127114D01*
X394173D01*
G01X393589Y125906D02*
X392589D01*
G01X396481Y124614D02*
Y127114D01*
X395981Y126614D01*
G01Y124614D02*
X396981D01*
G01X400081D02*
Y127114D01*
X398539Y125322D01*
X400623D01*
G01X388598Y119606D02*
X388348Y119731D01*
X388056Y119814D01*
X387723D01*
X387348Y119689D01*
X387056Y119481D01*
X386848Y119231D01*
X386681Y118814D01*
X386639Y118439D01*
X386723Y118064D01*
X386848Y117814D01*
X387098Y117564D01*
X387389Y117397D01*
X387681Y117314D01*
X387973D01*
X388264Y117397D01*
X388514Y117522D01*
X388723Y117689D01*
G01X390781Y117314D02*
Y119814D01*
X390281Y119314D01*
G01Y117314D02*
X391281D01*
G01X393089D02*
Y119814D01*
X394673D01*
G01X394089Y118606D02*
X393089D01*
G01X396981Y117314D02*
Y119814D01*
X396481Y119314D01*
G01Y117314D02*
X397481D01*
G01X399289Y118356D02*
X399581Y118647D01*
X399831Y118814D01*
X400164Y118897D01*
X400456Y118814D01*
X400664Y118647D01*
X400831Y118397D01*
X400873Y118106D01*
X400831Y117856D01*
X400664Y117606D01*
X400414Y117397D01*
X400123Y117314D01*
X399789Y117397D01*
X399498Y117647D01*
X399331Y118022D01*
X399289Y118439D01*
X399373Y118981D01*
X399498Y119272D01*
X399706Y119564D01*
X399998Y119772D01*
X400289Y119814D01*
X400581Y119731D01*
X400789Y119522D01*
G01X388426Y103910D02*
X388176Y104035D01*
X387884Y104118D01*
X387551D01*
X387176Y103993D01*
X386884Y103785D01*
X386676Y103535D01*
X386509Y103118D01*
X386467Y102743D01*
X386551Y102368D01*
X386676Y102118D01*
X386926Y101868D01*
X387217Y101701D01*
X387509Y101618D01*
X387801D01*
X388092Y101701D01*
X388342Y101826D01*
X388551Y101993D01*
G01X390609Y101618D02*
Y104118D01*
X390109Y103618D01*
G01Y101618D02*
X391109D01*
G01X392917D02*
Y104118D01*
X394501D01*
G01X393917Y102910D02*
X392917D01*
G01X396809Y101618D02*
Y104118D01*
X396309Y103618D01*
G01Y101618D02*
X397309D01*
G01X399909D02*
X400201Y101660D01*
X400534Y101785D01*
X400742Y101993D01*
X400826Y102285D01*
X400742Y102576D01*
X400492Y102826D01*
X400117Y102951D01*
X399701D01*
X399451Y103035D01*
X399242Y103243D01*
X399159Y103535D01*
X399284Y103826D01*
X399576Y104035D01*
X399909Y104118D01*
X400242Y104035D01*
X400534Y103826D01*
X400659Y103535D01*
X400576Y103243D01*
X400367Y103035D01*
X400117Y102951D01*
X399701D01*
X399326Y102826D01*
X399076Y102576D01*
X398992Y102285D01*
X399076Y101993D01*
X399284Y101785D01*
X399617Y101660D01*
X399909Y101618D01*
G01X388598Y110706D02*
X388348Y110831D01*
X388056Y110914D01*
X387723D01*
X387348Y110789D01*
X387056Y110581D01*
X386848Y110331D01*
X386681Y109914D01*
X386639Y109539D01*
X386723Y109164D01*
X386848Y108914D01*
X387098Y108664D01*
X387389Y108497D01*
X387681Y108414D01*
X387973D01*
X388264Y108497D01*
X388514Y108622D01*
X388723Y108789D01*
G01X390781Y108414D02*
Y110914D01*
X390281Y110414D01*
G01Y108414D02*
X391281D01*
G01X393089D02*
Y110914D01*
X394673D01*
G01X394089Y109706D02*
X393089D01*
G01X396981Y108414D02*
Y110914D01*
X396481Y110414D01*
G01Y108414D02*
X397481D01*
G01X399998D02*
X400081Y108956D01*
X400206Y109414D01*
X400373Y109831D01*
X400581Y110289D01*
X400914Y110914D01*
X399248D01*
G01X390098Y99906D02*
X389848Y100031D01*
X389556Y100114D01*
X389223D01*
X388848Y99989D01*
X388556Y99781D01*
X388348Y99531D01*
X388181Y99114D01*
X388139Y98739D01*
X388223Y98364D01*
X388348Y98114D01*
X388598Y97864D01*
X388889Y97697D01*
X389181Y97614D01*
X389473D01*
X389764Y97697D01*
X390014Y97822D01*
X390223Y97989D01*
G01X392281Y97614D02*
Y100114D01*
X391781Y99614D01*
G01Y97614D02*
X392781D01*
G01X394589D02*
Y100114D01*
X396173D01*
G01X395589Y98906D02*
X394589D01*
G01X397689Y99697D02*
X397939Y99947D01*
X398231Y100072D01*
X398564Y100114D01*
X398981Y100031D01*
X399273Y99822D01*
X399356Y99572D01*
X399314Y99322D01*
X399148Y99114D01*
X398314Y98697D01*
X397939Y98406D01*
X397689Y97989D01*
X397606Y97614D01*
X399356D01*
G01X401581Y100114D02*
X401248Y100031D01*
X400998Y99822D01*
X400831Y99572D01*
X400706Y99239D01*
X400664Y98864D01*
X400706Y98489D01*
X400831Y98156D01*
X400998Y97906D01*
X401248Y97697D01*
X401581Y97614D01*
X401914Y97697D01*
X402164Y97906D01*
X402331Y98156D01*
X402456Y98489D01*
X402498Y98864D01*
X402456Y99239D01*
X402331Y99572D01*
X402164Y99822D01*
X401914Y100031D01*
X401581Y100114D01*
G01X403639Y133031D02*
X403514Y132781D01*
X403431Y132489D01*
Y132156D01*
X403556Y131781D01*
X403764Y131489D01*
X404014Y131281D01*
X404431Y131114D01*
X404806Y131072D01*
X405181Y131156D01*
X405431Y131281D01*
X405681Y131531D01*
X405848Y131822D01*
X405931Y132114D01*
Y132406D01*
X405848Y132697D01*
X405723Y132947D01*
X405556Y133156D01*
G01X405931Y134381D02*
X403431D01*
Y135422D01*
X403556Y135756D01*
X403723Y135964D01*
X404056Y136047D01*
X404389Y135964D01*
X404598Y135714D01*
X404723Y135422D01*
Y134381D01*
G01Y135422D02*
X405931Y136047D01*
G01Y138314D02*
X403431D01*
X403931Y137814D01*
G01X405931D02*
Y138814D01*
G01Y140622D02*
X403431D01*
Y142206D01*
G01X404639Y141622D02*
Y140622D01*
G01X405431Y143597D02*
X405723Y143847D01*
X405889Y144181D01*
X405931Y144556D01*
X405889Y144889D01*
X405681Y145222D01*
X405431Y145431D01*
X405181Y145472D01*
X404889Y145389D01*
X404681Y145097D01*
X404598Y144806D01*
Y144431D01*
G01Y144806D02*
X404473Y145056D01*
X404264Y145264D01*
X404014Y145347D01*
X403764Y145264D01*
X403556Y145056D01*
X403431Y144681D01*
X403473Y144306D01*
X403639Y143931D01*
G01X410739Y133131D02*
X410614Y132881D01*
X410531Y132589D01*
Y132256D01*
X410656Y131881D01*
X410864Y131589D01*
X411114Y131381D01*
X411531Y131214D01*
X411906Y131172D01*
X412281Y131256D01*
X412531Y131381D01*
X412781Y131631D01*
X412948Y131922D01*
X413031Y132214D01*
Y132506D01*
X412948Y132797D01*
X412823Y133047D01*
X412656Y133256D01*
G01X413031Y134481D02*
X410531D01*
Y135522D01*
X410656Y135856D01*
X410823Y136064D01*
X411156Y136147D01*
X411489Y136064D01*
X411698Y135814D01*
X411823Y135522D01*
Y134481D01*
G01Y135522D02*
X413031Y136147D01*
G01Y138414D02*
X410531D01*
X411031Y137914D01*
G01X413031D02*
Y138914D01*
G01Y140722D02*
X410531D01*
Y142306D01*
G01X411739Y141722D02*
Y140722D01*
G01X413031Y144614D02*
X410531D01*
X411031Y144114D01*
G01X413031D02*
Y145114D01*
G01X407339Y133131D02*
X407214Y132881D01*
X407131Y132589D01*
Y132256D01*
X407256Y131881D01*
X407464Y131589D01*
X407714Y131381D01*
X408131Y131214D01*
X408506Y131172D01*
X408881Y131256D01*
X409131Y131381D01*
X409381Y131631D01*
X409548Y131922D01*
X409631Y132214D01*
Y132506D01*
X409548Y132797D01*
X409423Y133047D01*
X409256Y133256D01*
G01X409631Y134481D02*
X407131D01*
Y135522D01*
X407256Y135856D01*
X407423Y136064D01*
X407756Y136147D01*
X408089Y136064D01*
X408298Y135814D01*
X408423Y135522D01*
Y134481D01*
G01Y135522D02*
X409631Y136147D01*
G01Y138414D02*
X407131D01*
X407631Y137914D01*
G01X409631D02*
Y138914D01*
G01Y140722D02*
X407131D01*
Y142306D01*
G01X408339Y141722D02*
Y140722D01*
G01X409631Y145114D02*
X407131D01*
X408923Y143572D01*
Y145656D01*
G01X386548Y166114D02*
Y168614D01*
X387589D01*
X387923Y168489D01*
X388131Y168322D01*
X388214Y167989D01*
X388131Y167656D01*
X387881Y167447D01*
X387589Y167322D01*
X386548D01*
G01X387589D02*
X388214Y166114D01*
G01X390481D02*
Y168614D01*
X389981Y168114D01*
G01Y166114D02*
X390981D01*
G01X392789D02*
Y168614D01*
X394373D01*
G01X393789Y167406D02*
X392789D01*
G01X396681Y166114D02*
X396973Y166156D01*
X397306Y166281D01*
X397514Y166489D01*
X397598Y166781D01*
X397514Y167072D01*
X397264Y167322D01*
X396889Y167447D01*
X396473D01*
X396223Y167531D01*
X396014Y167739D01*
X395931Y168031D01*
X396056Y168322D01*
X396348Y168531D01*
X396681Y168614D01*
X397014Y168531D01*
X397306Y168322D01*
X397431Y168031D01*
X397348Y167739D01*
X397139Y167531D01*
X396889Y167447D01*
X396473D01*
X396098Y167322D01*
X395848Y167072D01*
X395764Y166781D01*
X395848Y166489D01*
X396056Y166281D01*
X396389Y166156D01*
X396681Y166114D01*
G01X386548Y162714D02*
Y165214D01*
X387589D01*
X387923Y165089D01*
X388131Y164922D01*
X388214Y164589D01*
X388131Y164256D01*
X387881Y164047D01*
X387589Y163922D01*
X386548D01*
G01X387589D02*
X388214Y162714D01*
G01X390481D02*
Y165214D01*
X389981Y164714D01*
G01Y162714D02*
X390981D01*
G01X392789D02*
Y165214D01*
X394373D01*
G01X393789Y164006D02*
X392789D01*
G01X395973Y163006D02*
X396264Y162797D01*
X396598Y162714D01*
X396931Y162797D01*
X397223Y163047D01*
X397431Y163422D01*
X397514Y163797D01*
Y164256D01*
X397431Y164631D01*
X397223Y164964D01*
X396973Y165131D01*
X396681Y165214D01*
X396348Y165131D01*
X396098Y164964D01*
X395931Y164714D01*
X395848Y164381D01*
X395931Y164089D01*
X396139Y163797D01*
X396389Y163631D01*
X396681Y163589D01*
X397014Y163672D01*
X397264Y163881D01*
X397514Y164256D01*
G01X388298Y161606D02*
X388048Y161731D01*
X387756Y161814D01*
X387423D01*
X387048Y161689D01*
X386756Y161481D01*
X386548Y161231D01*
X386381Y160814D01*
X386339Y160439D01*
X386423Y160064D01*
X386548Y159814D01*
X386798Y159564D01*
X387089Y159397D01*
X387381Y159314D01*
X387673D01*
X387964Y159397D01*
X388214Y159522D01*
X388423Y159689D01*
G01X390481Y159314D02*
Y161814D01*
X389981Y161314D01*
G01Y159314D02*
X390981D01*
G01X392789D02*
Y161814D01*
X394373D01*
G01X393789Y160606D02*
X392789D01*
G01X395889Y161397D02*
X396139Y161647D01*
X396431Y161772D01*
X396764Y161814D01*
X397181Y161731D01*
X397473Y161522D01*
X397556Y161272D01*
X397514Y161022D01*
X397348Y160814D01*
X396514Y160397D01*
X396139Y160106D01*
X395889Y159689D01*
X395806Y159314D01*
X397556D01*
G01X359849Y177764D02*
X359581Y177403D01*
X359351Y177196D01*
X359044Y177093D01*
X358776Y177196D01*
X358584Y177403D01*
X358431Y177713D01*
X358393Y178074D01*
X358431Y178384D01*
X358584Y178694D01*
X358814Y178953D01*
X359083Y179056D01*
X359389Y178953D01*
X359658Y178643D01*
X359811Y178178D01*
X359849Y177661D01*
X359773Y176989D01*
X359658Y176628D01*
X359466Y176266D01*
X359198Y176008D01*
X358929Y175956D01*
X358661Y176059D01*
X358469Y176318D01*
G01X356021Y179056D02*
Y175956D01*
X356481Y176576D01*
G01Y179056D02*
X355561D01*
G01X363294Y174061D02*
X363026Y173700D01*
X362796Y173493D01*
X362489Y173390D01*
X362221Y173493D01*
X362029Y173700D01*
X361876Y174010D01*
X361838Y174371D01*
X361876Y174681D01*
X362029Y174991D01*
X362259Y175250D01*
X362528Y175353D01*
X362834Y175250D01*
X363103Y174940D01*
X363256Y174475D01*
X363294Y173958D01*
X363218Y173286D01*
X363103Y172925D01*
X362911Y172563D01*
X362643Y172305D01*
X362374Y172253D01*
X362106Y172356D01*
X361914Y172615D01*
G01X359466Y172253D02*
X359773Y172356D01*
X360003Y172615D01*
X360156Y172925D01*
X360271Y173338D01*
X360309Y173803D01*
X360271Y174268D01*
X360156Y174681D01*
X360003Y174991D01*
X359773Y175250D01*
X359466Y175353D01*
X359159Y175250D01*
X358929Y174991D01*
X358776Y174681D01*
X358661Y174268D01*
X358623Y173803D01*
X358661Y173338D01*
X358776Y172925D01*
X358929Y172615D01*
X359159Y172356D01*
X359466Y172253D01*
G01X366724Y178591D02*
X366494Y178849D01*
X366226Y179004D01*
X365881Y179056D01*
X365536Y178953D01*
X365268Y178746D01*
X365076Y178384D01*
X365038Y177971D01*
X365114Y177558D01*
X365306Y177299D01*
X365574Y177093D01*
X365843Y177041D01*
X366111Y177093D01*
X366456Y177299D01*
X366341Y175956D01*
X365306D01*
G01X363433Y178694D02*
X363164Y178953D01*
X362858Y179056D01*
X362551Y178953D01*
X362283Y178643D01*
X362091Y178178D01*
X362014Y177713D01*
Y177144D01*
X362091Y176679D01*
X362283Y176266D01*
X362513Y176059D01*
X362781Y175956D01*
X363088Y176059D01*
X363318Y176266D01*
X363471Y176576D01*
X363548Y176989D01*
X363471Y177351D01*
X363279Y177713D01*
X363049Y177919D01*
X362781Y177971D01*
X362474Y177868D01*
X362244Y177609D01*
X362014Y177144D01*
G01X370169Y174888D02*
X369939Y175146D01*
X369671Y175301D01*
X369326Y175353D01*
X368981Y175250D01*
X368713Y175043D01*
X368521Y174681D01*
X368483Y174268D01*
X368559Y173855D01*
X368751Y173596D01*
X369019Y173390D01*
X369288Y173338D01*
X369556Y173390D01*
X369901Y173596D01*
X369786Y172253D01*
X368751D01*
G01X366226Y175353D02*
X365958Y175301D01*
X365651Y175146D01*
X365459Y174888D01*
X365383Y174526D01*
X365459Y174165D01*
X365689Y173855D01*
X366034Y173700D01*
X366418D01*
X366648Y173596D01*
X366839Y173338D01*
X366916Y172976D01*
X366801Y172615D01*
X366533Y172356D01*
X366226Y172253D01*
X365919Y172356D01*
X365651Y172615D01*
X365536Y172976D01*
X365613Y173338D01*
X365804Y173596D01*
X366034Y173700D01*
X366418D01*
X366763Y173855D01*
X366993Y174165D01*
X367069Y174526D01*
X366993Y174888D01*
X366801Y175146D01*
X366494Y175301D01*
X366226Y175353D01*
G01X373484Y178591D02*
X373254Y178849D01*
X372986Y179004D01*
X372641Y179056D01*
X372296Y178953D01*
X372028Y178746D01*
X371836Y178384D01*
X371798Y177971D01*
X371874Y177558D01*
X372066Y177299D01*
X372334Y177093D01*
X372603Y177041D01*
X372871Y177093D01*
X373216Y177299D01*
X373101Y175956D01*
X372066D01*
G01X369618Y179056D02*
X369541Y178384D01*
X369426Y177816D01*
X369273Y177299D01*
X369081Y176731D01*
X368774Y175956D01*
X370308D01*
G01X376929Y174888D02*
X376699Y175146D01*
X376431Y175301D01*
X376086Y175353D01*
X375741Y175250D01*
X375473Y175043D01*
X375281Y174681D01*
X375243Y174268D01*
X375319Y173855D01*
X375511Y173596D01*
X375779Y173390D01*
X376048Y173338D01*
X376316Y173390D01*
X376661Y173596D01*
X376546Y172253D01*
X375511D01*
G01X373714Y174061D02*
X373446Y173700D01*
X373216Y173493D01*
X372909Y173390D01*
X372641Y173493D01*
X372449Y173700D01*
X372296Y174010D01*
X372258Y174371D01*
X372296Y174681D01*
X372449Y174991D01*
X372679Y175250D01*
X372948Y175353D01*
X373254Y175250D01*
X373523Y174940D01*
X373676Y174475D01*
X373714Y173958D01*
X373638Y173286D01*
X373523Y172925D01*
X373331Y172563D01*
X373063Y172305D01*
X372794Y172253D01*
X372526Y172356D01*
X372334Y172615D01*
G01X380244Y178591D02*
X380014Y178849D01*
X379746Y179004D01*
X379401Y179056D01*
X379056Y178953D01*
X378788Y178746D01*
X378596Y178384D01*
X378558Y177971D01*
X378634Y177558D01*
X378826Y177299D01*
X379094Y177093D01*
X379363Y177041D01*
X379631Y177093D01*
X379976Y177299D01*
X379861Y175956D01*
X378826D01*
G01X377144Y178591D02*
X376914Y178849D01*
X376646Y179004D01*
X376301Y179056D01*
X375956Y178953D01*
X375688Y178746D01*
X375496Y178384D01*
X375458Y177971D01*
X375534Y177558D01*
X375726Y177299D01*
X375994Y177093D01*
X376263Y177041D01*
X376531Y177093D01*
X376876Y177299D01*
X376761Y175956D01*
X375726D01*
G01X383689Y174888D02*
X383459Y175146D01*
X383191Y175301D01*
X382846Y175353D01*
X382501Y175250D01*
X382233Y175043D01*
X382041Y174681D01*
X382003Y174268D01*
X382079Y173855D01*
X382271Y173596D01*
X382539Y173390D01*
X382808Y173338D01*
X383076Y173390D01*
X383421Y173596D01*
X383306Y172253D01*
X382271D01*
G01X379286Y175353D02*
Y172253D01*
X380704Y174475D01*
X378788D01*
G01X387004Y178591D02*
X386774Y178849D01*
X386506Y179004D01*
X386161Y179056D01*
X385816Y178953D01*
X385548Y178746D01*
X385356Y178384D01*
X385318Y177971D01*
X385394Y177558D01*
X385586Y177299D01*
X385854Y177093D01*
X386123Y177041D01*
X386391Y177093D01*
X386736Y177299D01*
X386621Y175956D01*
X385586D01*
G01X383904Y178436D02*
X383674Y178798D01*
X383368Y179004D01*
X383023Y179056D01*
X382716Y179004D01*
X382409Y178746D01*
X382218Y178436D01*
X382179Y178126D01*
X382256Y177764D01*
X382524Y177506D01*
X382793Y177403D01*
X383138D01*
G01X382793D02*
X382563Y177248D01*
X382371Y176989D01*
X382294Y176679D01*
X382371Y176369D01*
X382563Y176111D01*
X382908Y175956D01*
X383253Y176008D01*
X383598Y176214D01*
G01X390449Y174888D02*
X390219Y175146D01*
X389951Y175301D01*
X389606Y175353D01*
X389261Y175250D01*
X388993Y175043D01*
X388801Y174681D01*
X388763Y174268D01*
X388839Y173855D01*
X389031Y173596D01*
X389299Y173390D01*
X389568Y173338D01*
X389836Y173390D01*
X390181Y173596D01*
X390066Y172253D01*
X389031D01*
G01X387234Y172770D02*
X387004Y172460D01*
X386736Y172305D01*
X386429Y172253D01*
X386046Y172356D01*
X385778Y172615D01*
X385701Y172925D01*
X385739Y173235D01*
X385893Y173493D01*
X386659Y174010D01*
X387004Y174371D01*
X387234Y174888D01*
X387311Y175353D01*
X385701D01*
G01X393763Y178591D02*
X393533Y178849D01*
X393265Y179004D01*
X392920Y179056D01*
X392575Y178953D01*
X392307Y178746D01*
X392115Y178384D01*
X392077Y177971D01*
X392153Y177558D01*
X392345Y177299D01*
X392613Y177093D01*
X392882Y177041D01*
X393150Y177093D01*
X393495Y177299D01*
X393380Y175956D01*
X392345D01*
G01X389820Y179056D02*
Y175956D01*
X390280Y176576D01*
G01Y179056D02*
X389360D01*
G01X397209Y174888D02*
X396979Y175146D01*
X396711Y175301D01*
X396366Y175353D01*
X396021Y175250D01*
X395753Y175043D01*
X395561Y174681D01*
X395523Y174268D01*
X395599Y173855D01*
X395791Y173596D01*
X396059Y173390D01*
X396328Y173338D01*
X396596Y173390D01*
X396941Y173596D01*
X396826Y172253D01*
X395791D01*
G01X393266D02*
X393573Y172356D01*
X393803Y172615D01*
X393956Y172925D01*
X394071Y173338D01*
X394109Y173803D01*
X394071Y174268D01*
X393956Y174681D01*
X393803Y174991D01*
X393573Y175250D01*
X393266Y175353D01*
X392959Y175250D01*
X392729Y174991D01*
X392576Y174681D01*
X392461Y174268D01*
X392423Y173803D01*
X392461Y173338D01*
X392576Y172925D01*
X392729Y172615D01*
X392959Y172356D01*
X393266Y172253D01*
G01X399220Y179056D02*
Y175956D01*
X400638Y178178D01*
X398722D01*
G01X397232Y178694D02*
X396963Y178953D01*
X396657Y179056D01*
X396350Y178953D01*
X396082Y178643D01*
X395890Y178178D01*
X395813Y177713D01*
Y177144D01*
X395890Y176679D01*
X396082Y176266D01*
X396312Y176059D01*
X396580Y175956D01*
X396887Y176059D01*
X397117Y176266D01*
X397270Y176576D01*
X397347Y176989D01*
X397270Y177351D01*
X397078Y177713D01*
X396848Y177919D01*
X396580Y177971D01*
X396273Y177868D01*
X396043Y177609D01*
X395813Y177144D01*
G01X402666Y175353D02*
Y172253D01*
X404084Y174475D01*
X402168D01*
G01X400026Y175353D02*
X399758Y175301D01*
X399451Y175146D01*
X399259Y174888D01*
X399183Y174526D01*
X399259Y174165D01*
X399489Y173855D01*
X399834Y173700D01*
X400218D01*
X400448Y173596D01*
X400639Y173338D01*
X400716Y172976D01*
X400601Y172615D01*
X400333Y172356D01*
X400026Y172253D01*
X399719Y172356D01*
X399451Y172615D01*
X399336Y172976D01*
X399413Y173338D01*
X399604Y173596D01*
X399834Y173700D01*
X400218D01*
X400563Y173855D01*
X400793Y174165D01*
X400869Y174526D01*
X400793Y174888D01*
X400601Y175146D01*
X400294Y175301D01*
X400026Y175353D01*
G01X405980Y179056D02*
Y175956D01*
X407398Y178178D01*
X405482D01*
G01X403417Y179056D02*
X403340Y178384D01*
X403225Y177816D01*
X403072Y177299D01*
X402880Y176731D01*
X402573Y175956D01*
X404107D01*
G01X409425Y175353D02*
Y172253D01*
X410843Y174475D01*
X408927D01*
G01X407513Y174061D02*
X407245Y173700D01*
X407015Y173493D01*
X406708Y173390D01*
X406440Y173493D01*
X406248Y173700D01*
X406095Y174010D01*
X406057Y174371D01*
X406095Y174681D01*
X406248Y174991D01*
X406478Y175250D01*
X406747Y175353D01*
X407053Y175250D01*
X407322Y174940D01*
X407475Y174475D01*
X407513Y173958D01*
X407437Y173286D01*
X407322Y172925D01*
X407130Y172563D01*
X406862Y172305D01*
X406593Y172253D01*
X406325Y172356D01*
X406133Y172615D01*
G01X412740Y179056D02*
Y175956D01*
X414158Y178178D01*
X412242D01*
G01X410943Y178591D02*
X410713Y178849D01*
X410445Y179004D01*
X410100Y179056D01*
X409755Y178953D01*
X409487Y178746D01*
X409295Y178384D01*
X409257Y177971D01*
X409333Y177558D01*
X409525Y177299D01*
X409793Y177093D01*
X410062Y177041D01*
X410330Y177093D01*
X410675Y177299D01*
X410560Y175956D01*
X409525D01*
G01X416185Y175353D02*
Y172253D01*
X417603Y174475D01*
X415687D01*
G01X413085Y175353D02*
Y172253D01*
X414503Y174475D01*
X412587D01*
G01X419271Y179404D02*
Y176304D01*
X420689Y178526D01*
X418773D01*
G01X417474Y178784D02*
X417244Y179146D01*
X416938Y179352D01*
X416593Y179404D01*
X416286Y179352D01*
X415979Y179094D01*
X415788Y178784D01*
X415749Y178474D01*
X415826Y178112D01*
X416094Y177854D01*
X416363Y177751D01*
X416708D01*
G01X416363D02*
X416133Y177596D01*
X415941Y177337D01*
X415864Y177027D01*
X415941Y176717D01*
X416133Y176459D01*
X416478Y176304D01*
X416823Y176356D01*
X417168Y176562D01*
G01X415748Y413582D02*
Y339764D01*
X438819D01*
X464764Y324173D01*
Y278582D01*
X438819Y262992D01*
X413386D01*
Y189173D01*
X415748D01*
Y185236D01*
X419685D01*
Y189173D01*
X547244D01*
Y179134D01*
X574803D01*
Y269882D01*
X561024Y283661D01*
Y289567D01*
X559055D01*
Y313189D01*
X561024D01*
Y319094D01*
X574803Y332874D01*
Y423622D01*
X547244D01*
Y413582D01*
X419685D01*
Y417519D01*
X415748D01*
Y339764D01*
X438819D01*
X464764Y324173D01*
Y278582D01*
X438819Y262992D01*
X413386D01*
G01X393573Y515377D02*
X393650Y516049D01*
X393765Y516617D01*
X393918Y517134D01*
X394110Y517702D01*
X394417Y518477D01*
X392883D01*
G01X396750Y515377D02*
X397018Y515429D01*
X397325Y515584D01*
X397517Y515842D01*
X397593Y516204D01*
X397517Y516565D01*
X397287Y516875D01*
X396942Y517030D01*
X396558D01*
X396328Y517134D01*
X396137Y517392D01*
X396060Y517754D01*
X396175Y518115D01*
X396443Y518374D01*
X396750Y518477D01*
X397057Y518374D01*
X397325Y518115D01*
X397440Y517754D01*
X397363Y517392D01*
X397172Y517134D01*
X396942Y517030D01*
X396558D01*
X396213Y516875D01*
X395983Y516565D01*
X395907Y516204D01*
X395983Y515842D01*
X396175Y515584D01*
X396482Y515429D01*
X396750Y515377D01*
G01X369573Y513777D02*
X369650Y514449D01*
X369765Y515017D01*
X369918Y515534D01*
X370110Y516102D01*
X370417Y516877D01*
X368883D01*
G01X372673Y513777D02*
X372750Y514449D01*
X372865Y515017D01*
X373018Y515534D01*
X373210Y516102D01*
X373517Y516877D01*
X371983D01*
G01X374042Y503767D02*
X373917Y503517D01*
X373834Y503225D01*
Y502892D01*
X373959Y502517D01*
X374167Y502225D01*
X374417Y502017D01*
X374834Y501850D01*
X375209Y501808D01*
X375584Y501892D01*
X375834Y502017D01*
X376084Y502267D01*
X376251Y502558D01*
X376334Y502850D01*
Y503142D01*
X376251Y503433D01*
X376126Y503683D01*
X375959Y503892D01*
G01X374251Y505158D02*
X374001Y505408D01*
X373876Y505700D01*
X373834Y506033D01*
X373917Y506450D01*
X374126Y506742D01*
X374376Y506825D01*
X374626Y506783D01*
X374834Y506617D01*
X375251Y505783D01*
X375542Y505408D01*
X375959Y505158D01*
X376334Y505075D01*
Y506825D01*
G01X375001Y509383D02*
X374876Y509550D01*
X374667Y509675D01*
X374376Y509758D01*
X374126Y509675D01*
X373959Y509508D01*
X373834Y509217D01*
Y508092D01*
X376334D01*
Y509467D01*
X376167Y509758D01*
X375917Y509925D01*
X375626Y510008D01*
X375334Y509925D01*
X375084Y509675D01*
X375001Y509383D01*
Y508092D01*
G01X376334Y512150D02*
X373834D01*
X374334Y511650D01*
G01X376334D02*
Y512650D01*
G01X392309Y548808D02*
X392539Y549118D01*
X392807Y549273D01*
X393114Y549325D01*
X393497Y549222D01*
X393765Y548963D01*
X393842Y548653D01*
X393804Y548343D01*
X393650Y548085D01*
X392884Y547568D01*
X392539Y547207D01*
X392309Y546690D01*
X392232Y546225D01*
X393842D01*
G01X395409Y548808D02*
X395639Y549118D01*
X395907Y549273D01*
X396214Y549325D01*
X396597Y549222D01*
X396865Y548963D01*
X396942Y548653D01*
X396904Y548343D01*
X396750Y548085D01*
X395984Y547568D01*
X395639Y547207D01*
X395409Y546690D01*
X395332Y546225D01*
X396942D01*
G01X398509Y548808D02*
X398739Y549118D01*
X399007Y549273D01*
X399314Y549325D01*
X399697Y549222D01*
X399965Y548963D01*
X400042Y548653D01*
X400004Y548343D01*
X399850Y548085D01*
X399084Y547568D01*
X398739Y547207D01*
X398509Y546690D01*
X398432Y546225D01*
X400042D01*
G01X374422Y546960D02*
X374652Y547270D01*
X374920Y547425D01*
X375227Y547477D01*
X375610Y547374D01*
X375878Y547115D01*
X375955Y546805D01*
X375917Y546495D01*
X375763Y546237D01*
X374997Y545720D01*
X374652Y545359D01*
X374422Y544842D01*
X374345Y544377D01*
X375955D01*
G01X377522Y546960D02*
X377752Y547270D01*
X378020Y547425D01*
X378327Y547477D01*
X378710Y547374D01*
X378978Y547115D01*
X379055Y546805D01*
X379017Y546495D01*
X378863Y546237D01*
X378097Y545720D01*
X377752Y545359D01*
X377522Y544842D01*
X377445Y544377D01*
X379055D01*
G01X381350D02*
Y547477D01*
X380890Y546857D01*
G01Y544377D02*
X381810D01*
G01X392331Y554241D02*
X392408Y554913D01*
X392523Y555481D01*
X392676Y555998D01*
X392868Y556566D01*
X393175Y557341D01*
X391641D01*
G01X395508Y554241D02*
X395776Y554293D01*
X396083Y554448D01*
X396275Y554706D01*
X396351Y555068D01*
X396275Y555429D01*
X396045Y555739D01*
X395700Y555894D01*
X395316D01*
X395086Y555998D01*
X394895Y556256D01*
X394818Y556618D01*
X394933Y556979D01*
X395201Y557238D01*
X395508Y557341D01*
X395815Y557238D01*
X396083Y556979D01*
X396198Y556618D01*
X396121Y556256D01*
X395930Y555998D01*
X395700Y555894D01*
X395316D01*
X394971Y555739D01*
X394741Y555429D01*
X394665Y555068D01*
X394741Y554706D01*
X394933Y554448D01*
X395240Y554293D01*
X395508Y554241D01*
G01X379549Y554541D02*
X379626Y555213D01*
X379741Y555781D01*
X379894Y556298D01*
X380086Y556866D01*
X380393Y557641D01*
X378859D01*
G01X382649Y554541D02*
X382726Y555213D01*
X382841Y555781D01*
X382994Y556298D01*
X383186Y556866D01*
X383493Y557641D01*
X381959D01*
G01X393363Y586781D02*
X393593Y587091D01*
X393861Y587246D01*
X394168Y587298D01*
X394551Y587195D01*
X394819Y586936D01*
X394896Y586626D01*
X394858Y586316D01*
X394704Y586058D01*
X393938Y585541D01*
X393593Y585180D01*
X393363Y584663D01*
X393286Y584198D01*
X394896D01*
G01X396463Y586781D02*
X396693Y587091D01*
X396961Y587246D01*
X397268Y587298D01*
X397651Y587195D01*
X397919Y586936D01*
X397996Y586626D01*
X397958Y586316D01*
X397804Y586058D01*
X397038Y585541D01*
X396693Y585180D01*
X396463Y584663D01*
X396386Y584198D01*
X397996D01*
G01X399563Y586781D02*
X399793Y587091D01*
X400061Y587246D01*
X400368Y587298D01*
X400751Y587195D01*
X401019Y586936D01*
X401096Y586626D01*
X401058Y586316D01*
X400904Y586058D01*
X400138Y585541D01*
X399793Y585180D01*
X399563Y584663D01*
X399486Y584198D01*
X401096D01*
G01X373072Y585983D02*
X373302Y586293D01*
X373570Y586448D01*
X373877Y586500D01*
X374260Y586397D01*
X374528Y586138D01*
X374605Y585828D01*
X374567Y585518D01*
X374413Y585260D01*
X373647Y584743D01*
X373302Y584382D01*
X373072Y583865D01*
X372995Y583400D01*
X374605D01*
G01X376172Y585983D02*
X376402Y586293D01*
X376670Y586448D01*
X376977Y586500D01*
X377360Y586397D01*
X377628Y586138D01*
X377705Y585828D01*
X377667Y585518D01*
X377513Y585260D01*
X376747Y584743D01*
X376402Y584382D01*
X376172Y583865D01*
X376095Y583400D01*
X377705D01*
G01X380000D02*
Y586500D01*
X379540Y585880D01*
G01Y583400D02*
X380460D01*
G01X392538Y591803D02*
X392615Y592475D01*
X392730Y593043D01*
X392883Y593560D01*
X393075Y594128D01*
X393382Y594903D01*
X391848D01*
G01X395715Y591803D02*
X395983Y591855D01*
X396290Y592010D01*
X396482Y592268D01*
X396558Y592630D01*
X396482Y592991D01*
X396252Y593301D01*
X395907Y593456D01*
X395523D01*
X395293Y593560D01*
X395102Y593818D01*
X395025Y594180D01*
X395140Y594541D01*
X395408Y594800D01*
X395715Y594903D01*
X396022Y594800D01*
X396290Y594541D01*
X396405Y594180D01*
X396328Y593818D01*
X396137Y593560D01*
X395907Y593456D01*
X395523D01*
X395178Y593301D01*
X394948Y592991D01*
X394872Y592630D01*
X394948Y592268D01*
X395140Y592010D01*
X395447Y591855D01*
X395715Y591803D01*
G01X377583Y592573D02*
X377660Y593245D01*
X377775Y593813D01*
X377928Y594330D01*
X378120Y594898D01*
X378427Y595673D01*
X376893D01*
G01X380683Y592573D02*
X380760Y593245D01*
X380875Y593813D01*
X381028Y594330D01*
X381220Y594898D01*
X381527Y595673D01*
X379993D01*
G01X393122Y624460D02*
X393352Y624770D01*
X393620Y624925D01*
X393927Y624977D01*
X394310Y624874D01*
X394578Y624615D01*
X394655Y624305D01*
X394617Y623995D01*
X394463Y623737D01*
X393697Y623220D01*
X393352Y622859D01*
X393122Y622342D01*
X393045Y621877D01*
X394655D01*
G01X396222Y624460D02*
X396452Y624770D01*
X396720Y624925D01*
X397027Y624977D01*
X397410Y624874D01*
X397678Y624615D01*
X397755Y624305D01*
X397717Y623995D01*
X397563Y623737D01*
X396797Y623220D01*
X396452Y622859D01*
X396222Y622342D01*
X396145Y621877D01*
X397755D01*
G01X399322Y624460D02*
X399552Y624770D01*
X399820Y624925D01*
X400127Y624977D01*
X400510Y624874D01*
X400778Y624615D01*
X400855Y624305D01*
X400817Y623995D01*
X400663Y623737D01*
X399897Y623220D01*
X399552Y622859D01*
X399322Y622342D01*
X399245Y621877D01*
X400855D01*
G01X369442Y624450D02*
X369672Y624760D01*
X369940Y624915D01*
X370247Y624967D01*
X370630Y624864D01*
X370898Y624605D01*
X370975Y624295D01*
X370937Y623985D01*
X370783Y623727D01*
X370017Y623210D01*
X369672Y622849D01*
X369442Y622332D01*
X369365Y621867D01*
X370975D01*
G01X372542Y624450D02*
X372772Y624760D01*
X373040Y624915D01*
X373347Y624967D01*
X373730Y624864D01*
X373998Y624605D01*
X374075Y624295D01*
X374037Y623985D01*
X373883Y623727D01*
X373117Y623210D01*
X372772Y622849D01*
X372542Y622332D01*
X372465Y621867D01*
X374075D01*
G01X376370D02*
Y624967D01*
X375910Y624347D01*
G01Y621867D02*
X376830D01*
G01X403058Y622036D02*
X403391Y621828D01*
X403766Y621703D01*
X404100D01*
X404433Y621828D01*
X404683Y622036D01*
X404808Y622328D01*
X404725Y622620D01*
X404516Y622870D01*
X404141Y623036D01*
X403641Y623120D01*
X403350Y623286D01*
X403225Y623578D01*
X403308Y623870D01*
X403516Y624078D01*
X403808Y624203D01*
X404100D01*
X404391Y624120D01*
X404641Y623911D01*
G01X406158Y621703D02*
Y624203D01*
G01X407908D02*
Y621703D01*
G01Y622953D02*
X406158D01*
G01X410133Y621703D02*
X410425Y621745D01*
X410758Y621870D01*
X410966Y622078D01*
X411050Y622370D01*
X410966Y622661D01*
X410716Y622911D01*
X410341Y623036D01*
X409925D01*
X409675Y623120D01*
X409466Y623328D01*
X409383Y623620D01*
X409508Y623911D01*
X409800Y624120D01*
X410133Y624203D01*
X410466Y624120D01*
X410758Y623911D01*
X410883Y623620D01*
X410800Y623328D01*
X410591Y623120D01*
X410341Y623036D01*
X409925D01*
X409550Y622911D01*
X409300Y622661D01*
X409216Y622370D01*
X409300Y622078D01*
X409508Y621870D01*
X409841Y621745D01*
X410133Y621703D01*
G01X412400Y624203D02*
Y621703D01*
X414066D01*
G01X416333D02*
Y624203D01*
X415833Y623703D01*
G01Y621703D02*
X416833D01*
G01X415050Y658900D02*
X447750D01*
Y640200D01*
X415050D01*
Y658900D01*
G01X413104Y640150D02*
X380404D01*
Y658850D01*
X413104D01*
Y640150D01*
G01X471246Y-38301D02*
X453246D01*
Y-56301D01*
X471246D01*
Y-38301D01*
G01X491246D02*
X473246D01*
Y-56301D01*
X491246D01*
Y-38301D01*
G01X469217Y12658D02*
X468967Y12783D01*
X468675Y12866D01*
X468342D01*
X467967Y12741D01*
X467675Y12533D01*
X467467Y12283D01*
X467300Y11866D01*
X467258Y11491D01*
X467342Y11116D01*
X467467Y10866D01*
X467717Y10616D01*
X468008Y10449D01*
X468300Y10366D01*
X468592D01*
X468883Y10449D01*
X469133Y10574D01*
X469342Y10741D01*
G01X470608Y12449D02*
X470858Y12699D01*
X471150Y12824D01*
X471483Y12866D01*
X471900Y12783D01*
X472192Y12574D01*
X472275Y12324D01*
X472233Y12074D01*
X472067Y11866D01*
X471233Y11449D01*
X470858Y11158D01*
X470608Y10741D01*
X470525Y10366D01*
X472275D01*
G01X474750Y11616D02*
X475583D01*
Y10866D01*
X475333Y10616D01*
X475042Y10449D01*
X474625Y10366D01*
X474208Y10449D01*
X473917Y10616D01*
X473667Y10866D01*
X473500Y11158D01*
X473417Y11491D01*
Y11783D01*
X473500Y12033D01*
X473667Y12324D01*
X473917Y12574D01*
X474167Y12741D01*
X474500Y12866D01*
X474792D01*
X475125Y12783D01*
X475375Y12616D01*
G01X477600Y10366D02*
Y12866D01*
X477100Y12366D01*
G01Y10366D02*
X478100D01*
G01X481200D02*
Y12866D01*
X479658Y11074D01*
X481742D01*
G01X466017Y16758D02*
X465767Y16883D01*
X465475Y16966D01*
X465142D01*
X464767Y16841D01*
X464475Y16633D01*
X464267Y16383D01*
X464100Y15966D01*
X464058Y15591D01*
X464142Y15216D01*
X464267Y14966D01*
X464517Y14716D01*
X464808Y14549D01*
X465100Y14466D01*
X465392D01*
X465683Y14549D01*
X465933Y14674D01*
X466142Y14841D01*
G01X467408Y16549D02*
X467658Y16799D01*
X467950Y16924D01*
X468283Y16966D01*
X468700Y16883D01*
X468992Y16674D01*
X469075Y16424D01*
X469033Y16174D01*
X468867Y15966D01*
X468033Y15549D01*
X467658Y15258D01*
X467408Y14841D01*
X467325Y14466D01*
X469075D01*
G01X471550Y15716D02*
X472383D01*
Y14966D01*
X472133Y14716D01*
X471842Y14549D01*
X471425Y14466D01*
X471008Y14549D01*
X470717Y14716D01*
X470467Y14966D01*
X470300Y15258D01*
X470217Y15591D01*
Y15883D01*
X470300Y16133D01*
X470467Y16424D01*
X470717Y16674D01*
X470967Y16841D01*
X471300Y16966D01*
X471592D01*
X471925Y16883D01*
X472175Y16716D01*
G01X474400Y14466D02*
Y16966D01*
X473900Y16466D01*
G01Y14466D02*
X474900D01*
G01X476583Y14966D02*
X476833Y14674D01*
X477167Y14508D01*
X477542Y14466D01*
X477875Y14508D01*
X478208Y14716D01*
X478417Y14966D01*
X478458Y15216D01*
X478375Y15508D01*
X478083Y15716D01*
X477792Y15799D01*
X477417D01*
G01X477792D02*
X478042Y15924D01*
X478250Y16133D01*
X478333Y16383D01*
X478250Y16633D01*
X478042Y16841D01*
X477667Y16966D01*
X477292Y16924D01*
X476917Y16758D01*
G01X476632Y50858D02*
X476382Y50983D01*
X476090Y51066D01*
X475757D01*
X475382Y50941D01*
X475090Y50733D01*
X474882Y50483D01*
X474715Y50066D01*
X474673Y49691D01*
X474757Y49316D01*
X474882Y49066D01*
X475132Y48816D01*
X475423Y48649D01*
X475715Y48566D01*
X476007D01*
X476298Y48649D01*
X476548Y48774D01*
X476757Y48941D01*
G01X477898Y49066D02*
X478148Y48774D01*
X478482Y48608D01*
X478857Y48566D01*
X479190Y48608D01*
X479523Y48816D01*
X479732Y49066D01*
X479773Y49316D01*
X479690Y49608D01*
X479398Y49816D01*
X479107Y49899D01*
X478732D01*
G01X479107D02*
X479357Y50024D01*
X479565Y50233D01*
X479648Y50483D01*
X479565Y50733D01*
X479357Y50941D01*
X478982Y51066D01*
X478607Y51024D01*
X478232Y50858D01*
G01X482165Y49816D02*
X482998D01*
Y49066D01*
X482748Y48816D01*
X482457Y48649D01*
X482040Y48566D01*
X481623Y48649D01*
X481332Y48816D01*
X481082Y49066D01*
X480915Y49358D01*
X480832Y49691D01*
Y49983D01*
X480915Y50233D01*
X481082Y50524D01*
X481332Y50774D01*
X481582Y50941D01*
X481915Y51066D01*
X482207D01*
X482540Y50983D01*
X482790Y50816D01*
G01X484223Y50649D02*
X484473Y50899D01*
X484765Y51024D01*
X485098Y51066D01*
X485515Y50983D01*
X485807Y50774D01*
X485890Y50524D01*
X485848Y50274D01*
X485682Y50066D01*
X484848Y49649D01*
X484473Y49358D01*
X484223Y48941D01*
X484140Y48566D01*
X485890D01*
G01X474098Y55931D02*
X473848Y56056D01*
X473556Y56139D01*
X473223D01*
X472848Y56014D01*
X472556Y55806D01*
X472348Y55556D01*
X472181Y55139D01*
X472139Y54764D01*
X472223Y54389D01*
X472348Y54139D01*
X472598Y53889D01*
X472889Y53722D01*
X473181Y53639D01*
X473473D01*
X473764Y53722D01*
X474014Y53847D01*
X474223Y54014D01*
G01X475364Y54139D02*
X475614Y53847D01*
X475948Y53681D01*
X476323Y53639D01*
X476656Y53681D01*
X476989Y53889D01*
X477198Y54139D01*
X477239Y54389D01*
X477156Y54681D01*
X476864Y54889D01*
X476573Y54972D01*
X476198D01*
G01X476573D02*
X476823Y55097D01*
X477031Y55306D01*
X477114Y55556D01*
X477031Y55806D01*
X476823Y56014D01*
X476448Y56139D01*
X476073Y56097D01*
X475698Y55931D01*
G01X479631Y54889D02*
X480464D01*
Y54139D01*
X480214Y53889D01*
X479923Y53722D01*
X479506Y53639D01*
X479089Y53722D01*
X478798Y53889D01*
X478548Y54139D01*
X478381Y54431D01*
X478298Y54764D01*
Y55056D01*
X478381Y55306D01*
X478548Y55597D01*
X478798Y55847D01*
X479048Y56014D01*
X479381Y56139D01*
X479673D01*
X480006Y56056D01*
X480256Y55889D01*
G01X482481Y53639D02*
Y56139D01*
X481981Y55639D01*
G01Y53639D02*
X482981D01*
G01X454553Y48373D02*
X454303Y48498D01*
X454011Y48581D01*
X453678D01*
X453303Y48456D01*
X453011Y48248D01*
X452803Y47998D01*
X452636Y47581D01*
X452594Y47206D01*
X452678Y46831D01*
X452803Y46581D01*
X453053Y46331D01*
X453344Y46164D01*
X453636Y46081D01*
X453928D01*
X454219Y46164D01*
X454469Y46289D01*
X454678Y46456D01*
G01X455944Y48164D02*
X456194Y48414D01*
X456486Y48539D01*
X456819Y48581D01*
X457236Y48498D01*
X457528Y48289D01*
X457611Y48039D01*
X457569Y47789D01*
X457403Y47581D01*
X456569Y47164D01*
X456194Y46873D01*
X455944Y46456D01*
X455861Y46081D01*
X457611D01*
G01X460086Y47331D02*
X460919D01*
Y46581D01*
X460669Y46331D01*
X460378Y46164D01*
X459961Y46081D01*
X459544Y46164D01*
X459253Y46331D01*
X459003Y46581D01*
X458836Y46873D01*
X458753Y47206D01*
Y47498D01*
X458836Y47748D01*
X459003Y48039D01*
X459253Y48289D01*
X459503Y48456D01*
X459836Y48581D01*
X460128D01*
X460461Y48498D01*
X460711Y48331D01*
G01X462144Y47123D02*
X462436Y47414D01*
X462686Y47581D01*
X463019Y47664D01*
X463311Y47581D01*
X463519Y47414D01*
X463686Y47164D01*
X463728Y46873D01*
X463686Y46623D01*
X463519Y46373D01*
X463269Y46164D01*
X462978Y46081D01*
X462644Y46164D01*
X462353Y46414D01*
X462186Y46789D01*
X462144Y47206D01*
X462228Y47748D01*
X462353Y48039D01*
X462561Y48331D01*
X462853Y48539D01*
X463144Y48581D01*
X463436Y48498D01*
X463644Y48289D01*
G01X451079Y53628D02*
X450829Y53753D01*
X450537Y53836D01*
X450204D01*
X449829Y53711D01*
X449537Y53503D01*
X449329Y53253D01*
X449162Y52836D01*
X449120Y52461D01*
X449204Y52086D01*
X449329Y51836D01*
X449579Y51586D01*
X449870Y51419D01*
X450162Y51336D01*
X450454D01*
X450745Y51419D01*
X450995Y51544D01*
X451204Y51711D01*
G01X452470Y53419D02*
X452720Y53669D01*
X453012Y53794D01*
X453345Y53836D01*
X453762Y53753D01*
X454054Y53544D01*
X454137Y53294D01*
X454095Y53044D01*
X453929Y52836D01*
X453095Y52419D01*
X452720Y52128D01*
X452470Y51711D01*
X452387Y51336D01*
X454137D01*
G01X456612Y52586D02*
X457445D01*
Y51836D01*
X457195Y51586D01*
X456904Y51419D01*
X456487Y51336D01*
X456070Y51419D01*
X455779Y51586D01*
X455529Y51836D01*
X455362Y52128D01*
X455279Y52461D01*
Y52753D01*
X455362Y53003D01*
X455529Y53294D01*
X455779Y53544D01*
X456029Y53711D01*
X456362Y53836D01*
X456654D01*
X456987Y53753D01*
X457237Y53586D01*
G01X458545Y51711D02*
X458795Y51503D01*
X459087Y51378D01*
X459462Y51336D01*
X459837Y51419D01*
X460129Y51586D01*
X460337Y51878D01*
X460379Y52211D01*
X460295Y52544D01*
X460087Y52753D01*
X459795Y52919D01*
X459504Y52961D01*
X459212Y52919D01*
X458837Y52753D01*
X458962Y53836D01*
X460087D01*
G01X471367Y140300D02*
X474700Y147300D01*
X478033Y140300D01*
G01X476833Y142750D02*
X472567D01*
G01X480367Y140300D02*
Y147300D01*
X483033D01*
X484100Y146950D01*
X484900Y146483D01*
X485567Y145783D01*
X486100Y144967D01*
X486233Y143800D01*
X486100Y142633D01*
X485567Y141817D01*
X484900Y141116D01*
X484100Y140650D01*
X483033Y140300D01*
X480367D01*
G01X428500Y170000D02*
Y122600D01*
X488800D01*
Y170000D01*
X428500D01*
G01X468437Y153740D02*
Y156240D01*
X469478D01*
X469812Y156115D01*
X470020Y155948D01*
X470103Y155615D01*
X470020Y155282D01*
X469770Y155073D01*
X469478Y154948D01*
X468437D01*
G01X469478D02*
X470103Y153740D01*
G01X472370D02*
Y156240D01*
X471870Y155740D01*
G01Y153740D02*
X472870D01*
G01X474553Y156240D02*
Y154448D01*
X474720Y154073D01*
X475053Y153823D01*
X475470Y153740D01*
X475887Y153823D01*
X476220Y154073D01*
X476387Y154448D01*
Y156240D01*
G01X477653Y154115D02*
X477903Y153907D01*
X478195Y153782D01*
X478570Y153740D01*
X478945Y153823D01*
X479237Y153990D01*
X479445Y154282D01*
X479487Y154615D01*
X479403Y154948D01*
X479195Y155157D01*
X478903Y155323D01*
X478612Y155365D01*
X478320Y155323D01*
X477945Y155157D01*
X478070Y156240D01*
X479195D01*
G01X480753Y154240D02*
X481003Y153948D01*
X481337Y153782D01*
X481712Y153740D01*
X482045Y153782D01*
X482378Y153990D01*
X482587Y154240D01*
X482628Y154490D01*
X482545Y154782D01*
X482253Y154990D01*
X481962Y155073D01*
X481587D01*
G01X481962D02*
X482212Y155198D01*
X482420Y155407D01*
X482503Y155657D01*
X482420Y155907D01*
X482212Y156115D01*
X481837Y156240D01*
X481462Y156198D01*
X481087Y156032D01*
G01X452547Y153820D02*
Y156320D01*
X453588D01*
X453922Y156195D01*
X454130Y156028D01*
X454213Y155695D01*
X454130Y155362D01*
X453880Y155153D01*
X453588Y155028D01*
X452547D01*
G01X453588D02*
X454213Y153820D01*
G01X456480D02*
Y156320D01*
X455980Y155820D01*
G01Y153820D02*
X456980D01*
G01X458663Y156320D02*
Y154528D01*
X458830Y154153D01*
X459163Y153903D01*
X459580Y153820D01*
X459997Y153903D01*
X460330Y154153D01*
X460497Y154528D01*
Y156320D01*
G01X463180Y153820D02*
Y156320D01*
X461638Y154528D01*
X463722D01*
G01X465780Y153820D02*
Y156320D01*
X465280Y155820D01*
G01Y153820D02*
X466280D01*
G01X452547Y150320D02*
Y152820D01*
X453588D01*
X453922Y152695D01*
X454130Y152528D01*
X454213Y152195D01*
X454130Y151862D01*
X453880Y151653D01*
X453588Y151528D01*
X452547D01*
G01X453588D02*
X454213Y150320D01*
G01X456480D02*
Y152820D01*
X455980Y152320D01*
G01Y150320D02*
X456980D01*
G01X458663Y152820D02*
Y151028D01*
X458830Y150653D01*
X459163Y150403D01*
X459580Y150320D01*
X459997Y150403D01*
X460330Y150653D01*
X460497Y151028D01*
Y152820D01*
G01X461763Y150695D02*
X462013Y150487D01*
X462305Y150362D01*
X462680Y150320D01*
X463055Y150403D01*
X463347Y150570D01*
X463555Y150862D01*
X463597Y151195D01*
X463513Y151528D01*
X463305Y151737D01*
X463013Y151903D01*
X462722Y151945D01*
X462430Y151903D01*
X462055Y151737D01*
X462180Y152820D01*
X463305D01*
G01X464863Y150695D02*
X465113Y150487D01*
X465405Y150362D01*
X465780Y150320D01*
X466155Y150403D01*
X466447Y150570D01*
X466655Y150862D01*
X466697Y151195D01*
X466613Y151528D01*
X466405Y151737D01*
X466113Y151903D01*
X465822Y151945D01*
X465530Y151903D01*
X465155Y151737D01*
X465280Y152820D01*
X466405D01*
G01X468260Y134657D02*
X465760D01*
Y135698D01*
X465885Y136032D01*
X466052Y136240D01*
X466385Y136323D01*
X466718Y136240D01*
X466927Y135990D01*
X467052Y135698D01*
Y134657D01*
G01Y135698D02*
X468260Y136323D01*
G01X466177Y137798D02*
X465927Y138048D01*
X465802Y138340D01*
X465760Y138673D01*
X465843Y139090D01*
X466052Y139382D01*
X466302Y139465D01*
X466552Y139423D01*
X466760Y139257D01*
X467177Y138423D01*
X467468Y138048D01*
X467885Y137798D01*
X468260Y137715D01*
Y139465D01*
G01X465760Y140773D02*
X467552D01*
X467927Y140940D01*
X468177Y141273D01*
X468260Y141690D01*
X468177Y142107D01*
X467927Y142440D01*
X467552Y142607D01*
X465760D01*
G01X468260Y145290D02*
X465760D01*
X467552Y143748D01*
Y145832D01*
G01X468260Y147890D02*
X465760D01*
X466260Y147390D01*
G01X468260D02*
Y148390D01*
G01X464760Y134657D02*
X462260D01*
Y135698D01*
X462385Y136032D01*
X462552Y136240D01*
X462885Y136323D01*
X463218Y136240D01*
X463427Y135990D01*
X463552Y135698D01*
Y134657D01*
G01Y135698D02*
X464760Y136323D01*
G01Y138590D02*
X462260D01*
X462760Y138090D01*
G01X464760D02*
Y139090D01*
G01X462260Y140773D02*
X464052D01*
X464427Y140940D01*
X464677Y141273D01*
X464760Y141690D01*
X464677Y142107D01*
X464427Y142440D01*
X464052Y142607D01*
X462260D01*
G01X464385Y143873D02*
X464593Y144123D01*
X464718Y144415D01*
X464760Y144790D01*
X464677Y145165D01*
X464510Y145457D01*
X464218Y145665D01*
X463885Y145707D01*
X463552Y145623D01*
X463343Y145415D01*
X463177Y145123D01*
X463135Y144832D01*
X463177Y144540D01*
X463343Y144165D01*
X462260Y144290D01*
Y145415D01*
G01X463718Y147098D02*
X463427Y147390D01*
X463260Y147640D01*
X463177Y147973D01*
X463260Y148265D01*
X463427Y148473D01*
X463677Y148640D01*
X463968Y148682D01*
X464218Y148640D01*
X464468Y148473D01*
X464677Y148223D01*
X464760Y147932D01*
X464677Y147598D01*
X464427Y147307D01*
X464052Y147140D01*
X463635Y147098D01*
X463093Y147182D01*
X462802Y147307D01*
X462510Y147515D01*
X462302Y147807D01*
X462260Y148098D01*
X462343Y148390D01*
X462552Y148598D01*
G01X461260Y134657D02*
X458760D01*
Y135698D01*
X458885Y136032D01*
X459052Y136240D01*
X459385Y136323D01*
X459718Y136240D01*
X459927Y135990D01*
X460052Y135698D01*
Y134657D01*
G01Y135698D02*
X461260Y136323D01*
G01Y138590D02*
X458760D01*
X459260Y138090D01*
G01X461260D02*
Y139090D01*
G01X458760Y140773D02*
X460552D01*
X460927Y140940D01*
X461177Y141273D01*
X461260Y141690D01*
X461177Y142107D01*
X460927Y142440D01*
X460552Y142607D01*
X458760D01*
G01X460885Y143873D02*
X461093Y144123D01*
X461218Y144415D01*
X461260Y144790D01*
X461177Y145165D01*
X461010Y145457D01*
X460718Y145665D01*
X460385Y145707D01*
X460052Y145623D01*
X459843Y145415D01*
X459677Y145123D01*
X459635Y144832D01*
X459677Y144540D01*
X459843Y144165D01*
X458760Y144290D01*
Y145415D01*
G01X461260Y147890D02*
X461218Y148182D01*
X461093Y148515D01*
X460885Y148723D01*
X460593Y148807D01*
X460302Y148723D01*
X460052Y148473D01*
X459927Y148098D01*
Y147682D01*
X459843Y147432D01*
X459635Y147223D01*
X459343Y147140D01*
X459052Y147265D01*
X458843Y147557D01*
X458760Y147890D01*
X458843Y148223D01*
X459052Y148515D01*
X459343Y148640D01*
X459635Y148557D01*
X459843Y148348D01*
X459927Y148098D01*
Y147682D01*
X460052Y147307D01*
X460302Y147057D01*
X460593Y146973D01*
X460885Y147057D01*
X461093Y147265D01*
X461218Y147598D01*
X461260Y147890D01*
G01X430907Y141650D02*
Y144150D01*
X431948D01*
X432282Y144025D01*
X432490Y143858D01*
X432573Y143525D01*
X432490Y143192D01*
X432240Y142983D01*
X431948Y142858D01*
X430907D01*
G01X431948D02*
X432573Y141650D01*
G01X434048Y142692D02*
X434340Y142983D01*
X434590Y143150D01*
X434923Y143233D01*
X435215Y143150D01*
X435423Y142983D01*
X435590Y142733D01*
X435632Y142442D01*
X435590Y142192D01*
X435423Y141942D01*
X435173Y141733D01*
X434882Y141650D01*
X434548Y141733D01*
X434257Y141983D01*
X434090Y142358D01*
X434048Y142775D01*
X434132Y143317D01*
X434257Y143608D01*
X434465Y143900D01*
X434757Y144108D01*
X435048Y144150D01*
X435340Y144067D01*
X435548Y143858D01*
G01X436690Y144150D02*
X437273Y141650D01*
X437940Y144150D01*
X438607Y141650D01*
X439190Y144150D01*
G01X441540Y141650D02*
Y144150D01*
X439998Y142358D01*
X442082D01*
G01X444640Y141650D02*
Y144150D01*
X443098Y142358D01*
X445182D01*
G01X445690Y125727D02*
X443190D01*
Y126768D01*
X443315Y127102D01*
X443482Y127310D01*
X443815Y127393D01*
X444148Y127310D01*
X444357Y127060D01*
X444482Y126768D01*
Y125727D01*
G01Y126768D02*
X445690Y127393D01*
G01X444648Y128868D02*
X444357Y129160D01*
X444190Y129410D01*
X444107Y129743D01*
X444190Y130035D01*
X444357Y130243D01*
X444607Y130410D01*
X444898Y130452D01*
X445148Y130410D01*
X445398Y130243D01*
X445607Y129993D01*
X445690Y129702D01*
X445607Y129368D01*
X445357Y129077D01*
X444982Y128910D01*
X444565Y128868D01*
X444023Y128952D01*
X443732Y129077D01*
X443440Y129285D01*
X443232Y129577D01*
X443190Y129868D01*
X443273Y130160D01*
X443482Y130368D01*
G01X443190Y131510D02*
X445690Y132093D01*
X443190Y132760D01*
X445690Y133427D01*
X443190Y134010D01*
G01X445690Y136360D02*
X443190D01*
X444982Y134818D01*
Y136902D01*
G01X443607Y138168D02*
X443357Y138418D01*
X443232Y138710D01*
X443190Y139043D01*
X443273Y139460D01*
X443482Y139752D01*
X443732Y139835D01*
X443982Y139793D01*
X444190Y139627D01*
X444607Y138793D01*
X444898Y138418D01*
X445315Y138168D01*
X445690Y138085D01*
Y139835D01*
G01X449640Y130257D02*
X447140D01*
Y131298D01*
X447265Y131632D01*
X447432Y131840D01*
X447765Y131923D01*
X448098Y131840D01*
X448307Y131590D01*
X448432Y131298D01*
Y130257D01*
G01Y131298D02*
X449640Y131923D01*
G01X448598Y133398D02*
X448307Y133690D01*
X448140Y133940D01*
X448057Y134273D01*
X448140Y134565D01*
X448307Y134773D01*
X448557Y134940D01*
X448848Y134982D01*
X449098Y134940D01*
X449348Y134773D01*
X449557Y134523D01*
X449640Y134232D01*
X449557Y133898D01*
X449307Y133607D01*
X448932Y133440D01*
X448515Y133398D01*
X447973Y133482D01*
X447682Y133607D01*
X447390Y133815D01*
X447182Y134107D01*
X447140Y134398D01*
X447223Y134690D01*
X447432Y134898D01*
G01X447140Y136040D02*
X449640Y136623D01*
X447140Y137290D01*
X449640Y137957D01*
X447140Y138540D01*
G01X449640Y140890D02*
X447140D01*
X448932Y139348D01*
Y141432D01*
G01X449140Y142573D02*
X449432Y142823D01*
X449598Y143157D01*
X449640Y143532D01*
X449598Y143865D01*
X449390Y144198D01*
X449140Y144407D01*
X448890Y144448D01*
X448598Y144365D01*
X448390Y144073D01*
X448307Y143782D01*
Y143407D01*
G01Y143782D02*
X448182Y144032D01*
X447973Y144240D01*
X447723Y144323D01*
X447473Y144240D01*
X447265Y144032D01*
X447140Y143657D01*
X447182Y143282D01*
X447348Y142907D01*
G01X442190Y125727D02*
X439690D01*
Y126768D01*
X439815Y127102D01*
X439982Y127310D01*
X440315Y127393D01*
X440648Y127310D01*
X440857Y127060D01*
X440982Y126768D01*
Y125727D01*
G01Y126768D02*
X442190Y127393D01*
G01X441148Y128868D02*
X440857Y129160D01*
X440690Y129410D01*
X440607Y129743D01*
X440690Y130035D01*
X440857Y130243D01*
X441107Y130410D01*
X441398Y130452D01*
X441648Y130410D01*
X441898Y130243D01*
X442107Y129993D01*
X442190Y129702D01*
X442107Y129368D01*
X441857Y129077D01*
X441482Y128910D01*
X441065Y128868D01*
X440523Y128952D01*
X440232Y129077D01*
X439940Y129285D01*
X439732Y129577D01*
X439690Y129868D01*
X439773Y130160D01*
X439982Y130368D01*
G01X439690Y131510D02*
X442190Y132093D01*
X439690Y132760D01*
X442190Y133427D01*
X439690Y134010D01*
G01X442190Y136360D02*
X439690D01*
X441482Y134818D01*
Y136902D01*
G01X441815Y138043D02*
X442023Y138293D01*
X442148Y138585D01*
X442190Y138960D01*
X442107Y139335D01*
X441940Y139627D01*
X441648Y139835D01*
X441315Y139877D01*
X440982Y139793D01*
X440773Y139585D01*
X440607Y139293D01*
X440565Y139002D01*
X440607Y138710D01*
X440773Y138335D01*
X439690Y138460D01*
Y139585D01*
G01X453140Y130257D02*
X450640D01*
Y131298D01*
X450765Y131632D01*
X450932Y131840D01*
X451265Y131923D01*
X451598Y131840D01*
X451807Y131590D01*
X451932Y131298D01*
Y130257D01*
G01Y131298D02*
X453140Y131923D01*
G01X452098Y133398D02*
X451807Y133690D01*
X451640Y133940D01*
X451557Y134273D01*
X451640Y134565D01*
X451807Y134773D01*
X452057Y134940D01*
X452348Y134982D01*
X452598Y134940D01*
X452848Y134773D01*
X453057Y134523D01*
X453140Y134232D01*
X453057Y133898D01*
X452807Y133607D01*
X452432Y133440D01*
X452015Y133398D01*
X451473Y133482D01*
X451182Y133607D01*
X450890Y133815D01*
X450682Y134107D01*
X450640Y134398D01*
X450723Y134690D01*
X450932Y134898D01*
G01X450640Y136040D02*
X453140Y136623D01*
X450640Y137290D01*
X453140Y137957D01*
X450640Y138540D01*
G01X453140Y140890D02*
X450640D01*
X452432Y139348D01*
Y141432D01*
G01X452098Y142698D02*
X451807Y142990D01*
X451640Y143240D01*
X451557Y143573D01*
X451640Y143865D01*
X451807Y144073D01*
X452057Y144240D01*
X452348Y144282D01*
X452598Y144240D01*
X452848Y144073D01*
X453057Y143823D01*
X453140Y143532D01*
X453057Y143198D01*
X452807Y142907D01*
X452432Y142740D01*
X452015Y142698D01*
X451473Y142782D01*
X451182Y142907D01*
X450890Y143115D01*
X450682Y143407D01*
X450640Y143698D01*
X450723Y143990D01*
X450932Y144198D01*
G01X440880Y145697D02*
X438380D01*
Y146738D01*
X438505Y147072D01*
X438672Y147280D01*
X439005Y147363D01*
X439338Y147280D01*
X439547Y147030D01*
X439672Y146738D01*
Y145697D01*
G01Y146738D02*
X440880Y147363D01*
G01Y149630D02*
X438380D01*
X438880Y149130D01*
G01X440880D02*
Y150130D01*
G01X438380Y151813D02*
X440172D01*
X440547Y151980D01*
X440797Y152313D01*
X440880Y152730D01*
X440797Y153147D01*
X440547Y153480D01*
X440172Y153647D01*
X438380D01*
G01X439838Y155038D02*
X439547Y155330D01*
X439380Y155580D01*
X439297Y155913D01*
X439380Y156205D01*
X439547Y156413D01*
X439797Y156580D01*
X440088Y156622D01*
X440338Y156580D01*
X440588Y156413D01*
X440797Y156163D01*
X440880Y155872D01*
X440797Y155538D01*
X440547Y155247D01*
X440172Y155080D01*
X439755Y155038D01*
X439213Y155122D01*
X438922Y155247D01*
X438630Y155455D01*
X438422Y155747D01*
X438380Y156038D01*
X438463Y156330D01*
X438672Y156538D01*
G01X440880Y158930D02*
X438380D01*
X438880Y158430D01*
G01X440880D02*
Y159430D01*
G01X437380Y145697D02*
X434880D01*
Y146738D01*
X435005Y147072D01*
X435172Y147280D01*
X435505Y147363D01*
X435838Y147280D01*
X436047Y147030D01*
X436172Y146738D01*
Y145697D01*
G01Y146738D02*
X437380Y147363D01*
G01X436338Y148838D02*
X436047Y149130D01*
X435880Y149380D01*
X435797Y149713D01*
X435880Y150005D01*
X436047Y150213D01*
X436297Y150380D01*
X436588Y150422D01*
X436838Y150380D01*
X437088Y150213D01*
X437297Y149963D01*
X437380Y149672D01*
X437297Y149338D01*
X437047Y149047D01*
X436672Y148880D01*
X436255Y148838D01*
X435713Y148922D01*
X435422Y149047D01*
X435130Y149255D01*
X434922Y149547D01*
X434880Y149838D01*
X434963Y150130D01*
X435172Y150338D01*
G01X434880Y151480D02*
X437380Y152063D01*
X434880Y152730D01*
X437380Y153397D01*
X434880Y153980D01*
G01X437380Y156330D02*
X434880D01*
X436672Y154788D01*
Y156872D01*
G01X437380Y158847D02*
X436838Y158930D01*
X436380Y159055D01*
X435963Y159222D01*
X435505Y159430D01*
X434880Y159763D01*
Y158097D01*
G01X468437Y157240D02*
Y159740D01*
X469478D01*
X469812Y159615D01*
X470020Y159448D01*
X470103Y159115D01*
X470020Y158782D01*
X469770Y158573D01*
X469478Y158448D01*
X468437D01*
G01X469478D02*
X470103Y157240D01*
G01X472370D02*
Y159740D01*
X471870Y159240D01*
G01Y157240D02*
X472870D01*
G01X474553Y159740D02*
Y157948D01*
X474720Y157573D01*
X475053Y157323D01*
X475470Y157240D01*
X475887Y157323D01*
X476220Y157573D01*
X476387Y157948D01*
Y159740D01*
G01X477778Y158282D02*
X478070Y158573D01*
X478320Y158740D01*
X478653Y158823D01*
X478945Y158740D01*
X479153Y158573D01*
X479320Y158323D01*
X479362Y158032D01*
X479320Y157782D01*
X479153Y157532D01*
X478903Y157323D01*
X478612Y157240D01*
X478278Y157323D01*
X477987Y157573D01*
X477820Y157948D01*
X477778Y158365D01*
X477862Y158907D01*
X477987Y159198D01*
X478195Y159490D01*
X478487Y159698D01*
X478778Y159740D01*
X479070Y159657D01*
X479278Y159448D01*
G01X481670Y159740D02*
X481337Y159657D01*
X481087Y159448D01*
X480920Y159198D01*
X480795Y158865D01*
X480753Y158490D01*
X480795Y158115D01*
X480920Y157782D01*
X481087Y157532D01*
X481337Y157323D01*
X481670Y157240D01*
X482003Y157323D01*
X482253Y157532D01*
X482420Y157782D01*
X482545Y158115D01*
X482587Y158490D01*
X482545Y158865D01*
X482420Y159198D01*
X482253Y159448D01*
X482003Y159657D01*
X481670Y159740D01*
G01X452547Y157320D02*
Y159820D01*
X453588D01*
X453922Y159695D01*
X454130Y159528D01*
X454213Y159195D01*
X454130Y158862D01*
X453880Y158653D01*
X453588Y158528D01*
X452547D01*
G01X453588D02*
X454213Y157320D01*
G01X456480D02*
Y159820D01*
X455980Y159320D01*
G01Y157320D02*
X456980D01*
G01X458663Y159820D02*
Y158028D01*
X458830Y157653D01*
X459163Y157403D01*
X459580Y157320D01*
X459997Y157403D01*
X460330Y157653D01*
X460497Y158028D01*
Y159820D01*
G01X461763Y157820D02*
X462013Y157528D01*
X462347Y157362D01*
X462722Y157320D01*
X463055Y157362D01*
X463388Y157570D01*
X463597Y157820D01*
X463638Y158070D01*
X463555Y158362D01*
X463263Y158570D01*
X462972Y158653D01*
X462597D01*
G01X462972D02*
X463222Y158778D01*
X463430Y158987D01*
X463513Y159237D01*
X463430Y159487D01*
X463222Y159695D01*
X462847Y159820D01*
X462472Y159778D01*
X462097Y159612D01*
G01X464863Y157695D02*
X465113Y157487D01*
X465405Y157362D01*
X465780Y157320D01*
X466155Y157403D01*
X466447Y157570D01*
X466655Y157862D01*
X466697Y158195D01*
X466613Y158528D01*
X466405Y158737D01*
X466113Y158903D01*
X465822Y158945D01*
X465530Y158903D01*
X465155Y158737D01*
X465280Y159820D01*
X466405D01*
G01X452547Y160820D02*
Y163320D01*
X453588D01*
X453922Y163195D01*
X454130Y163028D01*
X454213Y162695D01*
X454130Y162362D01*
X453880Y162153D01*
X453588Y162028D01*
X452547D01*
G01X453588D02*
X454213Y160820D01*
G01X456480D02*
Y163320D01*
X455980Y162820D01*
G01Y160820D02*
X456980D01*
G01X458663Y163320D02*
Y161528D01*
X458830Y161153D01*
X459163Y160903D01*
X459580Y160820D01*
X459997Y160903D01*
X460330Y161153D01*
X460497Y161528D01*
Y163320D01*
G01X461888Y161862D02*
X462180Y162153D01*
X462430Y162320D01*
X462763Y162403D01*
X463055Y162320D01*
X463263Y162153D01*
X463430Y161903D01*
X463472Y161612D01*
X463430Y161362D01*
X463263Y161112D01*
X463013Y160903D01*
X462722Y160820D01*
X462388Y160903D01*
X462097Y161153D01*
X461930Y161528D01*
X461888Y161945D01*
X461972Y162487D01*
X462097Y162778D01*
X462305Y163070D01*
X462597Y163278D01*
X462888Y163320D01*
X463180Y163237D01*
X463388Y163028D01*
G01X464988Y162903D02*
X465238Y163153D01*
X465530Y163278D01*
X465863Y163320D01*
X466280Y163237D01*
X466572Y163028D01*
X466655Y162778D01*
X466613Y162528D01*
X466447Y162320D01*
X465613Y161903D01*
X465238Y161612D01*
X464988Y161195D01*
X464905Y160820D01*
X466655D01*
G01X432657Y163292D02*
X432407Y163417D01*
X432115Y163500D01*
X431782D01*
X431407Y163375D01*
X431115Y163167D01*
X430907Y162917D01*
X430740Y162500D01*
X430698Y162125D01*
X430782Y161750D01*
X430907Y161500D01*
X431157Y161250D01*
X431448Y161083D01*
X431740Y161000D01*
X432032D01*
X432323Y161083D01*
X432573Y161208D01*
X432782Y161375D01*
G01X434840Y161000D02*
Y163500D01*
X434340Y163000D01*
G01Y161000D02*
X435340D01*
G01X437940Y163500D02*
X437607Y163417D01*
X437357Y163208D01*
X437190Y162958D01*
X437065Y162625D01*
X437023Y162250D01*
X437065Y161875D01*
X437190Y161542D01*
X437357Y161292D01*
X437607Y161083D01*
X437940Y161000D01*
X438273Y161083D01*
X438523Y161292D01*
X438690Y161542D01*
X438815Y161875D01*
X438857Y162250D01*
X438815Y162625D01*
X438690Y162958D01*
X438523Y163208D01*
X438273Y163417D01*
X437940Y163500D01*
G01X439790D02*
X440373Y161000D01*
X441040Y163500D01*
X441707Y161000D01*
X442290Y163500D01*
G01X444640Y161000D02*
Y163500D01*
X443098Y161708D01*
X445182D01*
G01X422716Y175701D02*
Y172601D01*
X424134Y174823D01*
X422218D01*
G01X420804Y173118D02*
X420574Y172808D01*
X420306Y172653D01*
X419999Y172601D01*
X419616Y172704D01*
X419348Y172963D01*
X419271Y173273D01*
X419309Y173583D01*
X419463Y173841D01*
X420229Y174358D01*
X420574Y174719D01*
X420804Y175236D01*
X420881Y175701D01*
X419271D01*
G01X426031Y179404D02*
Y176304D01*
X427449Y178526D01*
X425533D01*
G01X423391Y179404D02*
Y176304D01*
X423851Y176924D01*
G01Y179404D02*
X422931D01*
G01X429476Y175701D02*
Y172601D01*
X430894Y174823D01*
X428978D01*
G01X426836Y172601D02*
X427143Y172704D01*
X427373Y172963D01*
X427526Y173273D01*
X427641Y173686D01*
X427679Y174151D01*
X427641Y174616D01*
X427526Y175029D01*
X427373Y175339D01*
X427143Y175598D01*
X426836Y175701D01*
X426529Y175598D01*
X426299Y175339D01*
X426146Y175029D01*
X426031Y174616D01*
X425993Y174151D01*
X426031Y173686D01*
X426146Y173273D01*
X426299Y172963D01*
X426529Y172704D01*
X426836Y172601D01*
G01X434093Y178784D02*
X433863Y179146D01*
X433557Y179352D01*
X433212Y179404D01*
X432905Y179352D01*
X432598Y179094D01*
X432407Y178784D01*
X432368Y178474D01*
X432445Y178112D01*
X432713Y177854D01*
X432982Y177751D01*
X433327D01*
G01X432982D02*
X432752Y177596D01*
X432560Y177337D01*
X432483Y177027D01*
X432560Y176717D01*
X432752Y176459D01*
X433097Y176304D01*
X433442Y176356D01*
X433787Y176562D01*
G01X430802Y179042D02*
X430533Y179301D01*
X430227Y179404D01*
X429920Y179301D01*
X429652Y178991D01*
X429460Y178526D01*
X429383Y178061D01*
Y177492D01*
X429460Y177027D01*
X429652Y176614D01*
X429882Y176407D01*
X430150Y176304D01*
X430457Y176407D01*
X430687Y176614D01*
X430840Y176924D01*
X430917Y177337D01*
X430840Y177699D01*
X430648Y178061D01*
X430418Y178267D01*
X430150Y178319D01*
X429843Y178216D01*
X429613Y177957D01*
X429383Y177492D01*
G01X437539Y175081D02*
X437309Y175443D01*
X437003Y175649D01*
X436658Y175701D01*
X436351Y175649D01*
X436044Y175391D01*
X435853Y175081D01*
X435814Y174771D01*
X435891Y174409D01*
X436159Y174151D01*
X436428Y174048D01*
X436773D01*
G01X436428D02*
X436198Y173893D01*
X436006Y173634D01*
X435929Y173324D01*
X436006Y173014D01*
X436198Y172756D01*
X436543Y172601D01*
X436888Y172653D01*
X437233Y172859D01*
G01X433596Y175701D02*
X433328Y175649D01*
X433021Y175494D01*
X432829Y175236D01*
X432753Y174874D01*
X432829Y174513D01*
X433059Y174203D01*
X433404Y174048D01*
X433788D01*
X434018Y173944D01*
X434209Y173686D01*
X434286Y173324D01*
X434171Y172963D01*
X433903Y172704D01*
X433596Y172601D01*
X433289Y172704D01*
X433021Y172963D01*
X432906Y173324D01*
X432983Y173686D01*
X433174Y173944D01*
X433404Y174048D01*
X433788D01*
X434133Y174203D01*
X434363Y174513D01*
X434439Y174874D01*
X434363Y175236D01*
X434171Y175494D01*
X433864Y175649D01*
X433596Y175701D01*
G01X440853Y178784D02*
X440623Y179146D01*
X440317Y179352D01*
X439972Y179404D01*
X439665Y179352D01*
X439358Y179094D01*
X439167Y178784D01*
X439128Y178474D01*
X439205Y178112D01*
X439473Y177854D01*
X439742Y177751D01*
X440087D01*
G01X439742D02*
X439512Y177596D01*
X439320Y177337D01*
X439243Y177027D01*
X439320Y176717D01*
X439512Y176459D01*
X439857Y176304D01*
X440202Y176356D01*
X440547Y176562D01*
G01X436987Y179404D02*
X436910Y178732D01*
X436795Y178164D01*
X436642Y177647D01*
X436450Y177079D01*
X436143Y176304D01*
X437677D01*
G01X444298Y175081D02*
X444068Y175443D01*
X443762Y175649D01*
X443417Y175701D01*
X443110Y175649D01*
X442803Y175391D01*
X442612Y175081D01*
X442573Y174771D01*
X442650Y174409D01*
X442918Y174151D01*
X443187Y174048D01*
X443532D01*
G01X443187D02*
X442957Y173893D01*
X442765Y173634D01*
X442688Y173324D01*
X442765Y173014D01*
X442957Y172756D01*
X443302Y172601D01*
X443647Y172653D01*
X443992Y172859D01*
G01X441083Y174409D02*
X440815Y174048D01*
X440585Y173841D01*
X440278Y173738D01*
X440010Y173841D01*
X439818Y174048D01*
X439665Y174358D01*
X439627Y174719D01*
X439665Y175029D01*
X439818Y175339D01*
X440048Y175598D01*
X440317Y175701D01*
X440623Y175598D01*
X440892Y175288D01*
X441045Y174823D01*
X441083Y174306D01*
X441007Y173634D01*
X440892Y173273D01*
X440700Y172911D01*
X440432Y172653D01*
X440163Y172601D01*
X439895Y172704D01*
X439703Y172963D01*
G01X447613Y178784D02*
X447383Y179146D01*
X447077Y179352D01*
X446732Y179404D01*
X446425Y179352D01*
X446118Y179094D01*
X445927Y178784D01*
X445888Y178474D01*
X445965Y178112D01*
X446233Y177854D01*
X446502Y177751D01*
X446847D01*
G01X446502D02*
X446272Y177596D01*
X446080Y177337D01*
X446003Y177027D01*
X446080Y176717D01*
X446272Y176459D01*
X446617Y176304D01*
X446962Y176356D01*
X447307Y176562D01*
G01X444513Y178939D02*
X444283Y179197D01*
X444015Y179352D01*
X443670Y179404D01*
X443325Y179301D01*
X443057Y179094D01*
X442865Y178732D01*
X442827Y178319D01*
X442903Y177906D01*
X443095Y177647D01*
X443363Y177441D01*
X443632Y177389D01*
X443900Y177441D01*
X444245Y177647D01*
X444130Y176304D01*
X443095D01*
G01X451058Y175081D02*
X450828Y175443D01*
X450522Y175649D01*
X450177Y175701D01*
X449870Y175649D01*
X449563Y175391D01*
X449372Y175081D01*
X449333Y174771D01*
X449410Y174409D01*
X449678Y174151D01*
X449947Y174048D01*
X450292D01*
G01X449947D02*
X449717Y173893D01*
X449525Y173634D01*
X449448Y173324D01*
X449525Y173014D01*
X449717Y172756D01*
X450062Y172601D01*
X450407Y172653D01*
X450752Y172859D01*
G01X446655Y175701D02*
Y172601D01*
X448073Y174823D01*
X446157D01*
G01X454373Y178784D02*
X454143Y179146D01*
X453837Y179352D01*
X453492Y179404D01*
X453185Y179352D01*
X452878Y179094D01*
X452687Y178784D01*
X452648Y178474D01*
X452725Y178112D01*
X452993Y177854D01*
X453262Y177751D01*
X453607D01*
G01X453262D02*
X453032Y177596D01*
X452840Y177337D01*
X452763Y177027D01*
X452840Y176717D01*
X453032Y176459D01*
X453377Y176304D01*
X453722Y176356D01*
X454067Y176562D01*
G01X451273Y178784D02*
X451043Y179146D01*
X450737Y179352D01*
X450392Y179404D01*
X450085Y179352D01*
X449778Y179094D01*
X449587Y178784D01*
X449548Y178474D01*
X449625Y178112D01*
X449893Y177854D01*
X450162Y177751D01*
X450507D01*
G01X450162D02*
X449932Y177596D01*
X449740Y177337D01*
X449663Y177027D01*
X449740Y176717D01*
X449932Y176459D01*
X450277Y176304D01*
X450622Y176356D01*
X450967Y176562D01*
G01X457818Y175081D02*
X457588Y175443D01*
X457282Y175649D01*
X456937Y175701D01*
X456630Y175649D01*
X456323Y175391D01*
X456132Y175081D01*
X456093Y174771D01*
X456170Y174409D01*
X456438Y174151D01*
X456707Y174048D01*
X457052D01*
G01X456707D02*
X456477Y173893D01*
X456285Y173634D01*
X456208Y173324D01*
X456285Y173014D01*
X456477Y172756D01*
X456822Y172601D01*
X457167Y172653D01*
X457512Y172859D01*
G01X454603Y173118D02*
X454373Y172808D01*
X454105Y172653D01*
X453798Y172601D01*
X453415Y172704D01*
X453147Y172963D01*
X453070Y173273D01*
X453108Y173583D01*
X453262Y173841D01*
X454028Y174358D01*
X454373Y174719D01*
X454603Y175236D01*
X454680Y175701D01*
X453070D01*
G01X461133Y178784D02*
X460903Y179146D01*
X460597Y179352D01*
X460252Y179404D01*
X459945Y179352D01*
X459638Y179094D01*
X459447Y178784D01*
X459408Y178474D01*
X459485Y178112D01*
X459753Y177854D01*
X460022Y177751D01*
X460367D01*
G01X460022D02*
X459792Y177596D01*
X459600Y177337D01*
X459523Y177027D01*
X459600Y176717D01*
X459792Y176459D01*
X460137Y176304D01*
X460482Y176356D01*
X460827Y176562D01*
G01X457190Y179404D02*
Y176304D01*
X457650Y176924D01*
G01Y179404D02*
X456730D01*
G01X464578Y175081D02*
X464348Y175443D01*
X464042Y175649D01*
X463697Y175701D01*
X463390Y175649D01*
X463083Y175391D01*
X462892Y175081D01*
X462853Y174771D01*
X462930Y174409D01*
X463198Y174151D01*
X463467Y174048D01*
X463812D01*
G01X463467D02*
X463237Y173893D01*
X463045Y173634D01*
X462968Y173324D01*
X463045Y173014D01*
X463237Y172756D01*
X463582Y172601D01*
X463927Y172653D01*
X464272Y172859D01*
G01X460635Y172601D02*
X460942Y172704D01*
X461172Y172963D01*
X461325Y173273D01*
X461440Y173686D01*
X461478Y174151D01*
X461440Y174616D01*
X461325Y175029D01*
X461172Y175339D01*
X460942Y175598D01*
X460635Y175701D01*
X460328Y175598D01*
X460098Y175339D01*
X459945Y175029D01*
X459830Y174616D01*
X459792Y174151D01*
X459830Y173686D01*
X459945Y173273D01*
X460098Y172963D01*
X460328Y172704D01*
X460635Y172601D01*
G01X467778Y176821D02*
X467548Y176511D01*
X467280Y176356D01*
X466973Y176304D01*
X466590Y176407D01*
X466322Y176666D01*
X466245Y176976D01*
X466283Y177286D01*
X466437Y177544D01*
X467203Y178061D01*
X467548Y178422D01*
X467778Y178939D01*
X467855Y179404D01*
X466245D01*
G01X464602Y179042D02*
X464333Y179301D01*
X464027Y179404D01*
X463720Y179301D01*
X463452Y178991D01*
X463260Y178526D01*
X463183Y178061D01*
Y177492D01*
X463260Y177027D01*
X463452Y176614D01*
X463682Y176407D01*
X463950Y176304D01*
X464257Y176407D01*
X464487Y176614D01*
X464640Y176924D01*
X464717Y177337D01*
X464640Y177699D01*
X464448Y178061D01*
X464218Y178267D01*
X463950Y178319D01*
X463643Y178216D01*
X463413Y177957D01*
X463183Y177492D01*
G01X471223Y173118D02*
X470993Y172808D01*
X470725Y172653D01*
X470418Y172601D01*
X470035Y172704D01*
X469767Y172963D01*
X469690Y173273D01*
X469728Y173583D01*
X469882Y173841D01*
X470648Y174358D01*
X470993Y174719D01*
X471223Y175236D01*
X471300Y175701D01*
X469690D01*
G01X467395D02*
X467127Y175649D01*
X466820Y175494D01*
X466628Y175236D01*
X466552Y174874D01*
X466628Y174513D01*
X466858Y174203D01*
X467203Y174048D01*
X467587D01*
X467817Y173944D01*
X468008Y173686D01*
X468085Y173324D01*
X467970Y172963D01*
X467702Y172704D01*
X467395Y172601D01*
X467088Y172704D01*
X466820Y172963D01*
X466705Y173324D01*
X466782Y173686D01*
X466973Y173944D01*
X467203Y174048D01*
X467587D01*
X467932Y174203D01*
X468162Y174513D01*
X468238Y174874D01*
X468162Y175236D01*
X467970Y175494D01*
X467663Y175649D01*
X467395Y175701D01*
G01X474537Y176821D02*
X474307Y176511D01*
X474039Y176356D01*
X473732Y176304D01*
X473349Y176407D01*
X473081Y176666D01*
X473004Y176976D01*
X473042Y177286D01*
X473196Y177544D01*
X473962Y178061D01*
X474307Y178422D01*
X474537Y178939D01*
X474614Y179404D01*
X473004D01*
G01X470786D02*
X470709Y178732D01*
X470594Y178164D01*
X470441Y177647D01*
X470249Y177079D01*
X469942Y176304D01*
X471476D01*
G01X477983Y173118D02*
X477753Y172808D01*
X477485Y172653D01*
X477178Y172601D01*
X476795Y172704D01*
X476527Y172963D01*
X476450Y173273D01*
X476488Y173583D01*
X476642Y173841D01*
X477408Y174358D01*
X477753Y174719D01*
X477983Y175236D01*
X478060Y175701D01*
X476450D01*
G01X474883Y174409D02*
X474615Y174048D01*
X474385Y173841D01*
X474078Y173738D01*
X473810Y173841D01*
X473618Y174048D01*
X473465Y174358D01*
X473427Y174719D01*
X473465Y175029D01*
X473618Y175339D01*
X473848Y175598D01*
X474117Y175701D01*
X474423Y175598D01*
X474692Y175288D01*
X474845Y174823D01*
X474883Y174306D01*
X474807Y173634D01*
X474692Y173273D01*
X474500Y172911D01*
X474232Y172653D01*
X473963Y172601D01*
X473695Y172704D01*
X473503Y172963D01*
G01X481297Y176821D02*
X481067Y176511D01*
X480799Y176356D01*
X480492Y176304D01*
X480109Y176407D01*
X479841Y176666D01*
X479764Y176976D01*
X479802Y177286D01*
X479956Y177544D01*
X480722Y178061D01*
X481067Y178422D01*
X481297Y178939D01*
X481374Y179404D01*
X479764D01*
G01X478312Y178939D02*
X478082Y179197D01*
X477814Y179352D01*
X477469Y179404D01*
X477124Y179301D01*
X476856Y179094D01*
X476664Y178732D01*
X476626Y178319D01*
X476702Y177906D01*
X476894Y177647D01*
X477162Y177441D01*
X477431Y177389D01*
X477699Y177441D01*
X478044Y177647D01*
X477929Y176304D01*
X476894D01*
G01X450200Y502400D02*
X485300D01*
Y487700D01*
X553600D01*
Y428800D01*
X450200D01*
Y502400D01*
G01X464250Y454077D02*
X461750D01*
Y455118D01*
X461875Y455452D01*
X462042Y455660D01*
X462375Y455743D01*
X462708Y455660D01*
X462917Y455410D01*
X463042Y455118D01*
Y454077D01*
G01Y455118D02*
X464250Y455743D01*
G01X462167Y457218D02*
X461917Y457468D01*
X461792Y457760D01*
X461750Y458093D01*
X461833Y458510D01*
X462042Y458802D01*
X462292Y458885D01*
X462542Y458843D01*
X462750Y458677D01*
X463167Y457843D01*
X463458Y457468D01*
X463875Y457218D01*
X464250Y457135D01*
Y458885D01*
G01X463875Y460193D02*
X464083Y460443D01*
X464208Y460735D01*
X464250Y461110D01*
X464167Y461485D01*
X464000Y461777D01*
X463708Y461985D01*
X463375Y462027D01*
X463042Y461943D01*
X462833Y461735D01*
X462667Y461443D01*
X462625Y461152D01*
X462667Y460860D01*
X462833Y460485D01*
X461750Y460610D01*
Y461735D01*
G01Y462960D02*
X464250Y463543D01*
X461750Y464210D01*
X464250Y464877D01*
X461750Y465460D01*
G01X462167Y466518D02*
X461917Y466768D01*
X461792Y467060D01*
X461750Y467393D01*
X461833Y467810D01*
X462042Y468102D01*
X462292Y468185D01*
X462542Y468143D01*
X462750Y467977D01*
X463167Y467143D01*
X463458Y466768D01*
X463875Y466518D01*
X464250Y466435D01*
Y468185D01*
G01X463875Y469493D02*
X464083Y469743D01*
X464208Y470035D01*
X464250Y470410D01*
X464167Y470785D01*
X464000Y471077D01*
X463708Y471285D01*
X463375Y471327D01*
X463042Y471243D01*
X462833Y471035D01*
X462667Y470743D01*
X462625Y470452D01*
X462667Y470160D01*
X462833Y469785D01*
X461750Y469910D01*
Y471035D01*
G01X467750Y454077D02*
X465250D01*
Y455118D01*
X465375Y455452D01*
X465542Y455660D01*
X465875Y455743D01*
X466208Y455660D01*
X466417Y455410D01*
X466542Y455118D01*
Y454077D01*
G01Y455118D02*
X467750Y455743D01*
G01X465667Y457218D02*
X465417Y457468D01*
X465292Y457760D01*
X465250Y458093D01*
X465333Y458510D01*
X465542Y458802D01*
X465792Y458885D01*
X466042Y458843D01*
X466250Y458677D01*
X466667Y457843D01*
X466958Y457468D01*
X467375Y457218D01*
X467750Y457135D01*
Y458885D01*
G01X467375Y460193D02*
X467583Y460443D01*
X467708Y460735D01*
X467750Y461110D01*
X467667Y461485D01*
X467500Y461777D01*
X467208Y461985D01*
X466875Y462027D01*
X466542Y461943D01*
X466333Y461735D01*
X466167Y461443D01*
X466125Y461152D01*
X466167Y460860D01*
X466333Y460485D01*
X465250Y460610D01*
Y461735D01*
G01Y462960D02*
X467750Y463543D01*
X465250Y464210D01*
X467750Y464877D01*
X465250Y465460D01*
G01X465667Y466518D02*
X465417Y466768D01*
X465292Y467060D01*
X465250Y467393D01*
X465333Y467810D01*
X465542Y468102D01*
X465792Y468185D01*
X466042Y468143D01*
X466250Y467977D01*
X466667Y467143D01*
X466958Y466768D01*
X467375Y466518D01*
X467750Y466435D01*
Y468185D01*
G01Y470410D02*
X465250D01*
X465750Y469910D01*
G01X467750D02*
Y470910D01*
G01X471250Y454077D02*
X468750D01*
Y455118D01*
X468875Y455452D01*
X469042Y455660D01*
X469375Y455743D01*
X469708Y455660D01*
X469917Y455410D01*
X470042Y455118D01*
Y454077D01*
G01Y455118D02*
X471250Y455743D01*
G01X469167Y457218D02*
X468917Y457468D01*
X468792Y457760D01*
X468750Y458093D01*
X468833Y458510D01*
X469042Y458802D01*
X469292Y458885D01*
X469542Y458843D01*
X469750Y458677D01*
X470167Y457843D01*
X470458Y457468D01*
X470875Y457218D01*
X471250Y457135D01*
Y458885D01*
G01X470875Y460193D02*
X471083Y460443D01*
X471208Y460735D01*
X471250Y461110D01*
X471167Y461485D01*
X471000Y461777D01*
X470708Y461985D01*
X470375Y462027D01*
X470042Y461943D01*
X469833Y461735D01*
X469667Y461443D01*
X469625Y461152D01*
X469667Y460860D01*
X469833Y460485D01*
X468750Y460610D01*
Y461735D01*
G01Y462960D02*
X471250Y463543D01*
X468750Y464210D01*
X471250Y464877D01*
X468750Y465460D01*
G01X471250Y467227D02*
X470708Y467310D01*
X470250Y467435D01*
X469833Y467602D01*
X469375Y467810D01*
X468750Y468143D01*
Y466477D01*
G01X474750Y454077D02*
X472250D01*
Y455118D01*
X472375Y455452D01*
X472542Y455660D01*
X472875Y455743D01*
X473208Y455660D01*
X473417Y455410D01*
X473542Y455118D01*
Y454077D01*
G01Y455118D02*
X474750Y455743D01*
G01X472667Y457218D02*
X472417Y457468D01*
X472292Y457760D01*
X472250Y458093D01*
X472333Y458510D01*
X472542Y458802D01*
X472792Y458885D01*
X473042Y458843D01*
X473250Y458677D01*
X473667Y457843D01*
X473958Y457468D01*
X474375Y457218D01*
X474750Y457135D01*
Y458885D01*
G01X474375Y460193D02*
X474583Y460443D01*
X474708Y460735D01*
X474750Y461110D01*
X474667Y461485D01*
X474500Y461777D01*
X474208Y461985D01*
X473875Y462027D01*
X473542Y461943D01*
X473333Y461735D01*
X473167Y461443D01*
X473125Y461152D01*
X473167Y460860D01*
X473333Y460485D01*
X472250Y460610D01*
Y461735D01*
G01Y462960D02*
X474750Y463543D01*
X472250Y464210D01*
X474750Y464877D01*
X472250Y465460D01*
G01X474375Y466393D02*
X474583Y466643D01*
X474708Y466935D01*
X474750Y467310D01*
X474667Y467685D01*
X474500Y467977D01*
X474208Y468185D01*
X473875Y468227D01*
X473542Y468143D01*
X473333Y467935D01*
X473167Y467643D01*
X473125Y467352D01*
X473167Y467060D01*
X473333Y466685D01*
X472250Y466810D01*
Y467935D01*
G01X460750Y454077D02*
X458250D01*
Y455118D01*
X458375Y455452D01*
X458542Y455660D01*
X458875Y455743D01*
X459208Y455660D01*
X459417Y455410D01*
X459542Y455118D01*
Y454077D01*
G01Y455118D02*
X460750Y455743D01*
G01X458667Y457218D02*
X458417Y457468D01*
X458292Y457760D01*
X458250Y458093D01*
X458333Y458510D01*
X458542Y458802D01*
X458792Y458885D01*
X459042Y458843D01*
X459250Y458677D01*
X459667Y457843D01*
X459958Y457468D01*
X460375Y457218D01*
X460750Y457135D01*
Y458885D01*
G01X460375Y460193D02*
X460583Y460443D01*
X460708Y460735D01*
X460750Y461110D01*
X460667Y461485D01*
X460500Y461777D01*
X460208Y461985D01*
X459875Y462027D01*
X459542Y461943D01*
X459333Y461735D01*
X459167Y461443D01*
X459125Y461152D01*
X459167Y460860D01*
X459333Y460485D01*
X458250Y460610D01*
Y461735D01*
G01Y462960D02*
X460750Y463543D01*
X458250Y464210D01*
X460750Y464877D01*
X458250Y465460D01*
G01X460750Y467310D02*
X458250D01*
X458750Y466810D01*
G01X460750D02*
Y467810D01*
G01X460458Y469702D02*
X460667Y469993D01*
X460750Y470327D01*
X460667Y470660D01*
X460417Y470952D01*
X460042Y471160D01*
X459667Y471243D01*
X459208D01*
X458833Y471160D01*
X458500Y470952D01*
X458333Y470702D01*
X458250Y470410D01*
X458333Y470077D01*
X458500Y469827D01*
X458750Y469660D01*
X459083Y469577D01*
X459375Y469660D01*
X459667Y469868D01*
X459833Y470118D01*
X459875Y470410D01*
X459792Y470743D01*
X459583Y470993D01*
X459208Y471243D01*
G01X457250Y454077D02*
X454750D01*
Y455118D01*
X454875Y455452D01*
X455042Y455660D01*
X455375Y455743D01*
X455708Y455660D01*
X455917Y455410D01*
X456042Y455118D01*
Y454077D01*
G01Y455118D02*
X457250Y455743D01*
G01X455167Y457218D02*
X454917Y457468D01*
X454792Y457760D01*
X454750Y458093D01*
X454833Y458510D01*
X455042Y458802D01*
X455292Y458885D01*
X455542Y458843D01*
X455750Y458677D01*
X456167Y457843D01*
X456458Y457468D01*
X456875Y457218D01*
X457250Y457135D01*
Y458885D01*
G01X456875Y460193D02*
X457083Y460443D01*
X457208Y460735D01*
X457250Y461110D01*
X457167Y461485D01*
X457000Y461777D01*
X456708Y461985D01*
X456375Y462027D01*
X456042Y461943D01*
X455833Y461735D01*
X455667Y461443D01*
X455625Y461152D01*
X455667Y460860D01*
X455833Y460485D01*
X454750Y460610D01*
Y461735D01*
G01Y462960D02*
X457250Y463543D01*
X454750Y464210D01*
X457250Y464877D01*
X454750Y465460D01*
G01X457250Y467810D02*
X454750D01*
X456542Y466268D01*
Y468352D01*
G01X457130Y473557D02*
X454630D01*
Y474598D01*
X454755Y474932D01*
X454922Y475140D01*
X455255Y475223D01*
X455588Y475140D01*
X455797Y474890D01*
X455922Y474598D01*
Y473557D01*
G01Y474598D02*
X457130Y475223D01*
G01X455047Y476698D02*
X454797Y476948D01*
X454672Y477240D01*
X454630Y477573D01*
X454713Y477990D01*
X454922Y478282D01*
X455172Y478365D01*
X455422Y478323D01*
X455630Y478157D01*
X456047Y477323D01*
X456338Y476948D01*
X456755Y476698D01*
X457130Y476615D01*
Y478365D01*
G01X456755Y479673D02*
X456963Y479923D01*
X457088Y480215D01*
X457130Y480590D01*
X457047Y480965D01*
X456880Y481257D01*
X456588Y481465D01*
X456255Y481507D01*
X455922Y481423D01*
X455713Y481215D01*
X455547Y480923D01*
X455505Y480632D01*
X455547Y480340D01*
X455713Y479965D01*
X454630Y480090D01*
Y481215D01*
G01Y482440D02*
X457130Y483023D01*
X454630Y483690D01*
X457130Y484357D01*
X454630Y484940D01*
G01X456630Y485873D02*
X456922Y486123D01*
X457088Y486457D01*
X457130Y486832D01*
X457088Y487165D01*
X456880Y487498D01*
X456630Y487707D01*
X456380Y487748D01*
X456088Y487665D01*
X455880Y487373D01*
X455797Y487082D01*
Y486707D01*
G01Y487082D02*
X455672Y487332D01*
X455463Y487540D01*
X455213Y487623D01*
X454963Y487540D01*
X454755Y487332D01*
X454630Y486957D01*
X454672Y486582D01*
X454838Y486207D01*
G01X454630Y489890D02*
X454713Y489557D01*
X454922Y489307D01*
X455172Y489140D01*
X455505Y489015D01*
X455880Y488973D01*
X456255Y489015D01*
X456588Y489140D01*
X456838Y489307D01*
X457047Y489557D01*
X457130Y489890D01*
X457047Y490223D01*
X456838Y490473D01*
X456588Y490640D01*
X456255Y490765D01*
X455880Y490807D01*
X455505Y490765D01*
X455172Y490640D01*
X454922Y490473D01*
X454713Y490223D01*
X454630Y489890D01*
G01X474630Y473557D02*
X472130D01*
Y474598D01*
X472255Y474932D01*
X472422Y475140D01*
X472755Y475223D01*
X473088Y475140D01*
X473297Y474890D01*
X473422Y474598D01*
Y473557D01*
G01Y474598D02*
X474630Y475223D01*
G01X472547Y476698D02*
X472297Y476948D01*
X472172Y477240D01*
X472130Y477573D01*
X472213Y477990D01*
X472422Y478282D01*
X472672Y478365D01*
X472922Y478323D01*
X473130Y478157D01*
X473547Y477323D01*
X473838Y476948D01*
X474255Y476698D01*
X474630Y476615D01*
Y478365D01*
G01X474255Y479673D02*
X474463Y479923D01*
X474588Y480215D01*
X474630Y480590D01*
X474547Y480965D01*
X474380Y481257D01*
X474088Y481465D01*
X473755Y481507D01*
X473422Y481423D01*
X473213Y481215D01*
X473047Y480923D01*
X473005Y480632D01*
X473047Y480340D01*
X473213Y479965D01*
X472130Y480090D01*
Y481215D01*
G01Y482440D02*
X474630Y483023D01*
X472130Y483690D01*
X474630Y484357D01*
X472130Y484940D01*
G01X474130Y485873D02*
X474422Y486123D01*
X474588Y486457D01*
X474630Y486832D01*
X474588Y487165D01*
X474380Y487498D01*
X474130Y487707D01*
X473880Y487748D01*
X473588Y487665D01*
X473380Y487373D01*
X473297Y487082D01*
Y486707D01*
G01Y487082D02*
X473172Y487332D01*
X472963Y487540D01*
X472713Y487623D01*
X472463Y487540D01*
X472255Y487332D01*
X472130Y486957D01*
X472172Y486582D01*
X472338Y486207D01*
G01X474630Y489890D02*
X472130D01*
X472630Y489390D01*
G01X474630D02*
Y490390D01*
G01X471130Y473557D02*
X468630D01*
Y474598D01*
X468755Y474932D01*
X468922Y475140D01*
X469255Y475223D01*
X469588Y475140D01*
X469797Y474890D01*
X469922Y474598D01*
Y473557D01*
G01Y474598D02*
X471130Y475223D01*
G01X469047Y476698D02*
X468797Y476948D01*
X468672Y477240D01*
X468630Y477573D01*
X468713Y477990D01*
X468922Y478282D01*
X469172Y478365D01*
X469422Y478323D01*
X469630Y478157D01*
X470047Y477323D01*
X470338Y476948D01*
X470755Y476698D01*
X471130Y476615D01*
Y478365D01*
G01X470755Y479673D02*
X470963Y479923D01*
X471088Y480215D01*
X471130Y480590D01*
X471047Y480965D01*
X470880Y481257D01*
X470588Y481465D01*
X470255Y481507D01*
X469922Y481423D01*
X469713Y481215D01*
X469547Y480923D01*
X469505Y480632D01*
X469547Y480340D01*
X469713Y479965D01*
X468630Y480090D01*
Y481215D01*
G01Y482440D02*
X471130Y483023D01*
X468630Y483690D01*
X471130Y484357D01*
X468630Y484940D01*
G01X470630Y485873D02*
X470922Y486123D01*
X471088Y486457D01*
X471130Y486832D01*
X471088Y487165D01*
X470880Y487498D01*
X470630Y487707D01*
X470380Y487748D01*
X470088Y487665D01*
X469880Y487373D01*
X469797Y487082D01*
Y486707D01*
G01Y487082D02*
X469672Y487332D01*
X469463Y487540D01*
X469213Y487623D01*
X468963Y487540D01*
X468755Y487332D01*
X468630Y486957D01*
X468672Y486582D01*
X468838Y486207D01*
G01X470630Y488973D02*
X470922Y489223D01*
X471088Y489557D01*
X471130Y489932D01*
X471088Y490265D01*
X470880Y490598D01*
X470630Y490807D01*
X470380Y490848D01*
X470088Y490765D01*
X469880Y490473D01*
X469797Y490182D01*
Y489807D01*
G01Y490182D02*
X469672Y490432D01*
X469463Y490640D01*
X469213Y490723D01*
X468963Y490640D01*
X468755Y490432D01*
X468630Y490057D01*
X468672Y489682D01*
X468838Y489307D01*
G01X467630Y473557D02*
X465130D01*
Y474598D01*
X465255Y474932D01*
X465422Y475140D01*
X465755Y475223D01*
X466088Y475140D01*
X466297Y474890D01*
X466422Y474598D01*
Y473557D01*
G01Y474598D02*
X467630Y475223D01*
G01X465547Y476698D02*
X465297Y476948D01*
X465172Y477240D01*
X465130Y477573D01*
X465213Y477990D01*
X465422Y478282D01*
X465672Y478365D01*
X465922Y478323D01*
X466130Y478157D01*
X466547Y477323D01*
X466838Y476948D01*
X467255Y476698D01*
X467630Y476615D01*
Y478365D01*
G01X467255Y479673D02*
X467463Y479923D01*
X467588Y480215D01*
X467630Y480590D01*
X467547Y480965D01*
X467380Y481257D01*
X467088Y481465D01*
X466755Y481507D01*
X466422Y481423D01*
X466213Y481215D01*
X466047Y480923D01*
X466005Y480632D01*
X466047Y480340D01*
X466213Y479965D01*
X465130Y480090D01*
Y481215D01*
G01Y482440D02*
X467630Y483023D01*
X465130Y483690D01*
X467630Y484357D01*
X465130Y484940D01*
G01X467630Y487290D02*
X465130D01*
X466922Y485748D01*
Y487832D01*
G01X467630Y489807D02*
X467088Y489890D01*
X466630Y490015D01*
X466213Y490182D01*
X465755Y490390D01*
X465130Y490723D01*
Y489057D01*
G01X464130Y473557D02*
X461630D01*
Y474598D01*
X461755Y474932D01*
X461922Y475140D01*
X462255Y475223D01*
X462588Y475140D01*
X462797Y474890D01*
X462922Y474598D01*
Y473557D01*
G01Y474598D02*
X464130Y475223D01*
G01X462047Y476698D02*
X461797Y476948D01*
X461672Y477240D01*
X461630Y477573D01*
X461713Y477990D01*
X461922Y478282D01*
X462172Y478365D01*
X462422Y478323D01*
X462630Y478157D01*
X463047Y477323D01*
X463338Y476948D01*
X463755Y476698D01*
X464130Y476615D01*
Y478365D01*
G01X463755Y479673D02*
X463963Y479923D01*
X464088Y480215D01*
X464130Y480590D01*
X464047Y480965D01*
X463880Y481257D01*
X463588Y481465D01*
X463255Y481507D01*
X462922Y481423D01*
X462713Y481215D01*
X462547Y480923D01*
X462505Y480632D01*
X462547Y480340D01*
X462713Y479965D01*
X461630Y480090D01*
Y481215D01*
G01Y482440D02*
X464130Y483023D01*
X461630Y483690D01*
X464130Y484357D01*
X461630Y484940D01*
G01X463755Y485873D02*
X463963Y486123D01*
X464088Y486415D01*
X464130Y486790D01*
X464047Y487165D01*
X463880Y487457D01*
X463588Y487665D01*
X463255Y487707D01*
X462922Y487623D01*
X462713Y487415D01*
X462547Y487123D01*
X462505Y486832D01*
X462547Y486540D01*
X462713Y486165D01*
X461630Y486290D01*
Y487415D01*
G01X464130Y489890D02*
X461630D01*
X462130Y489390D01*
G01X464130D02*
Y490390D01*
G01X460630Y473557D02*
X458130D01*
Y474598D01*
X458255Y474932D01*
X458422Y475140D01*
X458755Y475223D01*
X459088Y475140D01*
X459297Y474890D01*
X459422Y474598D01*
Y473557D01*
G01Y474598D02*
X460630Y475223D01*
G01X458547Y476698D02*
X458297Y476948D01*
X458172Y477240D01*
X458130Y477573D01*
X458213Y477990D01*
X458422Y478282D01*
X458672Y478365D01*
X458922Y478323D01*
X459130Y478157D01*
X459547Y477323D01*
X459838Y476948D01*
X460255Y476698D01*
X460630Y476615D01*
Y478365D01*
G01X460255Y479673D02*
X460463Y479923D01*
X460588Y480215D01*
X460630Y480590D01*
X460547Y480965D01*
X460380Y481257D01*
X460088Y481465D01*
X459755Y481507D01*
X459422Y481423D01*
X459213Y481215D01*
X459047Y480923D01*
X459005Y480632D01*
X459047Y480340D01*
X459213Y479965D01*
X458130Y480090D01*
Y481215D01*
G01Y482440D02*
X460630Y483023D01*
X458130Y483690D01*
X460630Y484357D01*
X458130Y484940D01*
G01X460630Y487290D02*
X458130D01*
X459922Y485748D01*
Y487832D01*
G01X460255Y488973D02*
X460463Y489223D01*
X460588Y489515D01*
X460630Y489890D01*
X460547Y490265D01*
X460380Y490557D01*
X460088Y490765D01*
X459755Y490807D01*
X459422Y490723D01*
X459213Y490515D01*
X459047Y490223D01*
X459005Y489932D01*
X459047Y489640D01*
X459213Y489265D01*
X458130Y489390D01*
Y490515D01*
G01X475838Y475307D02*
X475713Y475057D01*
X475630Y474765D01*
Y474432D01*
X475755Y474057D01*
X475963Y473765D01*
X476213Y473557D01*
X476630Y473390D01*
X477005Y473348D01*
X477380Y473432D01*
X477630Y473557D01*
X477880Y473807D01*
X478047Y474098D01*
X478130Y474390D01*
Y474682D01*
X478047Y474973D01*
X477922Y475223D01*
X477755Y475432D01*
G01X476047Y476698D02*
X475797Y476948D01*
X475672Y477240D01*
X475630Y477573D01*
X475713Y477990D01*
X475922Y478282D01*
X476172Y478365D01*
X476422Y478323D01*
X476630Y478157D01*
X477047Y477323D01*
X477338Y476948D01*
X477755Y476698D01*
X478130Y476615D01*
Y478365D01*
G01X477755Y479673D02*
X477963Y479923D01*
X478088Y480215D01*
X478130Y480590D01*
X478047Y480965D01*
X477880Y481257D01*
X477588Y481465D01*
X477255Y481507D01*
X476922Y481423D01*
X476713Y481215D01*
X476547Y480923D01*
X476505Y480632D01*
X476547Y480340D01*
X476713Y479965D01*
X475630Y480090D01*
Y481215D01*
G01Y482440D02*
X478130Y483023D01*
X475630Y483690D01*
X478130Y484357D01*
X475630Y484940D01*
G01X478130Y486790D02*
X475630D01*
X476130Y486290D01*
G01X478130D02*
Y487290D01*
G01Y489890D02*
X478088Y490182D01*
X477963Y490515D01*
X477755Y490723D01*
X477463Y490807D01*
X477172Y490723D01*
X476922Y490473D01*
X476797Y490098D01*
Y489682D01*
X476713Y489432D01*
X476505Y489223D01*
X476213Y489140D01*
X475922Y489265D01*
X475713Y489557D01*
X475630Y489890D01*
X475713Y490223D01*
X475922Y490515D01*
X476213Y490640D01*
X476505Y490557D01*
X476713Y490348D01*
X476797Y490098D01*
Y489682D01*
X476922Y489307D01*
X477172Y489057D01*
X477463Y488973D01*
X477755Y489057D01*
X477963Y489265D01*
X478088Y489598D01*
X478130Y489890D01*
G01X448217Y556959D02*
X447967Y557084D01*
X447675Y557167D01*
X447342D01*
X446967Y557042D01*
X446675Y556834D01*
X446467Y556584D01*
X446300Y556167D01*
X446258Y555792D01*
X446342Y555417D01*
X446467Y555167D01*
X446717Y554917D01*
X447008Y554750D01*
X447300Y554667D01*
X447592D01*
X447883Y554750D01*
X448133Y554875D01*
X448342Y555042D01*
G01X449608Y556750D02*
X449858Y557000D01*
X450150Y557125D01*
X450483Y557167D01*
X450900Y557084D01*
X451192Y556875D01*
X451275Y556625D01*
X451233Y556375D01*
X451067Y556167D01*
X450233Y555750D01*
X449858Y555459D01*
X449608Y555042D01*
X449525Y554667D01*
X451275D01*
G01X452458D02*
X453500Y557167D01*
X454542Y554667D01*
G01X454167Y555542D02*
X452833D01*
G01X456600Y554667D02*
Y557167D01*
X456100Y556667D01*
G01Y554667D02*
X457100D01*
G01X458908Y555709D02*
X459200Y556000D01*
X459450Y556167D01*
X459783Y556250D01*
X460075Y556167D01*
X460283Y556000D01*
X460450Y555750D01*
X460492Y555459D01*
X460450Y555209D01*
X460283Y554959D01*
X460033Y554750D01*
X459742Y554667D01*
X459408Y554750D01*
X459117Y555000D01*
X458950Y555375D01*
X458908Y555792D01*
X458992Y556334D01*
X459117Y556625D01*
X459325Y556917D01*
X459617Y557125D01*
X459908Y557167D01*
X460200Y557084D01*
X460408Y556875D01*
G01X478190Y551424D02*
X477940Y551549D01*
X477648Y551632D01*
X477315D01*
X476940Y551507D01*
X476648Y551299D01*
X476440Y551049D01*
X476273Y550632D01*
X476231Y550257D01*
X476315Y549882D01*
X476440Y549632D01*
X476690Y549382D01*
X476981Y549215D01*
X477273Y549132D01*
X477565D01*
X477856Y549215D01*
X478106Y549340D01*
X478315Y549507D01*
G01X479456Y549632D02*
X479706Y549340D01*
X480040Y549174D01*
X480415Y549132D01*
X480748Y549174D01*
X481081Y549382D01*
X481290Y549632D01*
X481331Y549882D01*
X481248Y550174D01*
X480956Y550382D01*
X480665Y550465D01*
X480290D01*
G01X480665D02*
X480915Y550590D01*
X481123Y550799D01*
X481206Y551049D01*
X481123Y551299D01*
X480915Y551507D01*
X480540Y551632D01*
X480165Y551590D01*
X479790Y551424D01*
G01X482431Y549132D02*
X483473Y551632D01*
X484515Y549132D01*
G01X484140Y550007D02*
X482806D01*
G01X485781Y550174D02*
X486073Y550465D01*
X486323Y550632D01*
X486656Y550715D01*
X486948Y550632D01*
X487156Y550465D01*
X487323Y550215D01*
X487365Y549924D01*
X487323Y549674D01*
X487156Y549424D01*
X486906Y549215D01*
X486615Y549132D01*
X486281Y549215D01*
X485990Y549465D01*
X485823Y549840D01*
X485781Y550257D01*
X485865Y550799D01*
X485990Y551090D01*
X486198Y551382D01*
X486490Y551590D01*
X486781Y551632D01*
X487073Y551549D01*
X487281Y551340D01*
G01X474583Y554626D02*
X474333Y554751D01*
X474041Y554834D01*
X473708D01*
X473333Y554709D01*
X473041Y554501D01*
X472833Y554251D01*
X472666Y553834D01*
X472624Y553459D01*
X472708Y553084D01*
X472833Y552834D01*
X473083Y552584D01*
X473374Y552417D01*
X473666Y552334D01*
X473958D01*
X474249Y552417D01*
X474499Y552542D01*
X474708Y552709D01*
G01X475849Y552834D02*
X476099Y552542D01*
X476433Y552376D01*
X476808Y552334D01*
X477141Y552376D01*
X477474Y552584D01*
X477683Y552834D01*
X477724Y553084D01*
X477641Y553376D01*
X477349Y553584D01*
X477058Y553667D01*
X476683D01*
G01X477058D02*
X477308Y553792D01*
X477516Y554001D01*
X477599Y554251D01*
X477516Y554501D01*
X477308Y554709D01*
X476933Y554834D01*
X476558Y554792D01*
X476183Y554626D01*
G01X478824Y552334D02*
X479866Y554834D01*
X480908Y552334D01*
G01X480533Y553209D02*
X479199D01*
G01X482049Y552709D02*
X482299Y552501D01*
X482591Y552376D01*
X482966Y552334D01*
X483341Y552417D01*
X483633Y552584D01*
X483841Y552876D01*
X483883Y553209D01*
X483799Y553542D01*
X483591Y553751D01*
X483299Y553917D01*
X483008Y553959D01*
X482716Y553917D01*
X482341Y553751D01*
X482466Y554834D01*
X483591D01*
G01X475744Y586009D02*
X475619Y585759D01*
X475536Y585467D01*
Y585134D01*
X475661Y584759D01*
X475869Y584467D01*
X476119Y584259D01*
X476536Y584092D01*
X476911Y584050D01*
X477286Y584134D01*
X477536Y584259D01*
X477786Y584509D01*
X477953Y584800D01*
X478036Y585092D01*
Y585384D01*
X477953Y585675D01*
X477828Y585925D01*
X477661Y586134D01*
G01X477536Y587275D02*
X477828Y587525D01*
X477994Y587859D01*
X478036Y588234D01*
X477994Y588567D01*
X477786Y588900D01*
X477536Y589109D01*
X477286Y589150D01*
X476994Y589067D01*
X476786Y588775D01*
X476703Y588484D01*
Y588109D01*
G01Y588484D02*
X476578Y588734D01*
X476369Y588942D01*
X476119Y589025D01*
X475869Y588942D01*
X475661Y588734D01*
X475536Y588359D01*
X475578Y587984D01*
X475744Y587609D01*
G01X478036Y590250D02*
X475536Y591292D01*
X478036Y592334D01*
G01X477161Y591959D02*
Y590625D01*
G01X475953Y593600D02*
X475703Y593850D01*
X475578Y594142D01*
X475536Y594475D01*
X475619Y594892D01*
X475828Y595184D01*
X476078Y595267D01*
X476328Y595225D01*
X476536Y595059D01*
X476953Y594225D01*
X477244Y593850D01*
X477661Y593600D01*
X478036Y593517D01*
Y595267D01*
G01X471298Y586101D02*
X471173Y585851D01*
X471090Y585559D01*
Y585226D01*
X471215Y584851D01*
X471423Y584559D01*
X471673Y584351D01*
X472090Y584184D01*
X472465Y584142D01*
X472840Y584226D01*
X473090Y584351D01*
X473340Y584601D01*
X473507Y584892D01*
X473590Y585184D01*
Y585476D01*
X473507Y585767D01*
X473382Y586017D01*
X473215Y586226D01*
G01X473090Y587367D02*
X473382Y587617D01*
X473548Y587951D01*
X473590Y588326D01*
X473548Y588659D01*
X473340Y588992D01*
X473090Y589201D01*
X472840Y589242D01*
X472548Y589159D01*
X472340Y588867D01*
X472257Y588576D01*
Y588201D01*
G01Y588576D02*
X472132Y588826D01*
X471923Y589034D01*
X471673Y589117D01*
X471423Y589034D01*
X471215Y588826D01*
X471090Y588451D01*
X471132Y588076D01*
X471298Y587701D01*
G01X473590Y590342D02*
X471090Y591384D01*
X473590Y592426D01*
G01X472715Y592051D02*
Y590717D01*
G01X473590Y594484D02*
X471090D01*
X471590Y593984D01*
G01X473590D02*
Y594984D01*
G01X458388Y549060D02*
X458138Y549185D01*
X457846Y549268D01*
X457513D01*
X457138Y549143D01*
X456846Y548935D01*
X456638Y548685D01*
X456471Y548268D01*
X456429Y547893D01*
X456513Y547518D01*
X456638Y547268D01*
X456888Y547018D01*
X457179Y546851D01*
X457471Y546768D01*
X457763D01*
X458054Y546851D01*
X458304Y546976D01*
X458513Y547143D01*
G01X459779Y548851D02*
X460029Y549101D01*
X460321Y549226D01*
X460654Y549268D01*
X461071Y549185D01*
X461363Y548976D01*
X461446Y548726D01*
X461404Y548476D01*
X461238Y548268D01*
X460404Y547851D01*
X460029Y547560D01*
X459779Y547143D01*
X459696Y546768D01*
X461446D01*
G01X462629D02*
X463671Y549268D01*
X464713Y546768D01*
G01X464338Y547643D02*
X463004D01*
G01X466771Y546768D02*
Y549268D01*
X466271Y548768D01*
G01Y546768D02*
X467271D01*
G01X468954Y547143D02*
X469204Y546935D01*
X469496Y546810D01*
X469871Y546768D01*
X470246Y546851D01*
X470538Y547018D01*
X470746Y547310D01*
X470788Y547643D01*
X470704Y547976D01*
X470496Y548185D01*
X470204Y548351D01*
X469913Y548393D01*
X469621Y548351D01*
X469246Y548185D01*
X469371Y549268D01*
X470496D01*
G01X453942Y553042D02*
X453692Y553167D01*
X453400Y553250D01*
X453067D01*
X452692Y553125D01*
X452400Y552917D01*
X452192Y552667D01*
X452025Y552250D01*
X451983Y551875D01*
X452067Y551500D01*
X452192Y551250D01*
X452442Y551000D01*
X452733Y550833D01*
X453025Y550750D01*
X453317D01*
X453608Y550833D01*
X453858Y550958D01*
X454067Y551125D01*
G01X455333Y552833D02*
X455583Y553083D01*
X455875Y553208D01*
X456208Y553250D01*
X456625Y553167D01*
X456917Y552958D01*
X457000Y552708D01*
X456958Y552458D01*
X456792Y552250D01*
X455958Y551833D01*
X455583Y551542D01*
X455333Y551125D01*
X455250Y550750D01*
X457000D01*
G01X458183D02*
X459225Y553250D01*
X460267Y550750D01*
G01X459892Y551625D02*
X458558D01*
G01X462325Y550750D02*
Y553250D01*
X461825Y552750D01*
G01Y550750D02*
X462825D01*
G01X465925D02*
Y553250D01*
X464383Y551458D01*
X466467D01*
G01X466074Y586101D02*
X465949Y585851D01*
X465866Y585559D01*
Y585226D01*
X465991Y584851D01*
X466199Y584559D01*
X466449Y584351D01*
X466866Y584184D01*
X467241Y584142D01*
X467616Y584226D01*
X467866Y584351D01*
X468116Y584601D01*
X468283Y584892D01*
X468366Y585184D01*
Y585476D01*
X468283Y585767D01*
X468158Y586017D01*
X467991Y586226D01*
G01X466283Y587492D02*
X466033Y587742D01*
X465908Y588034D01*
X465866Y588367D01*
X465949Y588784D01*
X466158Y589076D01*
X466408Y589159D01*
X466658Y589117D01*
X466866Y588951D01*
X467283Y588117D01*
X467574Y587742D01*
X467991Y587492D01*
X468366Y587409D01*
Y589159D01*
G01Y590342D02*
X465866Y591384D01*
X468366Y592426D01*
G01X467491Y592051D02*
Y590717D01*
G01X468366Y594401D02*
X467824Y594484D01*
X467366Y594609D01*
X466949Y594776D01*
X466491Y594984D01*
X465866Y595317D01*
Y593651D01*
G01X461658Y586039D02*
X461533Y585789D01*
X461450Y585497D01*
Y585164D01*
X461575Y584789D01*
X461783Y584497D01*
X462033Y584289D01*
X462450Y584122D01*
X462825Y584080D01*
X463200Y584164D01*
X463450Y584289D01*
X463700Y584539D01*
X463867Y584830D01*
X463950Y585122D01*
Y585414D01*
X463867Y585705D01*
X463742Y585955D01*
X463575Y586164D01*
G01X461867Y587430D02*
X461617Y587680D01*
X461492Y587972D01*
X461450Y588305D01*
X461533Y588722D01*
X461742Y589014D01*
X461992Y589097D01*
X462242Y589055D01*
X462450Y588889D01*
X462867Y588055D01*
X463158Y587680D01*
X463575Y587430D01*
X463950Y587347D01*
Y589097D01*
G01Y590280D02*
X461450Y591322D01*
X463950Y592364D01*
G01X463075Y591989D02*
Y590655D01*
G01X462908Y593630D02*
X462617Y593922D01*
X462450Y594172D01*
X462367Y594505D01*
X462450Y594797D01*
X462617Y595005D01*
X462867Y595172D01*
X463158Y595214D01*
X463408Y595172D01*
X463658Y595005D01*
X463867Y594755D01*
X463950Y594464D01*
X463867Y594130D01*
X463617Y593839D01*
X463242Y593672D01*
X462825Y593630D01*
X462283Y593714D01*
X461992Y593839D01*
X461700Y594047D01*
X461492Y594339D01*
X461450Y594630D01*
X461533Y594922D01*
X461742Y595130D01*
G01X511246Y-38301D02*
X493246D01*
Y-56301D01*
X511246D01*
Y-38301D01*
G01X531246D02*
X513246D01*
Y-56301D01*
X531246D01*
Y-38301D01*
G01X551246D02*
X533246D01*
Y-56301D01*
X551246D01*
Y-38301D01*
G01X487667Y11958D02*
X487417Y12083D01*
X487125Y12166D01*
X486792D01*
X486417Y12041D01*
X486125Y11833D01*
X485917Y11583D01*
X485750Y11166D01*
X485708Y10791D01*
X485792Y10416D01*
X485917Y10166D01*
X486167Y9916D01*
X486458Y9749D01*
X486750Y9666D01*
X487042D01*
X487333Y9749D01*
X487583Y9874D01*
X487792Y10041D01*
G01X488933Y10166D02*
X489183Y9874D01*
X489517Y9708D01*
X489892Y9666D01*
X490225Y9708D01*
X490558Y9916D01*
X490767Y10166D01*
X490808Y10416D01*
X490725Y10708D01*
X490433Y10916D01*
X490142Y10999D01*
X489767D01*
G01X490142D02*
X490392Y11124D01*
X490600Y11333D01*
X490683Y11583D01*
X490600Y11833D01*
X490392Y12041D01*
X490017Y12166D01*
X489642Y12124D01*
X489267Y11958D01*
G01X493200Y10916D02*
X494033D01*
Y10166D01*
X493783Y9916D01*
X493492Y9749D01*
X493075Y9666D01*
X492658Y9749D01*
X492367Y9916D01*
X492117Y10166D01*
X491950Y10458D01*
X491867Y10791D01*
Y11083D01*
X491950Y11333D01*
X492117Y11624D01*
X492367Y11874D01*
X492617Y12041D01*
X492950Y12166D01*
X493242D01*
X493575Y12083D01*
X493825Y11916D01*
G01X495258Y10708D02*
X495550Y10999D01*
X495800Y11166D01*
X496133Y11249D01*
X496425Y11166D01*
X496633Y10999D01*
X496800Y10749D01*
X496842Y10458D01*
X496800Y10208D01*
X496633Y9958D01*
X496383Y9749D01*
X496092Y9666D01*
X495758Y9749D01*
X495467Y9999D01*
X495300Y10374D01*
X495258Y10791D01*
X495342Y11333D01*
X495467Y11624D01*
X495675Y11916D01*
X495967Y12124D01*
X496258Y12166D01*
X496550Y12083D01*
X496758Y11874D01*
G01X484667Y17258D02*
X484417Y17383D01*
X484125Y17466D01*
X483792D01*
X483417Y17341D01*
X483125Y17133D01*
X482917Y16883D01*
X482750Y16466D01*
X482708Y16091D01*
X482792Y15716D01*
X482917Y15466D01*
X483167Y15216D01*
X483458Y15049D01*
X483750Y14966D01*
X484042D01*
X484333Y15049D01*
X484583Y15174D01*
X484792Y15341D01*
G01X485933Y15466D02*
X486183Y15174D01*
X486517Y15008D01*
X486892Y14966D01*
X487225Y15008D01*
X487558Y15216D01*
X487767Y15466D01*
X487808Y15716D01*
X487725Y16008D01*
X487433Y16216D01*
X487142Y16299D01*
X486767D01*
G01X487142D02*
X487392Y16424D01*
X487600Y16633D01*
X487683Y16883D01*
X487600Y17133D01*
X487392Y17341D01*
X487017Y17466D01*
X486642Y17424D01*
X486267Y17258D01*
G01X490200Y16216D02*
X491033D01*
Y15466D01*
X490783Y15216D01*
X490492Y15049D01*
X490075Y14966D01*
X489658Y15049D01*
X489367Y15216D01*
X489117Y15466D01*
X488950Y15758D01*
X488867Y16091D01*
Y16383D01*
X488950Y16633D01*
X489117Y16924D01*
X489367Y17174D01*
X489617Y17341D01*
X489950Y17466D01*
X490242D01*
X490575Y17383D01*
X490825Y17216D01*
G01X492133Y15341D02*
X492383Y15133D01*
X492675Y15008D01*
X493050Y14966D01*
X493425Y15049D01*
X493717Y15216D01*
X493925Y15508D01*
X493967Y15841D01*
X493883Y16174D01*
X493675Y16383D01*
X493383Y16549D01*
X493092Y16591D01*
X492800Y16549D01*
X492425Y16383D01*
X492550Y17466D01*
X493675D01*
G01X484743Y173118D02*
X484513Y172808D01*
X484245Y172653D01*
X483938Y172601D01*
X483555Y172704D01*
X483287Y172963D01*
X483210Y173273D01*
X483248Y173583D01*
X483402Y173841D01*
X484168Y174358D01*
X484513Y174719D01*
X484743Y175236D01*
X484820Y175701D01*
X483210D01*
G01X480455D02*
Y172601D01*
X481873Y174823D01*
X479957D01*
G01X488057Y176821D02*
X487827Y176511D01*
X487559Y176356D01*
X487252Y176304D01*
X486869Y176407D01*
X486601Y176666D01*
X486524Y176976D01*
X486562Y177286D01*
X486716Y177544D01*
X487482Y178061D01*
X487827Y178422D01*
X488057Y178939D01*
X488134Y179404D01*
X486524D01*
G01X485072Y178784D02*
X484842Y179146D01*
X484536Y179352D01*
X484191Y179404D01*
X483884Y179352D01*
X483577Y179094D01*
X483386Y178784D01*
X483347Y178474D01*
X483424Y178112D01*
X483692Y177854D01*
X483961Y177751D01*
X484306D01*
G01X483961D02*
X483731Y177596D01*
X483539Y177337D01*
X483462Y177027D01*
X483539Y176717D01*
X483731Y176459D01*
X484076Y176304D01*
X484421Y176356D01*
X484766Y176562D01*
G01X491502Y173118D02*
X491272Y172808D01*
X491004Y172653D01*
X490697Y172601D01*
X490314Y172704D01*
X490046Y172963D01*
X489969Y173273D01*
X490007Y173583D01*
X490161Y173841D01*
X490927Y174358D01*
X491272Y174719D01*
X491502Y175236D01*
X491579Y175701D01*
X489969D01*
G01X488402Y173118D02*
X488172Y172808D01*
X487904Y172653D01*
X487597Y172601D01*
X487214Y172704D01*
X486946Y172963D01*
X486869Y173273D01*
X486907Y173583D01*
X487061Y173841D01*
X487827Y174358D01*
X488172Y174719D01*
X488402Y175236D01*
X488479Y175701D01*
X486869D01*
G01X494817Y176821D02*
X494587Y176511D01*
X494319Y176356D01*
X494012Y176304D01*
X493629Y176407D01*
X493361Y176666D01*
X493284Y176976D01*
X493322Y177286D01*
X493476Y177544D01*
X494242Y178061D01*
X494587Y178422D01*
X494817Y178939D01*
X494894Y179404D01*
X493284D01*
G01X490989D02*
Y176304D01*
X491449Y176924D01*
G01Y179404D02*
X490529D01*
G01X498262Y173118D02*
X498032Y172808D01*
X497764Y172653D01*
X497457Y172601D01*
X497074Y172704D01*
X496806Y172963D01*
X496729Y173273D01*
X496767Y173583D01*
X496921Y173841D01*
X497687Y174358D01*
X498032Y174719D01*
X498262Y175236D01*
X498339Y175701D01*
X496729D01*
G01X494434Y172601D02*
X494741Y172704D01*
X494971Y172963D01*
X495124Y173273D01*
X495239Y173686D01*
X495277Y174151D01*
X495239Y174616D01*
X495124Y175029D01*
X494971Y175339D01*
X494741Y175598D01*
X494434Y175701D01*
X494127Y175598D01*
X493897Y175339D01*
X493744Y175029D01*
X493629Y174616D01*
X493591Y174151D01*
X493629Y173686D01*
X493744Y173273D01*
X493897Y172963D01*
X494127Y172704D01*
X494434Y172601D01*
G01X500849Y179404D02*
Y176304D01*
X501309Y176924D01*
G01Y179404D02*
X500389D01*
G01X498401Y179042D02*
X498132Y179301D01*
X497826Y179404D01*
X497519Y179301D01*
X497251Y178991D01*
X497059Y178526D01*
X496982Y178061D01*
Y177492D01*
X497059Y177027D01*
X497251Y176614D01*
X497481Y176407D01*
X497749Y176304D01*
X498056Y176407D01*
X498286Y176614D01*
X498439Y176924D01*
X498516Y177337D01*
X498439Y177699D01*
X498247Y178061D01*
X498017Y178267D01*
X497749Y178319D01*
X497442Y178216D01*
X497212Y177957D01*
X496982Y177492D01*
G01X504294Y175701D02*
Y172601D01*
X504754Y173221D01*
G01Y175701D02*
X503834D01*
G01X501194D02*
X500926Y175649D01*
X500619Y175494D01*
X500427Y175236D01*
X500351Y174874D01*
X500427Y174513D01*
X500657Y174203D01*
X501002Y174048D01*
X501386D01*
X501616Y173944D01*
X501807Y173686D01*
X501884Y173324D01*
X501769Y172963D01*
X501501Y172704D01*
X501194Y172601D01*
X500887Y172704D01*
X500619Y172963D01*
X500504Y173324D01*
X500581Y173686D01*
X500772Y173944D01*
X501002Y174048D01*
X501386D01*
X501731Y174203D01*
X501961Y174513D01*
X502037Y174874D01*
X501961Y175236D01*
X501769Y175494D01*
X501462Y175649D01*
X501194Y175701D01*
G01X507609Y179404D02*
Y176304D01*
X508069Y176924D01*
G01Y179404D02*
X507149D01*
G01X504586D02*
X504509Y178732D01*
X504394Y178164D01*
X504241Y177647D01*
X504049Y177079D01*
X503742Y176304D01*
X505276D01*
G01X511054Y175701D02*
Y172601D01*
X511514Y173221D01*
G01Y175701D02*
X510594D01*
G01X508682Y174409D02*
X508414Y174048D01*
X508184Y173841D01*
X507877Y173738D01*
X507609Y173841D01*
X507417Y174048D01*
X507264Y174358D01*
X507226Y174719D01*
X507264Y175029D01*
X507417Y175339D01*
X507647Y175598D01*
X507916Y175701D01*
X508222Y175598D01*
X508491Y175288D01*
X508644Y174823D01*
X508682Y174306D01*
X508606Y173634D01*
X508491Y173273D01*
X508299Y172911D01*
X508031Y172653D01*
X507762Y172601D01*
X507494Y172704D01*
X507302Y172963D01*
G01X514368Y179404D02*
Y176304D01*
X514828Y176924D01*
G01Y179404D02*
X513908D01*
G01X512111Y178939D02*
X511881Y179197D01*
X511613Y179352D01*
X511268Y179404D01*
X510923Y179301D01*
X510655Y179094D01*
X510463Y178732D01*
X510425Y178319D01*
X510501Y177906D01*
X510693Y177647D01*
X510961Y177441D01*
X511230Y177389D01*
X511498Y177441D01*
X511843Y177647D01*
X511728Y176304D01*
X510693D01*
G01X517814Y175701D02*
Y172601D01*
X518274Y173221D01*
G01Y175701D02*
X517354D01*
G01X514254D02*
Y172601D01*
X515672Y174823D01*
X513756D01*
G01X521128Y179404D02*
Y176304D01*
X521588Y176924D01*
G01Y179404D02*
X520668D01*
G01X518871Y178784D02*
X518641Y179146D01*
X518335Y179352D01*
X517990Y179404D01*
X517683Y179352D01*
X517376Y179094D01*
X517185Y178784D01*
X517146Y178474D01*
X517223Y178112D01*
X517491Y177854D01*
X517760Y177751D01*
X518105D01*
G01X517760D02*
X517530Y177596D01*
X517338Y177337D01*
X517261Y177027D01*
X517338Y176717D01*
X517530Y176459D01*
X517875Y176304D01*
X518220Y176356D01*
X518565Y176562D01*
G01X524574Y175701D02*
Y172601D01*
X525034Y173221D01*
G01Y175701D02*
X524114D01*
G01X522202Y173118D02*
X521972Y172808D01*
X521704Y172653D01*
X521397Y172601D01*
X521014Y172704D01*
X520746Y172963D01*
X520669Y173273D01*
X520707Y173583D01*
X520861Y173841D01*
X521627Y174358D01*
X521972Y174719D01*
X522202Y175236D01*
X522279Y175701D01*
X520669D01*
G01X527888Y179404D02*
Y176304D01*
X528348Y176924D01*
G01Y179404D02*
X527428D01*
G01X524788D02*
Y176304D01*
X525248Y176924D01*
G01Y179404D02*
X524328D01*
G01X531333Y175701D02*
Y172601D01*
X531793Y173221D01*
G01Y175701D02*
X530873D01*
G01X528233Y172601D02*
X528540Y172704D01*
X528770Y172963D01*
X528923Y173273D01*
X529038Y173686D01*
X529076Y174151D01*
X529038Y174616D01*
X528923Y175029D01*
X528770Y175339D01*
X528540Y175598D01*
X528233Y175701D01*
X527926Y175598D01*
X527696Y175339D01*
X527543Y175029D01*
X527428Y174616D01*
X527390Y174151D01*
X527428Y173686D01*
X527543Y173273D01*
X527696Y172963D01*
X527926Y172704D01*
X528233Y172601D01*
G01X533750Y179042D02*
X533481Y179301D01*
X533175Y179404D01*
X532868Y179301D01*
X532600Y178991D01*
X532408Y178526D01*
X532331Y178061D01*
Y177492D01*
X532408Y177027D01*
X532600Y176614D01*
X532830Y176407D01*
X533098Y176304D01*
X533405Y176407D01*
X533635Y176614D01*
X533788Y176924D01*
X533865Y177337D01*
X533788Y177699D01*
X533596Y178061D01*
X533366Y178267D01*
X533098Y178319D01*
X532791Y178216D01*
X532561Y177957D01*
X532331Y177492D01*
G01X536543Y175701D02*
X536275Y175649D01*
X535968Y175494D01*
X535776Y175236D01*
X535700Y174874D01*
X535776Y174513D01*
X536006Y174203D01*
X536351Y174048D01*
X536735D01*
X536965Y173944D01*
X537156Y173686D01*
X537233Y173324D01*
X537118Y172963D01*
X536850Y172704D01*
X536543Y172601D01*
X536236Y172704D01*
X535968Y172963D01*
X535853Y173324D01*
X535930Y173686D01*
X536121Y173944D01*
X536351Y174048D01*
X536735D01*
X537080Y174203D01*
X537310Y174513D01*
X537386Y174874D01*
X537310Y175236D01*
X537118Y175494D01*
X536811Y175649D01*
X536543Y175701D01*
G01X536877Y179900D02*
X536800Y179228D01*
X536685Y178660D01*
X536532Y178143D01*
X536340Y177575D01*
X536033Y176800D01*
X537567D01*
G01X541043Y179235D02*
X540813Y179493D01*
X540545Y179648D01*
X540200Y179700D01*
X539855Y179597D01*
X539587Y179390D01*
X539395Y179028D01*
X539357Y178615D01*
X539433Y178202D01*
X539625Y177943D01*
X539893Y177737D01*
X540162Y177685D01*
X540430Y177737D01*
X540775Y177943D01*
X540660Y176600D01*
X539625D01*
G01X480067Y461900D02*
Y468900D01*
G01X485133D02*
X480067Y464583D01*
G01X485933Y461900D02*
X482333Y466567D01*
G01X536267Y438100D02*
Y440600D01*
X537308D01*
X537642Y440475D01*
X537850Y440308D01*
X537933Y439975D01*
X537850Y439642D01*
X537600Y439433D01*
X537308Y439308D01*
X536267D01*
G01X537308D02*
X537933Y438100D01*
G01X539492Y438392D02*
X539783Y438183D01*
X540117Y438100D01*
X540450Y438183D01*
X540742Y438433D01*
X540950Y438808D01*
X541033Y439183D01*
Y439642D01*
X540950Y440017D01*
X540742Y440350D01*
X540492Y440517D01*
X540200Y440600D01*
X539867Y440517D01*
X539617Y440350D01*
X539450Y440100D01*
X539367Y439767D01*
X539450Y439475D01*
X539658Y439183D01*
X539908Y439017D01*
X540200Y438975D01*
X540533Y439058D01*
X540783Y439267D01*
X541033Y439642D01*
G01X542508Y438100D02*
Y440600D01*
X544092D01*
G01X543508Y439392D02*
X542508D01*
G01X545483Y438475D02*
X545733Y438267D01*
X546025Y438142D01*
X546400Y438100D01*
X546775Y438183D01*
X547067Y438350D01*
X547275Y438642D01*
X547317Y438975D01*
X547233Y439308D01*
X547025Y439517D01*
X546733Y439683D01*
X546442Y439725D01*
X546150Y439683D01*
X545775Y439517D01*
X545900Y440600D01*
X547025D01*
G01X548708Y440183D02*
X548958Y440433D01*
X549250Y440558D01*
X549583Y440600D01*
X550000Y440517D01*
X550292Y440308D01*
X550375Y440058D01*
X550333Y439808D01*
X550167Y439600D01*
X549333Y439183D01*
X548958Y438892D01*
X548708Y438475D01*
X548625Y438100D01*
X550375D01*
G01X532367Y441800D02*
Y444300D01*
X533408D01*
X533742Y444175D01*
X533950Y444008D01*
X534033Y443675D01*
X533950Y443342D01*
X533700Y443133D01*
X533408Y443008D01*
X532367D01*
G01X533408D02*
X534033Y441800D01*
G01X535592Y442092D02*
X535883Y441883D01*
X536217Y441800D01*
X536550Y441883D01*
X536842Y442133D01*
X537050Y442508D01*
X537133Y442883D01*
Y443342D01*
X537050Y443717D01*
X536842Y444050D01*
X536592Y444217D01*
X536300Y444300D01*
X535967Y444217D01*
X535717Y444050D01*
X535550Y443800D01*
X535467Y443467D01*
X535550Y443175D01*
X535758Y442883D01*
X536008Y442717D01*
X536300Y442675D01*
X536633Y442758D01*
X536883Y442967D01*
X537133Y443342D01*
G01X538608Y441800D02*
Y444300D01*
X540192D01*
G01X539608Y443092D02*
X538608D01*
G01X541708Y443883D02*
X541958Y444133D01*
X542250Y444258D01*
X542583Y444300D01*
X543000Y444217D01*
X543292Y444008D01*
X543375Y443758D01*
X543333Y443508D01*
X543167Y443300D01*
X542333Y442883D01*
X541958Y442592D01*
X541708Y442175D01*
X541625Y441800D01*
X543375D01*
G01X545600D02*
X545892Y441842D01*
X546225Y441967D01*
X546433Y442175D01*
X546517Y442467D01*
X546433Y442758D01*
X546183Y443008D01*
X545808Y443133D01*
X545392D01*
X545142Y443217D01*
X544933Y443425D01*
X544850Y443717D01*
X544975Y444008D01*
X545267Y444217D01*
X545600Y444300D01*
X545933Y444217D01*
X546225Y444008D01*
X546350Y443717D01*
X546267Y443425D01*
X546058Y443217D01*
X545808Y443133D01*
X545392D01*
X545017Y443008D01*
X544767Y442758D01*
X544683Y442467D01*
X544767Y442175D01*
X544975Y441967D01*
X545308Y441842D01*
X545600Y441800D01*
G01X534700Y446167D02*
X532200D01*
Y447208D01*
X532325Y447542D01*
X532492Y447750D01*
X532825Y447833D01*
X533158Y447750D01*
X533367Y447500D01*
X533492Y447208D01*
Y446167D01*
G01Y447208D02*
X534700Y447833D01*
G01X534408Y449392D02*
X534617Y449683D01*
X534700Y450017D01*
X534617Y450350D01*
X534367Y450642D01*
X533992Y450850D01*
X533617Y450933D01*
X533158D01*
X532783Y450850D01*
X532450Y450642D01*
X532283Y450392D01*
X532200Y450100D01*
X532283Y449767D01*
X532450Y449517D01*
X532700Y449350D01*
X533033Y449267D01*
X533325Y449350D01*
X533617Y449558D01*
X533783Y449808D01*
X533825Y450100D01*
X533742Y450433D01*
X533533Y450683D01*
X533158Y450933D01*
G01X534700Y452408D02*
X532200D01*
Y453992D01*
G01X533408Y453408D02*
Y452408D01*
G01X532617Y455508D02*
X532367Y455758D01*
X532242Y456050D01*
X532200Y456383D01*
X532283Y456800D01*
X532492Y457092D01*
X532742Y457175D01*
X532992Y457133D01*
X533200Y456967D01*
X533617Y456133D01*
X533908Y455758D01*
X534325Y455508D01*
X534700Y455425D01*
Y457175D01*
G01X534408Y458692D02*
X534617Y458983D01*
X534700Y459317D01*
X534617Y459650D01*
X534367Y459942D01*
X533992Y460150D01*
X533617Y460233D01*
X533158D01*
X532783Y460150D01*
X532450Y459942D01*
X532283Y459692D01*
X532200Y459400D01*
X532283Y459067D01*
X532450Y458817D01*
X532700Y458650D01*
X533033Y458567D01*
X533325Y458650D01*
X533617Y458858D01*
X533783Y459108D01*
X533825Y459400D01*
X533742Y459733D01*
X533533Y459983D01*
X533158Y460233D01*
G01X535700Y446083D02*
X537492D01*
X537867Y446250D01*
X538117Y446583D01*
X538200Y447000D01*
X538117Y447417D01*
X537867Y447750D01*
X537492Y447917D01*
X535700D01*
G01X537908Y449392D02*
X538117Y449683D01*
X538200Y450017D01*
X538117Y450350D01*
X537867Y450642D01*
X537492Y450850D01*
X537117Y450933D01*
X536658D01*
X536283Y450850D01*
X535950Y450642D01*
X535783Y450392D01*
X535700Y450100D01*
X535783Y449767D01*
X535950Y449517D01*
X536200Y449350D01*
X536533Y449267D01*
X536825Y449350D01*
X537117Y449558D01*
X537283Y449808D01*
X537325Y450100D01*
X537242Y450433D01*
X537033Y450683D01*
X536658Y450933D01*
G01X538200Y452408D02*
X535700D01*
Y453992D01*
G01X536908Y453408D02*
Y452408D01*
G01X537700Y455383D02*
X537992Y455633D01*
X538158Y455967D01*
X538200Y456342D01*
X538158Y456675D01*
X537950Y457008D01*
X537700Y457217D01*
X537450Y457258D01*
X537158Y457175D01*
X536950Y456883D01*
X536867Y456592D01*
Y456217D01*
G01Y456592D02*
X536742Y456842D01*
X536533Y457050D01*
X536283Y457133D01*
X536033Y457050D01*
X535825Y456842D01*
X535700Y456467D01*
X535742Y456092D01*
X535908Y455717D01*
G01X516708Y438317D02*
X516583Y438067D01*
X516500Y437775D01*
Y437442D01*
X516625Y437067D01*
X516833Y436775D01*
X517083Y436567D01*
X517500Y436400D01*
X517875Y436358D01*
X518250Y436442D01*
X518500Y436567D01*
X518750Y436817D01*
X518917Y437108D01*
X519000Y437400D01*
Y437692D01*
X518917Y437983D01*
X518792Y438233D01*
X518625Y438442D01*
G01X516917Y439708D02*
X516667Y439958D01*
X516542Y440250D01*
X516500Y440583D01*
X516583Y441000D01*
X516792Y441292D01*
X517042Y441375D01*
X517292Y441333D01*
X517500Y441167D01*
X517917Y440333D01*
X518208Y439958D01*
X518625Y439708D01*
X519000Y439625D01*
Y441375D01*
G01X518625Y442683D02*
X518833Y442933D01*
X518958Y443225D01*
X519000Y443600D01*
X518917Y443975D01*
X518750Y444267D01*
X518458Y444475D01*
X518125Y444517D01*
X517792Y444433D01*
X517583Y444225D01*
X517417Y443933D01*
X517375Y443642D01*
X517417Y443350D01*
X517583Y442975D01*
X516500Y443100D01*
Y444225D01*
G01Y445450D02*
X519000Y446033D01*
X516500Y446700D01*
X519000Y447367D01*
X516500Y447950D01*
G01X519000Y450300D02*
X516500D01*
X518292Y448758D01*
Y450842D01*
G01X523708Y438317D02*
X523583Y438067D01*
X523500Y437775D01*
Y437442D01*
X523625Y437067D01*
X523833Y436775D01*
X524083Y436567D01*
X524500Y436400D01*
X524875Y436358D01*
X525250Y436442D01*
X525500Y436567D01*
X525750Y436817D01*
X525917Y437108D01*
X526000Y437400D01*
Y437692D01*
X525917Y437983D01*
X525792Y438233D01*
X525625Y438442D01*
G01X523917Y439708D02*
X523667Y439958D01*
X523542Y440250D01*
X523500Y440583D01*
X523583Y441000D01*
X523792Y441292D01*
X524042Y441375D01*
X524292Y441333D01*
X524500Y441167D01*
X524917Y440333D01*
X525208Y439958D01*
X525625Y439708D01*
X526000Y439625D01*
Y441375D01*
G01X525625Y442683D02*
X525833Y442933D01*
X525958Y443225D01*
X526000Y443600D01*
X525917Y443975D01*
X525750Y444267D01*
X525458Y444475D01*
X525125Y444517D01*
X524792Y444433D01*
X524583Y444225D01*
X524417Y443933D01*
X524375Y443642D01*
X524417Y443350D01*
X524583Y442975D01*
X523500Y443100D01*
Y444225D01*
G01Y445450D02*
X526000Y446033D01*
X523500Y446700D01*
X526000Y447367D01*
X523500Y447950D01*
G01X525500Y448883D02*
X525792Y449133D01*
X525958Y449467D01*
X526000Y449842D01*
X525958Y450175D01*
X525750Y450508D01*
X525500Y450717D01*
X525250Y450758D01*
X524958Y450675D01*
X524750Y450383D01*
X524667Y450092D01*
Y449717D01*
G01Y450092D02*
X524542Y450342D01*
X524333Y450550D01*
X524083Y450633D01*
X523833Y450550D01*
X523625Y450342D01*
X523500Y449967D01*
X523542Y449592D01*
X523708Y449217D01*
G01X520208Y438317D02*
X520083Y438067D01*
X520000Y437775D01*
Y437442D01*
X520125Y437067D01*
X520333Y436775D01*
X520583Y436567D01*
X521000Y436400D01*
X521375Y436358D01*
X521750Y436442D01*
X522000Y436567D01*
X522250Y436817D01*
X522417Y437108D01*
X522500Y437400D01*
Y437692D01*
X522417Y437983D01*
X522292Y438233D01*
X522125Y438442D01*
G01X520417Y439708D02*
X520167Y439958D01*
X520042Y440250D01*
X520000Y440583D01*
X520083Y441000D01*
X520292Y441292D01*
X520542Y441375D01*
X520792Y441333D01*
X521000Y441167D01*
X521417Y440333D01*
X521708Y439958D01*
X522125Y439708D01*
X522500Y439625D01*
Y441375D01*
G01X522125Y442683D02*
X522333Y442933D01*
X522458Y443225D01*
X522500Y443600D01*
X522417Y443975D01*
X522250Y444267D01*
X521958Y444475D01*
X521625Y444517D01*
X521292Y444433D01*
X521083Y444225D01*
X520917Y443933D01*
X520875Y443642D01*
X520917Y443350D01*
X521083Y442975D01*
X520000Y443100D01*
Y444225D01*
G01Y445450D02*
X522500Y446033D01*
X520000Y446700D01*
X522500Y447367D01*
X520000Y447950D01*
G01X520417Y449008D02*
X520167Y449258D01*
X520042Y449550D01*
X520000Y449883D01*
X520083Y450300D01*
X520292Y450592D01*
X520542Y450675D01*
X520792Y450633D01*
X521000Y450467D01*
X521417Y449633D01*
X521708Y449258D01*
X522125Y449008D01*
X522500Y448925D01*
Y450675D01*
G01X534700Y462483D02*
X532200D01*
Y463317D01*
X532325Y463650D01*
X532492Y463900D01*
X532742Y464108D01*
X533033Y464275D01*
X533450Y464317D01*
X533867Y464275D01*
X534158Y464108D01*
X534408Y463900D01*
X534575Y463650D01*
X534700Y463317D01*
Y462483D01*
G01X534367Y465625D02*
X534575Y465958D01*
X534700Y466333D01*
Y466667D01*
X534575Y467000D01*
X534367Y467250D01*
X534075Y467375D01*
X533783Y467292D01*
X533533Y467083D01*
X533367Y466708D01*
X533283Y466208D01*
X533117Y465917D01*
X532825Y465792D01*
X532533Y465875D01*
X532325Y466083D01*
X532200Y466375D01*
Y466667D01*
X532283Y466958D01*
X532492Y467208D01*
G01X534408Y468892D02*
X534617Y469183D01*
X534700Y469517D01*
X534617Y469850D01*
X534367Y470142D01*
X533992Y470350D01*
X533617Y470433D01*
X533158D01*
X532783Y470350D01*
X532450Y470142D01*
X532283Y469892D01*
X532200Y469600D01*
X532283Y469267D01*
X532450Y469017D01*
X532700Y468850D01*
X533033Y468767D01*
X533325Y468850D01*
X533617Y469058D01*
X533783Y469308D01*
X533825Y469600D01*
X533742Y469933D01*
X533533Y470183D01*
X533158Y470433D01*
G01X534700Y473533D02*
Y471867D01*
X532200D01*
Y473533D01*
G01X533408Y472867D02*
Y471867D01*
G01X534700Y475800D02*
X532200D01*
X532700Y475300D01*
G01X534700D02*
Y476300D01*
G01X530000Y436583D02*
X527500D01*
Y437417D01*
X527625Y437750D01*
X527792Y438000D01*
X528042Y438208D01*
X528333Y438375D01*
X528750Y438417D01*
X529167Y438375D01*
X529458Y438208D01*
X529708Y438000D01*
X529875Y437750D01*
X530000Y437417D01*
Y436583D01*
G01X529667Y439725D02*
X529875Y440058D01*
X530000Y440433D01*
Y440767D01*
X529875Y441100D01*
X529667Y441350D01*
X529375Y441475D01*
X529083Y441392D01*
X528833Y441183D01*
X528667Y440808D01*
X528583Y440308D01*
X528417Y440017D01*
X528125Y439892D01*
X527833Y439975D01*
X527625Y440183D01*
X527500Y440475D01*
Y440767D01*
X527583Y441058D01*
X527792Y441308D01*
G01X529708Y442992D02*
X529917Y443283D01*
X530000Y443617D01*
X529917Y443950D01*
X529667Y444242D01*
X529292Y444450D01*
X528917Y444533D01*
X528458D01*
X528083Y444450D01*
X527750Y444242D01*
X527583Y443992D01*
X527500Y443700D01*
X527583Y443367D01*
X527750Y443117D01*
X528000Y442950D01*
X528333Y442867D01*
X528625Y442950D01*
X528917Y443158D01*
X529083Y443408D01*
X529125Y443700D01*
X529042Y444033D01*
X528833Y444283D01*
X528458Y444533D01*
G01X530000Y446008D02*
X527500D01*
Y447592D01*
G01X528708Y447008D02*
Y446008D01*
G01X530000Y449900D02*
X527500D01*
X528000Y449400D01*
G01X530000D02*
Y450400D01*
G01X493717Y463100D02*
Y465600D01*
X494758D01*
X495092Y465475D01*
X495300Y465308D01*
X495383Y464975D01*
X495300Y464642D01*
X495050Y464433D01*
X494758Y464308D01*
X493717D01*
G01X494758D02*
X495383Y463100D01*
G01X496858Y465183D02*
X497108Y465433D01*
X497400Y465558D01*
X497733Y465600D01*
X498150Y465517D01*
X498442Y465308D01*
X498525Y465058D01*
X498483Y464808D01*
X498317Y464600D01*
X497483Y464183D01*
X497108Y463892D01*
X496858Y463475D01*
X496775Y463100D01*
X498525D01*
G01X499833Y463475D02*
X500083Y463267D01*
X500375Y463142D01*
X500750Y463100D01*
X501125Y463183D01*
X501417Y463350D01*
X501625Y463642D01*
X501667Y463975D01*
X501583Y464308D01*
X501375Y464517D01*
X501083Y464683D01*
X500792Y464725D01*
X500500Y464683D01*
X500125Y464517D01*
X500250Y465600D01*
X501375D01*
G01X502600D02*
X503183Y463100D01*
X503850Y465600D01*
X504517Y463100D01*
X505100Y465600D01*
G01X506242Y463392D02*
X506533Y463183D01*
X506867Y463100D01*
X507200Y463183D01*
X507492Y463433D01*
X507700Y463808D01*
X507783Y464183D01*
Y464642D01*
X507700Y465017D01*
X507492Y465350D01*
X507242Y465517D01*
X506950Y465600D01*
X506617Y465517D01*
X506367Y465350D01*
X506200Y465100D01*
X506117Y464767D01*
X506200Y464475D01*
X506408Y464183D01*
X506658Y464017D01*
X506950Y463975D01*
X507283Y464058D01*
X507533Y464267D01*
X507783Y464642D01*
G01X493717Y459600D02*
Y462100D01*
X494758D01*
X495092Y461975D01*
X495300Y461808D01*
X495383Y461475D01*
X495300Y461142D01*
X495050Y460933D01*
X494758Y460808D01*
X493717D01*
G01X494758D02*
X495383Y459600D01*
G01X496858Y461683D02*
X497108Y461933D01*
X497400Y462058D01*
X497733Y462100D01*
X498150Y462017D01*
X498442Y461808D01*
X498525Y461558D01*
X498483Y461308D01*
X498317Y461100D01*
X497483Y460683D01*
X497108Y460392D01*
X496858Y459975D01*
X496775Y459600D01*
X498525D01*
G01X499833Y459975D02*
X500083Y459767D01*
X500375Y459642D01*
X500750Y459600D01*
X501125Y459683D01*
X501417Y459850D01*
X501625Y460142D01*
X501667Y460475D01*
X501583Y460808D01*
X501375Y461017D01*
X501083Y461183D01*
X500792Y461225D01*
X500500Y461183D01*
X500125Y461017D01*
X500250Y462100D01*
X501375D01*
G01X502600D02*
X503183Y459600D01*
X503850Y462100D01*
X504517Y459600D01*
X505100Y462100D01*
G01X506950Y459600D02*
Y462100D01*
X506450Y461600D01*
G01Y459600D02*
X507450D01*
G01X510050D02*
Y462100D01*
X509550Y461600D01*
G01Y459600D02*
X510550D01*
G01X493717Y456100D02*
Y458600D01*
X494758D01*
X495092Y458475D01*
X495300Y458308D01*
X495383Y457975D01*
X495300Y457642D01*
X495050Y457433D01*
X494758Y457308D01*
X493717D01*
G01X494758D02*
X495383Y456100D01*
G01X496858Y458183D02*
X497108Y458433D01*
X497400Y458558D01*
X497733Y458600D01*
X498150Y458517D01*
X498442Y458308D01*
X498525Y458058D01*
X498483Y457808D01*
X498317Y457600D01*
X497483Y457183D01*
X497108Y456892D01*
X496858Y456475D01*
X496775Y456100D01*
X498525D01*
G01X499833Y456475D02*
X500083Y456267D01*
X500375Y456142D01*
X500750Y456100D01*
X501125Y456183D01*
X501417Y456350D01*
X501625Y456642D01*
X501667Y456975D01*
X501583Y457308D01*
X501375Y457517D01*
X501083Y457683D01*
X500792Y457725D01*
X500500Y457683D01*
X500125Y457517D01*
X500250Y458600D01*
X501375D01*
G01X502600D02*
X503183Y456100D01*
X503850Y458600D01*
X504517Y456100D01*
X505100Y458600D01*
G01X506158Y458183D02*
X506408Y458433D01*
X506700Y458558D01*
X507033Y458600D01*
X507450Y458517D01*
X507742Y458308D01*
X507825Y458058D01*
X507783Y457808D01*
X507617Y457600D01*
X506783Y457183D01*
X506408Y456892D01*
X506158Y456475D01*
X506075Y456100D01*
X507825D01*
G01X509258Y457142D02*
X509550Y457433D01*
X509800Y457600D01*
X510133Y457683D01*
X510425Y457600D01*
X510633Y457433D01*
X510800Y457183D01*
X510842Y456892D01*
X510800Y456642D01*
X510633Y456392D01*
X510383Y456183D01*
X510092Y456100D01*
X509758Y456183D01*
X509467Y456433D01*
X509300Y456808D01*
X509258Y457225D01*
X509342Y457767D01*
X509467Y458058D01*
X509675Y458350D01*
X509967Y458558D01*
X510258Y458600D01*
X510550Y458517D01*
X510758Y458308D01*
G01X493717Y452600D02*
Y455100D01*
X494758D01*
X495092Y454975D01*
X495300Y454808D01*
X495383Y454475D01*
X495300Y454142D01*
X495050Y453933D01*
X494758Y453808D01*
X493717D01*
G01X494758D02*
X495383Y452600D01*
G01X496858Y454683D02*
X497108Y454933D01*
X497400Y455058D01*
X497733Y455100D01*
X498150Y455017D01*
X498442Y454808D01*
X498525Y454558D01*
X498483Y454308D01*
X498317Y454100D01*
X497483Y453683D01*
X497108Y453392D01*
X496858Y452975D01*
X496775Y452600D01*
X498525D01*
G01X499833Y452975D02*
X500083Y452767D01*
X500375Y452642D01*
X500750Y452600D01*
X501125Y452683D01*
X501417Y452850D01*
X501625Y453142D01*
X501667Y453475D01*
X501583Y453808D01*
X501375Y454017D01*
X501083Y454183D01*
X500792Y454225D01*
X500500Y454183D01*
X500125Y454017D01*
X500250Y455100D01*
X501375D01*
G01X502600D02*
X503183Y452600D01*
X503850Y455100D01*
X504517Y452600D01*
X505100Y455100D01*
G01X506950Y452600D02*
X507242Y452642D01*
X507575Y452767D01*
X507783Y452975D01*
X507867Y453267D01*
X507783Y453558D01*
X507533Y453808D01*
X507158Y453933D01*
X506742D01*
X506492Y454017D01*
X506283Y454225D01*
X506200Y454517D01*
X506325Y454808D01*
X506617Y455017D01*
X506950Y455100D01*
X507283Y455017D01*
X507575Y454808D01*
X507700Y454517D01*
X507617Y454225D01*
X507408Y454017D01*
X507158Y453933D01*
X506742D01*
X506367Y453808D01*
X506117Y453558D01*
X506033Y453267D01*
X506117Y452975D01*
X506325Y452767D01*
X506658Y452642D01*
X506950Y452600D01*
G01X513017Y463000D02*
Y465500D01*
X514058D01*
X514392Y465375D01*
X514600Y465208D01*
X514683Y464875D01*
X514600Y464542D01*
X514350Y464333D01*
X514058Y464208D01*
X513017D01*
G01X514058D02*
X514683Y463000D01*
G01X516158Y465083D02*
X516408Y465333D01*
X516700Y465458D01*
X517033Y465500D01*
X517450Y465417D01*
X517742Y465208D01*
X517825Y464958D01*
X517783Y464708D01*
X517617Y464500D01*
X516783Y464083D01*
X516408Y463792D01*
X516158Y463375D01*
X516075Y463000D01*
X517825D01*
G01X519133Y463375D02*
X519383Y463167D01*
X519675Y463042D01*
X520050Y463000D01*
X520425Y463083D01*
X520717Y463250D01*
X520925Y463542D01*
X520967Y463875D01*
X520883Y464208D01*
X520675Y464417D01*
X520383Y464583D01*
X520092Y464625D01*
X519800Y464583D01*
X519425Y464417D01*
X519550Y465500D01*
X520675D01*
G01X521900D02*
X522483Y463000D01*
X523150Y465500D01*
X523817Y463000D01*
X524400Y465500D01*
G01X525333Y463500D02*
X525583Y463208D01*
X525917Y463042D01*
X526292Y463000D01*
X526625Y463042D01*
X526958Y463250D01*
X527167Y463500D01*
X527208Y463750D01*
X527125Y464042D01*
X526833Y464250D01*
X526542Y464333D01*
X526167D01*
G01X526542D02*
X526792Y464458D01*
X527000Y464667D01*
X527083Y464917D01*
X527000Y465167D01*
X526792Y465375D01*
X526417Y465500D01*
X526042Y465458D01*
X525667Y465292D01*
G01X528433Y463375D02*
X528683Y463167D01*
X528975Y463042D01*
X529350Y463000D01*
X529725Y463083D01*
X530017Y463250D01*
X530225Y463542D01*
X530267Y463875D01*
X530183Y464208D01*
X529975Y464417D01*
X529683Y464583D01*
X529392Y464625D01*
X529100Y464583D01*
X528725Y464417D01*
X528850Y465500D01*
X529975D01*
G01X513017Y459500D02*
Y462000D01*
X514058D01*
X514392Y461875D01*
X514600Y461708D01*
X514683Y461375D01*
X514600Y461042D01*
X514350Y460833D01*
X514058Y460708D01*
X513017D01*
G01X514058D02*
X514683Y459500D01*
G01X516158Y461583D02*
X516408Y461833D01*
X516700Y461958D01*
X517033Y462000D01*
X517450Y461917D01*
X517742Y461708D01*
X517825Y461458D01*
X517783Y461208D01*
X517617Y461000D01*
X516783Y460583D01*
X516408Y460292D01*
X516158Y459875D01*
X516075Y459500D01*
X517825D01*
G01X519133Y459875D02*
X519383Y459667D01*
X519675Y459542D01*
X520050Y459500D01*
X520425Y459583D01*
X520717Y459750D01*
X520925Y460042D01*
X520967Y460375D01*
X520883Y460708D01*
X520675Y460917D01*
X520383Y461083D01*
X520092Y461125D01*
X519800Y461083D01*
X519425Y460917D01*
X519550Y462000D01*
X520675D01*
G01X521900D02*
X522483Y459500D01*
X523150Y462000D01*
X523817Y459500D01*
X524400Y462000D01*
G01X525333Y460000D02*
X525583Y459708D01*
X525917Y459542D01*
X526292Y459500D01*
X526625Y459542D01*
X526958Y459750D01*
X527167Y460000D01*
X527208Y460250D01*
X527125Y460542D01*
X526833Y460750D01*
X526542Y460833D01*
X526167D01*
G01X526542D02*
X526792Y460958D01*
X527000Y461167D01*
X527083Y461417D01*
X527000Y461667D01*
X526792Y461875D01*
X526417Y462000D01*
X526042Y461958D01*
X525667Y461792D01*
G01X529267Y459500D02*
X529350Y460042D01*
X529475Y460500D01*
X529642Y460917D01*
X529850Y461375D01*
X530183Y462000D01*
X528517D01*
G01X513017Y456000D02*
Y458500D01*
X514058D01*
X514392Y458375D01*
X514600Y458208D01*
X514683Y457875D01*
X514600Y457542D01*
X514350Y457333D01*
X514058Y457208D01*
X513017D01*
G01X514058D02*
X514683Y456000D01*
G01X516158Y458083D02*
X516408Y458333D01*
X516700Y458458D01*
X517033Y458500D01*
X517450Y458417D01*
X517742Y458208D01*
X517825Y457958D01*
X517783Y457708D01*
X517617Y457500D01*
X516783Y457083D01*
X516408Y456792D01*
X516158Y456375D01*
X516075Y456000D01*
X517825D01*
G01X519133Y456375D02*
X519383Y456167D01*
X519675Y456042D01*
X520050Y456000D01*
X520425Y456083D01*
X520717Y456250D01*
X520925Y456542D01*
X520967Y456875D01*
X520883Y457208D01*
X520675Y457417D01*
X520383Y457583D01*
X520092Y457625D01*
X519800Y457583D01*
X519425Y457417D01*
X519550Y458500D01*
X520675D01*
G01X521900D02*
X522483Y456000D01*
X523150Y458500D01*
X523817Y456000D01*
X524400Y458500D01*
G01X525333Y456375D02*
X525583Y456167D01*
X525875Y456042D01*
X526250Y456000D01*
X526625Y456083D01*
X526917Y456250D01*
X527125Y456542D01*
X527167Y456875D01*
X527083Y457208D01*
X526875Y457417D01*
X526583Y457583D01*
X526292Y457625D01*
X526000Y457583D01*
X525625Y457417D01*
X525750Y458500D01*
X526875D01*
G01X528558Y458083D02*
X528808Y458333D01*
X529100Y458458D01*
X529433Y458500D01*
X529850Y458417D01*
X530142Y458208D01*
X530225Y457958D01*
X530183Y457708D01*
X530017Y457500D01*
X529183Y457083D01*
X528808Y456792D01*
X528558Y456375D01*
X528475Y456000D01*
X530225D01*
G01X513017Y452500D02*
Y455000D01*
X514058D01*
X514392Y454875D01*
X514600Y454708D01*
X514683Y454375D01*
X514600Y454042D01*
X514350Y453833D01*
X514058Y453708D01*
X513017D01*
G01X514058D02*
X514683Y452500D01*
G01X516158Y454583D02*
X516408Y454833D01*
X516700Y454958D01*
X517033Y455000D01*
X517450Y454917D01*
X517742Y454708D01*
X517825Y454458D01*
X517783Y454208D01*
X517617Y454000D01*
X516783Y453583D01*
X516408Y453292D01*
X516158Y452875D01*
X516075Y452500D01*
X517825D01*
G01X519133Y452875D02*
X519383Y452667D01*
X519675Y452542D01*
X520050Y452500D01*
X520425Y452583D01*
X520717Y452750D01*
X520925Y453042D01*
X520967Y453375D01*
X520883Y453708D01*
X520675Y453917D01*
X520383Y454083D01*
X520092Y454125D01*
X519800Y454083D01*
X519425Y453917D01*
X519550Y455000D01*
X520675D01*
G01X521900D02*
X522483Y452500D01*
X523150Y455000D01*
X523817Y452500D01*
X524400Y455000D01*
G01X525333Y453000D02*
X525583Y452708D01*
X525917Y452542D01*
X526292Y452500D01*
X526625Y452542D01*
X526958Y452750D01*
X527167Y453000D01*
X527208Y453250D01*
X527125Y453542D01*
X526833Y453750D01*
X526542Y453833D01*
X526167D01*
G01X526542D02*
X526792Y453958D01*
X527000Y454167D01*
X527083Y454417D01*
X527000Y454667D01*
X526792Y454875D01*
X526417Y455000D01*
X526042Y454958D01*
X525667Y454792D01*
G01X529850Y452500D02*
Y455000D01*
X528308Y453208D01*
X530392D01*
G01X484217Y478500D02*
Y481000D01*
X485258D01*
X485592Y480875D01*
X485800Y480708D01*
X485883Y480375D01*
X485800Y480042D01*
X485550Y479833D01*
X485258Y479708D01*
X484217D01*
G01X485258D02*
X485883Y478500D01*
G01X487358Y480583D02*
X487608Y480833D01*
X487900Y480958D01*
X488233Y481000D01*
X488650Y480917D01*
X488942Y480708D01*
X489025Y480458D01*
X488983Y480208D01*
X488817Y480000D01*
X487983Y479583D01*
X487608Y479292D01*
X487358Y478875D01*
X487275Y478500D01*
X489025D01*
G01X490333Y478875D02*
X490583Y478667D01*
X490875Y478542D01*
X491250Y478500D01*
X491625Y478583D01*
X491917Y478750D01*
X492125Y479042D01*
X492167Y479375D01*
X492083Y479708D01*
X491875Y479917D01*
X491583Y480083D01*
X491292Y480125D01*
X491000Y480083D01*
X490625Y479917D01*
X490750Y481000D01*
X491875D01*
G01X493100D02*
X493683Y478500D01*
X494350Y481000D01*
X495017Y478500D01*
X495600Y481000D01*
G01X496742Y478792D02*
X497033Y478583D01*
X497367Y478500D01*
X497700Y478583D01*
X497992Y478833D01*
X498200Y479208D01*
X498283Y479583D01*
Y480042D01*
X498200Y480417D01*
X497992Y480750D01*
X497742Y480917D01*
X497450Y481000D01*
X497117Y480917D01*
X496867Y480750D01*
X496700Y480500D01*
X496617Y480167D01*
X496700Y479875D01*
X496908Y479583D01*
X497158Y479417D01*
X497450Y479375D01*
X497783Y479458D01*
X498033Y479667D01*
X498283Y480042D01*
G01X501050Y478500D02*
Y481000D01*
X499508Y479208D01*
X501592D01*
G01X493717Y473600D02*
Y476100D01*
X494758D01*
X495092Y475975D01*
X495300Y475808D01*
X495383Y475475D01*
X495300Y475142D01*
X495050Y474933D01*
X494758Y474808D01*
X493717D01*
G01X494758D02*
X495383Y473600D01*
G01X496858Y475683D02*
X497108Y475933D01*
X497400Y476058D01*
X497733Y476100D01*
X498150Y476017D01*
X498442Y475808D01*
X498525Y475558D01*
X498483Y475308D01*
X498317Y475100D01*
X497483Y474683D01*
X497108Y474392D01*
X496858Y473975D01*
X496775Y473600D01*
X498525D01*
G01X499833Y473975D02*
X500083Y473767D01*
X500375Y473642D01*
X500750Y473600D01*
X501125Y473683D01*
X501417Y473850D01*
X501625Y474142D01*
X501667Y474475D01*
X501583Y474808D01*
X501375Y475017D01*
X501083Y475183D01*
X500792Y475225D01*
X500500Y475183D01*
X500125Y475017D01*
X500250Y476100D01*
X501375D01*
G01X502600D02*
X503183Y473600D01*
X503850Y476100D01*
X504517Y473600D01*
X505100Y476100D01*
G01X506158Y475683D02*
X506408Y475933D01*
X506700Y476058D01*
X507033Y476100D01*
X507450Y476017D01*
X507742Y475808D01*
X507825Y475558D01*
X507783Y475308D01*
X507617Y475100D01*
X506783Y474683D01*
X506408Y474392D01*
X506158Y473975D01*
X506075Y473600D01*
X507825D01*
G01X509133Y474100D02*
X509383Y473808D01*
X509717Y473642D01*
X510092Y473600D01*
X510425Y473642D01*
X510758Y473850D01*
X510967Y474100D01*
X511008Y474350D01*
X510925Y474642D01*
X510633Y474850D01*
X510342Y474933D01*
X509967D01*
G01X510342D02*
X510592Y475058D01*
X510800Y475267D01*
X510883Y475517D01*
X510800Y475767D01*
X510592Y475975D01*
X510217Y476100D01*
X509842Y476058D01*
X509467Y475892D01*
G01X493717Y470100D02*
Y472600D01*
X494758D01*
X495092Y472475D01*
X495300Y472308D01*
X495383Y471975D01*
X495300Y471642D01*
X495050Y471433D01*
X494758Y471308D01*
X493717D01*
G01X494758D02*
X495383Y470100D01*
G01X496858Y472183D02*
X497108Y472433D01*
X497400Y472558D01*
X497733Y472600D01*
X498150Y472517D01*
X498442Y472308D01*
X498525Y472058D01*
X498483Y471808D01*
X498317Y471600D01*
X497483Y471183D01*
X497108Y470892D01*
X496858Y470475D01*
X496775Y470100D01*
X498525D01*
G01X499833Y470475D02*
X500083Y470267D01*
X500375Y470142D01*
X500750Y470100D01*
X501125Y470183D01*
X501417Y470350D01*
X501625Y470642D01*
X501667Y470975D01*
X501583Y471308D01*
X501375Y471517D01*
X501083Y471683D01*
X500792Y471725D01*
X500500Y471683D01*
X500125Y471517D01*
X500250Y472600D01*
X501375D01*
G01X502600D02*
X503183Y470100D01*
X503850Y472600D01*
X504517Y470100D01*
X505100Y472600D01*
G01X506158Y472183D02*
X506408Y472433D01*
X506700Y472558D01*
X507033Y472600D01*
X507450Y472517D01*
X507742Y472308D01*
X507825Y472058D01*
X507783Y471808D01*
X507617Y471600D01*
X506783Y471183D01*
X506408Y470892D01*
X506158Y470475D01*
X506075Y470100D01*
X507825D01*
G01X510050Y472600D02*
X509717Y472517D01*
X509467Y472308D01*
X509300Y472058D01*
X509175Y471725D01*
X509133Y471350D01*
X509175Y470975D01*
X509300Y470642D01*
X509467Y470392D01*
X509717Y470183D01*
X510050Y470100D01*
X510383Y470183D01*
X510633Y470392D01*
X510800Y470642D01*
X510925Y470975D01*
X510967Y471350D01*
X510925Y471725D01*
X510800Y472058D01*
X510633Y472308D01*
X510383Y472517D01*
X510050Y472600D01*
G01X513017Y466500D02*
Y469000D01*
X514058D01*
X514392Y468875D01*
X514600Y468708D01*
X514683Y468375D01*
X514600Y468042D01*
X514350Y467833D01*
X514058Y467708D01*
X513017D01*
G01X514058D02*
X514683Y466500D01*
G01X516158Y468583D02*
X516408Y468833D01*
X516700Y468958D01*
X517033Y469000D01*
X517450Y468917D01*
X517742Y468708D01*
X517825Y468458D01*
X517783Y468208D01*
X517617Y468000D01*
X516783Y467583D01*
X516408Y467292D01*
X516158Y466875D01*
X516075Y466500D01*
X517825D01*
G01X519133Y466875D02*
X519383Y466667D01*
X519675Y466542D01*
X520050Y466500D01*
X520425Y466583D01*
X520717Y466750D01*
X520925Y467042D01*
X520967Y467375D01*
X520883Y467708D01*
X520675Y467917D01*
X520383Y468083D01*
X520092Y468125D01*
X519800Y468083D01*
X519425Y467917D01*
X519550Y469000D01*
X520675D01*
G01X521900D02*
X522483Y466500D01*
X523150Y469000D01*
X523817Y466500D01*
X524400Y469000D01*
G01X525458Y468583D02*
X525708Y468833D01*
X526000Y468958D01*
X526333Y469000D01*
X526750Y468917D01*
X527042Y468708D01*
X527125Y468458D01*
X527083Y468208D01*
X526917Y468000D01*
X526083Y467583D01*
X525708Y467292D01*
X525458Y466875D01*
X525375Y466500D01*
X527125D01*
G01X528642Y466792D02*
X528933Y466583D01*
X529267Y466500D01*
X529600Y466583D01*
X529892Y466833D01*
X530100Y467208D01*
X530183Y467583D01*
Y468042D01*
X530100Y468417D01*
X529892Y468750D01*
X529642Y468917D01*
X529350Y469000D01*
X529017Y468917D01*
X528767Y468750D01*
X528600Y468500D01*
X528517Y468167D01*
X528600Y467875D01*
X528808Y467583D01*
X529058Y467417D01*
X529350Y467375D01*
X529683Y467458D01*
X529933Y467667D01*
X530183Y468042D01*
G01X513017Y473500D02*
Y476000D01*
X514058D01*
X514392Y475875D01*
X514600Y475708D01*
X514683Y475375D01*
X514600Y475042D01*
X514350Y474833D01*
X514058Y474708D01*
X513017D01*
G01X514058D02*
X514683Y473500D01*
G01X516158Y475583D02*
X516408Y475833D01*
X516700Y475958D01*
X517033Y476000D01*
X517450Y475917D01*
X517742Y475708D01*
X517825Y475458D01*
X517783Y475208D01*
X517617Y475000D01*
X516783Y474583D01*
X516408Y474292D01*
X516158Y473875D01*
X516075Y473500D01*
X517825D01*
G01X519133Y473875D02*
X519383Y473667D01*
X519675Y473542D01*
X520050Y473500D01*
X520425Y473583D01*
X520717Y473750D01*
X520925Y474042D01*
X520967Y474375D01*
X520883Y474708D01*
X520675Y474917D01*
X520383Y475083D01*
X520092Y475125D01*
X519800Y475083D01*
X519425Y474917D01*
X519550Y476000D01*
X520675D01*
G01X521900D02*
X522483Y473500D01*
X523150Y476000D01*
X523817Y473500D01*
X524400Y476000D01*
G01X526750Y473500D02*
Y476000D01*
X525208Y474208D01*
X527292D01*
G01X528642Y473792D02*
X528933Y473583D01*
X529267Y473500D01*
X529600Y473583D01*
X529892Y473833D01*
X530100Y474208D01*
X530183Y474583D01*
Y475042D01*
X530100Y475417D01*
X529892Y475750D01*
X529642Y475917D01*
X529350Y476000D01*
X529017Y475917D01*
X528767Y475750D01*
X528600Y475500D01*
X528517Y475167D01*
X528600Y474875D01*
X528808Y474583D01*
X529058Y474417D01*
X529350Y474375D01*
X529683Y474458D01*
X529933Y474667D01*
X530183Y475042D01*
G01X513017Y470000D02*
Y472500D01*
X514058D01*
X514392Y472375D01*
X514600Y472208D01*
X514683Y471875D01*
X514600Y471542D01*
X514350Y471333D01*
X514058Y471208D01*
X513017D01*
G01X514058D02*
X514683Y470000D01*
G01X516158Y472083D02*
X516408Y472333D01*
X516700Y472458D01*
X517033Y472500D01*
X517450Y472417D01*
X517742Y472208D01*
X517825Y471958D01*
X517783Y471708D01*
X517617Y471500D01*
X516783Y471083D01*
X516408Y470792D01*
X516158Y470375D01*
X516075Y470000D01*
X517825D01*
G01X519133Y470375D02*
X519383Y470167D01*
X519675Y470042D01*
X520050Y470000D01*
X520425Y470083D01*
X520717Y470250D01*
X520925Y470542D01*
X520967Y470875D01*
X520883Y471208D01*
X520675Y471417D01*
X520383Y471583D01*
X520092Y471625D01*
X519800Y471583D01*
X519425Y471417D01*
X519550Y472500D01*
X520675D01*
G01X521900D02*
X522483Y470000D01*
X523150Y472500D01*
X523817Y470000D01*
X524400Y472500D01*
G01X526750Y470000D02*
Y472500D01*
X525208Y470708D01*
X527292D01*
G01X528558Y471042D02*
X528850Y471333D01*
X529100Y471500D01*
X529433Y471583D01*
X529725Y471500D01*
X529933Y471333D01*
X530100Y471083D01*
X530142Y470792D01*
X530100Y470542D01*
X529933Y470292D01*
X529683Y470083D01*
X529392Y470000D01*
X529058Y470083D01*
X528767Y470333D01*
X528600Y470708D01*
X528558Y471125D01*
X528642Y471667D01*
X528767Y471958D01*
X528975Y472250D01*
X529267Y472458D01*
X529558Y472500D01*
X529850Y472417D01*
X530058Y472208D01*
G01X493717Y466600D02*
Y469100D01*
X494758D01*
X495092Y468975D01*
X495300Y468808D01*
X495383Y468475D01*
X495300Y468142D01*
X495050Y467933D01*
X494758Y467808D01*
X493717D01*
G01X494758D02*
X495383Y466600D01*
G01X496858Y468683D02*
X497108Y468933D01*
X497400Y469058D01*
X497733Y469100D01*
X498150Y469017D01*
X498442Y468808D01*
X498525Y468558D01*
X498483Y468308D01*
X498317Y468100D01*
X497483Y467683D01*
X497108Y467392D01*
X496858Y466975D01*
X496775Y466600D01*
X498525D01*
G01X499833Y466975D02*
X500083Y466767D01*
X500375Y466642D01*
X500750Y466600D01*
X501125Y466683D01*
X501417Y466850D01*
X501625Y467142D01*
X501667Y467475D01*
X501583Y467808D01*
X501375Y468017D01*
X501083Y468183D01*
X500792Y468225D01*
X500500Y468183D01*
X500125Y468017D01*
X500250Y469100D01*
X501375D01*
G01X502600D02*
X503183Y466600D01*
X503850Y469100D01*
X504517Y466600D01*
X505100Y469100D01*
G01X506033Y467100D02*
X506283Y466808D01*
X506617Y466642D01*
X506992Y466600D01*
X507325Y466642D01*
X507658Y466850D01*
X507867Y467100D01*
X507908Y467350D01*
X507825Y467642D01*
X507533Y467850D01*
X507242Y467933D01*
X506867D01*
G01X507242D02*
X507492Y468058D01*
X507700Y468267D01*
X507783Y468517D01*
X507700Y468767D01*
X507492Y468975D01*
X507117Y469100D01*
X506742Y469058D01*
X506367Y468892D01*
G01X489200Y658000D02*
Y661000D01*
X490200D01*
X490600Y660850D01*
X490900Y660650D01*
X491150Y660350D01*
X491350Y660000D01*
X491400Y659500D01*
X491350Y659000D01*
X491150Y658650D01*
X490900Y658350D01*
X490600Y658150D01*
X490200Y658000D01*
X489200D01*
G01X493150Y659350D02*
X494750D01*
X494600Y659700D01*
X494350Y659900D01*
X494000Y660000D01*
X493650Y659950D01*
X493350Y659800D01*
X493150Y659450D01*
X493050Y659150D01*
Y658850D01*
X493150Y658550D01*
X493400Y658250D01*
X493700Y658050D01*
X494050Y658000D01*
X494400Y658100D01*
X494750Y658400D01*
G01X497500Y658000D02*
Y661000D01*
G01X501100D02*
Y658000D01*
G01X500400Y660000D02*
X501800D01*
G01X505600Y658000D02*
Y660000D01*
G01Y659650D02*
X505400Y659850D01*
X505100Y659950D01*
X504750Y660000D01*
X504400Y659900D01*
X504100Y659700D01*
X503900Y659400D01*
X503800Y659000D01*
X503900Y658600D01*
X504100Y658300D01*
X504400Y658100D01*
X504750Y658000D01*
X505100Y658050D01*
X505400Y658200D01*
X505600Y658400D01*
G01X506800Y657000D02*
X509800D01*
G01X510900Y661000D02*
Y658000D01*
X512900D01*
G01X515500D02*
Y661000D01*
X514900Y660400D01*
G01Y658000D02*
X516100D01*
G01X519100Y661000D02*
X518700Y660900D01*
X518400Y660650D01*
X518200Y660350D01*
X518050Y659950D01*
X518000Y659500D01*
X518050Y659050D01*
X518200Y658650D01*
X518400Y658350D01*
X518700Y658100D01*
X519100Y658000D01*
X519500Y658100D01*
X519800Y658350D01*
X520000Y658650D01*
X520150Y659050D01*
X520200Y659500D01*
X520150Y659950D01*
X520000Y660350D01*
X519800Y660650D01*
X519500Y660900D01*
X519100Y661000D01*
G01X521200Y657000D02*
X524200D01*
G01X525200Y658450D02*
X525500Y658200D01*
X525850Y658050D01*
X526300Y658000D01*
X526750Y658100D01*
X527100Y658300D01*
X527350Y658650D01*
X527400Y659050D01*
X527300Y659450D01*
X527050Y659700D01*
X526700Y659900D01*
X526350Y659950D01*
X526000Y659900D01*
X525550Y659700D01*
X525700Y661000D01*
X527050D01*
G01X529900Y660000D02*
Y658000D01*
G01Y660800D02*
X529800Y660850D01*
Y660950D01*
X529900Y661000D01*
X530000Y660950D01*
Y660850D01*
X529900Y660800D01*
G01X532650Y658000D02*
Y660000D01*
G01Y659500D02*
X532850Y659750D01*
X533150Y659950D01*
X533550Y660000D01*
X533900Y659950D01*
X534200Y659750D01*
X534350Y659400D01*
Y658000D01*
G01X537900Y659750D02*
X537550Y659950D01*
X537250Y660000D01*
X536850Y659900D01*
X536550Y659700D01*
X536350Y659350D01*
X536300Y659000D01*
X536350Y658650D01*
X536550Y658350D01*
X536850Y658100D01*
X537250Y658000D01*
X537600Y658100D01*
X537900Y658300D01*
G01X539850Y658000D02*
Y661000D01*
G01Y659550D02*
X540100Y659800D01*
X540350Y659950D01*
X540750Y660000D01*
X541050Y659950D01*
X541400Y659750D01*
X541550Y659450D01*
Y658000D01*
G01X571246Y-38301D02*
X553246D01*
Y-56301D01*
X571246D01*
Y-38301D01*
G01X581720Y9528D02*
X581595Y9278D01*
X581512Y8986D01*
Y8653D01*
X581637Y8278D01*
X581845Y7986D01*
X582095Y7778D01*
X582512Y7611D01*
X582887Y7569D01*
X583262Y7653D01*
X583512Y7778D01*
X583762Y8028D01*
X583929Y8319D01*
X584012Y8611D01*
Y8903D01*
X583929Y9194D01*
X583804Y9444D01*
X583637Y9653D01*
G01X583512Y10794D02*
X583804Y11044D01*
X583970Y11378D01*
X584012Y11753D01*
X583970Y12086D01*
X583762Y12419D01*
X583512Y12628D01*
X583262Y12669D01*
X582970Y12586D01*
X582762Y12294D01*
X582679Y12003D01*
Y11628D01*
G01Y12003D02*
X582554Y12253D01*
X582345Y12461D01*
X582095Y12544D01*
X581845Y12461D01*
X581637Y12253D01*
X581512Y11878D01*
X581554Y11503D01*
X581720Y11128D01*
G01X582762Y15061D02*
Y15894D01*
X583512D01*
X583762Y15644D01*
X583929Y15353D01*
X584012Y14936D01*
X583929Y14519D01*
X583762Y14228D01*
X583512Y13978D01*
X583220Y13811D01*
X582887Y13728D01*
X582595D01*
X582345Y13811D01*
X582054Y13978D01*
X581804Y14228D01*
X581637Y14478D01*
X581512Y14811D01*
Y15103D01*
X581595Y15436D01*
X581762Y15686D01*
G01X584012Y17911D02*
X583970Y18203D01*
X583845Y18536D01*
X583637Y18744D01*
X583345Y18828D01*
X583054Y18744D01*
X582804Y18494D01*
X582679Y18119D01*
Y17703D01*
X582595Y17453D01*
X582387Y17244D01*
X582095Y17161D01*
X581804Y17286D01*
X581595Y17578D01*
X581512Y17911D01*
X581595Y18244D01*
X581804Y18536D01*
X582095Y18661D01*
X582387Y18578D01*
X582595Y18369D01*
X582679Y18119D01*
Y17703D01*
X582804Y17328D01*
X583054Y17078D01*
X583345Y16994D01*
X583637Y17078D01*
X583845Y17286D01*
X583970Y17619D01*
X584012Y17911D01*
G01X576744Y9578D02*
X576619Y9328D01*
X576536Y9036D01*
Y8703D01*
X576661Y8328D01*
X576869Y8036D01*
X577119Y7828D01*
X577536Y7661D01*
X577911Y7619D01*
X578286Y7703D01*
X578536Y7828D01*
X578786Y8078D01*
X578953Y8369D01*
X579036Y8661D01*
Y8953D01*
X578953Y9244D01*
X578828Y9494D01*
X578661Y9703D01*
G01X578536Y10844D02*
X578828Y11094D01*
X578994Y11428D01*
X579036Y11803D01*
X578994Y12136D01*
X578786Y12469D01*
X578536Y12678D01*
X578286Y12719D01*
X577994Y12636D01*
X577786Y12344D01*
X577703Y12053D01*
Y11678D01*
G01Y12053D02*
X577578Y12303D01*
X577369Y12511D01*
X577119Y12594D01*
X576869Y12511D01*
X576661Y12303D01*
X576536Y11928D01*
X576578Y11553D01*
X576744Y11178D01*
G01X577786Y15111D02*
Y15944D01*
X578536D01*
X578786Y15694D01*
X578953Y15403D01*
X579036Y14986D01*
X578953Y14569D01*
X578786Y14278D01*
X578536Y14028D01*
X578244Y13861D01*
X577911Y13778D01*
X577619D01*
X577369Y13861D01*
X577078Y14028D01*
X576828Y14278D01*
X576661Y14528D01*
X576536Y14861D01*
Y15153D01*
X576619Y15486D01*
X576786Y15736D01*
G01X579036Y17878D02*
X578494Y17961D01*
X578036Y18086D01*
X577619Y18253D01*
X577161Y18461D01*
X576536Y18794D01*
Y17128D01*
G01X581761Y47327D02*
X581636Y47077D01*
X581553Y46785D01*
Y46452D01*
X581678Y46077D01*
X581886Y45785D01*
X582136Y45577D01*
X582553Y45410D01*
X582928Y45368D01*
X583303Y45452D01*
X583553Y45577D01*
X583803Y45827D01*
X583970Y46118D01*
X584053Y46410D01*
Y46702D01*
X583970Y46993D01*
X583845Y47243D01*
X583678Y47452D01*
G01X583553Y48593D02*
X583845Y48843D01*
X584011Y49177D01*
X584053Y49552D01*
X584011Y49885D01*
X583803Y50218D01*
X583553Y50427D01*
X583303Y50468D01*
X583011Y50385D01*
X582803Y50093D01*
X582720Y49802D01*
Y49427D01*
G01Y49802D02*
X582595Y50052D01*
X582386Y50260D01*
X582136Y50343D01*
X581886Y50260D01*
X581678Y50052D01*
X581553Y49677D01*
X581595Y49302D01*
X581761Y48927D01*
G01X582803Y52860D02*
Y53693D01*
X583553D01*
X583803Y53443D01*
X583970Y53152D01*
X584053Y52735D01*
X583970Y52318D01*
X583803Y52027D01*
X583553Y51777D01*
X583261Y51610D01*
X582928Y51527D01*
X582636D01*
X582386Y51610D01*
X582095Y51777D01*
X581845Y52027D01*
X581678Y52277D01*
X581553Y52610D01*
Y52902D01*
X581636Y53235D01*
X581803Y53485D01*
G01X584053Y56210D02*
X581553D01*
X583345Y54668D01*
Y56752D01*
G01X576676Y47396D02*
X576551Y47146D01*
X576468Y46854D01*
Y46521D01*
X576593Y46146D01*
X576801Y45854D01*
X577051Y45646D01*
X577468Y45479D01*
X577843Y45437D01*
X578218Y45521D01*
X578468Y45646D01*
X578718Y45896D01*
X578885Y46187D01*
X578968Y46479D01*
Y46771D01*
X578885Y47062D01*
X578760Y47312D01*
X578593Y47521D01*
G01X578468Y48662D02*
X578760Y48912D01*
X578926Y49246D01*
X578968Y49621D01*
X578926Y49954D01*
X578718Y50287D01*
X578468Y50496D01*
X578218Y50537D01*
X577926Y50454D01*
X577718Y50162D01*
X577635Y49871D01*
Y49496D01*
G01Y49871D02*
X577510Y50121D01*
X577301Y50329D01*
X577051Y50412D01*
X576801Y50329D01*
X576593Y50121D01*
X576468Y49746D01*
X576510Y49371D01*
X576676Y48996D01*
G01X577718Y52929D02*
Y53762D01*
X578468D01*
X578718Y53512D01*
X578885Y53221D01*
X578968Y52804D01*
X578885Y52387D01*
X578718Y52096D01*
X578468Y51846D01*
X578176Y51679D01*
X577843Y51596D01*
X577551D01*
X577301Y51679D01*
X577010Y51846D01*
X576760Y52096D01*
X576593Y52346D01*
X576468Y52679D01*
Y52971D01*
X576551Y53304D01*
X576718Y53554D01*
G01X578468Y54862D02*
X578760Y55112D01*
X578926Y55446D01*
X578968Y55821D01*
X578926Y56154D01*
X578718Y56487D01*
X578468Y56696D01*
X578218Y56737D01*
X577926Y56654D01*
X577718Y56362D01*
X577635Y56071D01*
Y55696D01*
G01Y56071D02*
X577510Y56321D01*
X577301Y56529D01*
X577051Y56612D01*
X576801Y56529D01*
X576593Y56321D01*
X576468Y55946D01*
X576510Y55571D01*
X576676Y55196D01*
G01X596457Y96281D02*
X596207Y96406D01*
X595915Y96489D01*
X595582D01*
X595207Y96364D01*
X594915Y96156D01*
X594707Y95906D01*
X594540Y95489D01*
X594498Y95114D01*
X594582Y94739D01*
X594707Y94489D01*
X594957Y94239D01*
X595248Y94072D01*
X595540Y93989D01*
X595832D01*
X596123Y94072D01*
X596373Y94197D01*
X596582Y94364D01*
G01X597723Y94489D02*
X597973Y94197D01*
X598307Y94031D01*
X598682Y93989D01*
X599015Y94031D01*
X599348Y94239D01*
X599557Y94489D01*
X599598Y94739D01*
X599515Y95031D01*
X599223Y95239D01*
X598932Y95322D01*
X598557D01*
G01X598932D02*
X599182Y95447D01*
X599390Y95656D01*
X599473Y95906D01*
X599390Y96156D01*
X599182Y96364D01*
X598807Y96489D01*
X598432Y96447D01*
X598057Y96281D01*
G01X600948Y93989D02*
Y96489D01*
X602532D01*
G01X601948Y95281D02*
X600948D01*
G01X603923Y94489D02*
X604173Y94197D01*
X604507Y94031D01*
X604882Y93989D01*
X605215Y94031D01*
X605548Y94239D01*
X605757Y94489D01*
X605798Y94739D01*
X605715Y95031D01*
X605423Y95239D01*
X605132Y95322D01*
X604757D01*
G01X605132D02*
X605382Y95447D01*
X605590Y95656D01*
X605673Y95906D01*
X605590Y96156D01*
X605382Y96364D01*
X605007Y96489D01*
X604632Y96447D01*
X604257Y96281D01*
G01X596597Y146560D02*
X570009D01*
X570008Y146561D01*
Y174452D01*
X576999D01*
X577000Y174453D01*
Y197500D01*
X586000D01*
Y201750D01*
X586001Y201751D01*
X598749D01*
G01X606500Y202251D02*
X628873D01*
Y146560D01*
X600720D01*
G01X589989Y148710D02*
X587489D01*
Y149751D01*
X587614Y150085D01*
X587781Y150293D01*
X588114Y150376D01*
X588447Y150293D01*
X588656Y150043D01*
X588781Y149751D01*
Y148710D01*
G01Y149751D02*
X589989Y150376D01*
G01Y152643D02*
X587489D01*
X587989Y152143D01*
G01X589989D02*
Y153143D01*
G01X588739Y155993D02*
Y156826D01*
X589489D01*
X589739Y156576D01*
X589906Y156285D01*
X589989Y155868D01*
X589906Y155451D01*
X589739Y155160D01*
X589489Y154910D01*
X589197Y154743D01*
X588864Y154660D01*
X588572D01*
X588322Y154743D01*
X588031Y154910D01*
X587781Y155160D01*
X587614Y155410D01*
X587489Y155743D01*
Y156035D01*
X587572Y156368D01*
X587739Y156618D01*
G01X587906Y158051D02*
X587656Y158301D01*
X587531Y158593D01*
X587489Y158926D01*
X587572Y159343D01*
X587781Y159635D01*
X588031Y159718D01*
X588281Y159676D01*
X588489Y159510D01*
X588906Y158676D01*
X589197Y158301D01*
X589614Y158051D01*
X589989Y157968D01*
Y159718D01*
G01X588947Y161151D02*
X588656Y161443D01*
X588489Y161693D01*
X588406Y162026D01*
X588489Y162318D01*
X588656Y162526D01*
X588906Y162693D01*
X589197Y162735D01*
X589447Y162693D01*
X589697Y162526D01*
X589906Y162276D01*
X589989Y161985D01*
X589906Y161651D01*
X589656Y161360D01*
X589281Y161193D01*
X588864Y161151D01*
X588322Y161235D01*
X588031Y161360D01*
X587739Y161568D01*
X587531Y161860D01*
X587489Y162151D01*
X587572Y162443D01*
X587781Y162651D01*
G01X594300Y151817D02*
X591800D01*
Y152858D01*
X591925Y153192D01*
X592092Y153400D01*
X592425Y153483D01*
X592758Y153400D01*
X592967Y153150D01*
X593092Y152858D01*
Y151817D01*
G01Y152858D02*
X594300Y153483D01*
G01X591800Y155750D02*
X594300D01*
G01X591800Y154792D02*
Y156708D01*
G01X594300Y158850D02*
X591800D01*
X592300Y158350D01*
G01X594300D02*
Y159350D01*
G01X594008Y161242D02*
X594217Y161533D01*
X594300Y161867D01*
X594217Y162200D01*
X593967Y162492D01*
X593592Y162700D01*
X593217Y162783D01*
X592758D01*
X592383Y162700D01*
X592050Y162492D01*
X591883Y162242D01*
X591800Y161950D01*
X591883Y161617D01*
X592050Y161367D01*
X592300Y161200D01*
X592633Y161117D01*
X592925Y161200D01*
X593217Y161408D01*
X593383Y161658D01*
X593425Y161950D01*
X593342Y162283D01*
X593133Y162533D01*
X592758Y162783D01*
G01X583860Y103496D02*
X583610Y103621D01*
X583318Y103704D01*
X582985D01*
X582610Y103579D01*
X582318Y103371D01*
X582110Y103121D01*
X581943Y102704D01*
X581901Y102329D01*
X581985Y101954D01*
X582110Y101704D01*
X582360Y101454D01*
X582651Y101287D01*
X582943Y101204D01*
X583235D01*
X583526Y101287D01*
X583776Y101412D01*
X583985Y101579D01*
G01X585126Y101704D02*
X585376Y101412D01*
X585710Y101246D01*
X586085Y101204D01*
X586418Y101246D01*
X586751Y101454D01*
X586960Y101704D01*
X587001Y101954D01*
X586918Y102246D01*
X586626Y102454D01*
X586335Y102537D01*
X585960D01*
G01X586335D02*
X586585Y102662D01*
X586793Y102871D01*
X586876Y103121D01*
X586793Y103371D01*
X586585Y103579D01*
X586210Y103704D01*
X585835Y103662D01*
X585460Y103496D01*
G01X588351Y101204D02*
Y103704D01*
X589935D01*
G01X589351Y102496D02*
X588351D01*
G01X591451Y103287D02*
X591701Y103537D01*
X591993Y103662D01*
X592326Y103704D01*
X592743Y103621D01*
X593035Y103412D01*
X593118Y103162D01*
X593076Y102912D01*
X592910Y102704D01*
X592076Y102287D01*
X591701Y101996D01*
X591451Y101579D01*
X591368Y101204D01*
X593118D01*
G01X590574Y129356D02*
Y130481D01*
X589741Y131856D01*
G01X591407D02*
X590574Y130481D01*
G01X592757Y129856D02*
X593007Y129564D01*
X593341Y129398D01*
X593716Y129356D01*
X594049Y129398D01*
X594382Y129606D01*
X594591Y129856D01*
X594632Y130106D01*
X594549Y130398D01*
X594257Y130606D01*
X593966Y130689D01*
X593591D01*
G01X593966D02*
X594216Y130814D01*
X594424Y131023D01*
X594507Y131273D01*
X594424Y131523D01*
X594216Y131731D01*
X593841Y131856D01*
X593466Y131814D01*
X593091Y131648D01*
G01X595982Y129356D02*
Y131856D01*
X597566D01*
G01X596982Y130648D02*
X595982D01*
G01X599874Y129356D02*
Y131856D01*
X599374Y131356D01*
G01Y129356D02*
X600374D01*
G01X588207Y125865D02*
Y127936D01*
G01X601593Y109432D02*
Y107464D01*
X588207D01*
Y109458D01*
G01Y127936D02*
X601593D01*
Y125814D01*
G01X573117Y158792D02*
X572867Y158917D01*
X572575Y159000D01*
X572242D01*
X571867Y158875D01*
X571575Y158667D01*
X571367Y158417D01*
X571200Y158000D01*
X571158Y157625D01*
X571242Y157250D01*
X571367Y157000D01*
X571617Y156750D01*
X571908Y156583D01*
X572200Y156500D01*
X572492D01*
X572783Y156583D01*
X573033Y156708D01*
X573242Y156875D01*
G01X575300Y156500D02*
Y159000D01*
X574800Y158500D01*
G01Y156500D02*
X575800D01*
G01X578650Y157750D02*
X579483D01*
Y157000D01*
X579233Y156750D01*
X578942Y156583D01*
X578525Y156500D01*
X578108Y156583D01*
X577817Y156750D01*
X577567Y157000D01*
X577400Y157292D01*
X577317Y157625D01*
Y157917D01*
X577400Y158167D01*
X577567Y158458D01*
X577817Y158708D01*
X578067Y158875D01*
X578400Y159000D01*
X578692D01*
X579025Y158917D01*
X579275Y158750D01*
G01X581500Y156500D02*
Y159000D01*
X581000Y158500D01*
G01Y156500D02*
X582000D01*
G01X583683Y156875D02*
X583933Y156667D01*
X584225Y156542D01*
X584600Y156500D01*
X584975Y156583D01*
X585267Y156750D01*
X585475Y157042D01*
X585517Y157375D01*
X585433Y157708D01*
X585225Y157917D01*
X584933Y158083D01*
X584642Y158125D01*
X584350Y158083D01*
X583975Y157917D01*
X584100Y159000D01*
X585225D01*
G01X585910Y184511D02*
X580576D01*
Y191511D01*
X585910D01*
G01X583776Y188128D02*
X580576D01*
G01X585263Y169161D02*
X582763D01*
Y170202D01*
X582888Y170536D01*
X583055Y170744D01*
X583388Y170827D01*
X583721Y170744D01*
X583930Y170494D01*
X584055Y170202D01*
Y169161D01*
G01Y170202D02*
X585263Y170827D01*
G01Y173094D02*
X582763D01*
X583263Y172594D01*
G01X585263D02*
Y173594D01*
G01X584013Y176444D02*
Y177277D01*
X584763D01*
X585013Y177027D01*
X585180Y176736D01*
X585263Y176319D01*
X585180Y175902D01*
X585013Y175611D01*
X584763Y175361D01*
X584471Y175194D01*
X584138Y175111D01*
X583846D01*
X583596Y175194D01*
X583305Y175361D01*
X583055Y175611D01*
X582888Y175861D01*
X582763Y176194D01*
Y176486D01*
X582846Y176819D01*
X583013Y177069D01*
G01X583180Y178502D02*
X582930Y178752D01*
X582805Y179044D01*
X582763Y179377D01*
X582846Y179794D01*
X583055Y180086D01*
X583305Y180169D01*
X583555Y180127D01*
X583763Y179961D01*
X584180Y179127D01*
X584471Y178752D01*
X584888Y178502D01*
X585263Y178419D01*
Y180169D01*
G01X584888Y181477D02*
X585096Y181727D01*
X585221Y182019D01*
X585263Y182394D01*
X585180Y182769D01*
X585013Y183061D01*
X584721Y183269D01*
X584388Y183311D01*
X584055Y183227D01*
X583846Y183019D01*
X583680Y182727D01*
X583638Y182436D01*
X583680Y182144D01*
X583846Y181769D01*
X582763Y181894D01*
Y183019D01*
G01X588560Y188411D02*
Y190911D01*
X589601D01*
X589935Y190786D01*
X590143Y190619D01*
X590226Y190286D01*
X590143Y189953D01*
X589893Y189744D01*
X589601Y189619D01*
X588560D01*
G01X589601D02*
X590226Y188411D01*
G01X592493Y190911D02*
Y188411D01*
G01X591535Y190911D02*
X593451D01*
G01X594801Y190494D02*
X595051Y190744D01*
X595343Y190869D01*
X595676Y190911D01*
X596093Y190828D01*
X596385Y190619D01*
X596468Y190369D01*
X596426Y190119D01*
X596260Y189911D01*
X595426Y189494D01*
X595051Y189203D01*
X594801Y188786D01*
X594718Y188411D01*
X596468D01*
G01X598693D02*
Y190911D01*
X598193Y190411D01*
G01Y188411D02*
X599193D01*
G01X597723Y178302D02*
X597473Y178427D01*
X597181Y178510D01*
X596848D01*
X596473Y178385D01*
X596181Y178177D01*
X595973Y177927D01*
X595806Y177510D01*
X595764Y177135D01*
X595848Y176760D01*
X595973Y176510D01*
X596223Y176260D01*
X596514Y176093D01*
X596806Y176010D01*
X597098D01*
X597389Y176093D01*
X597639Y176218D01*
X597848Y176385D01*
G01X599906Y176010D02*
Y178510D01*
X599406Y178010D01*
G01Y176010D02*
X600406D01*
G01X603256Y177260D02*
X604089D01*
Y176510D01*
X603839Y176260D01*
X603548Y176093D01*
X603131Y176010D01*
X602714Y176093D01*
X602423Y176260D01*
X602173Y176510D01*
X602006Y176802D01*
X601923Y177135D01*
Y177427D01*
X602006Y177677D01*
X602173Y177968D01*
X602423Y178218D01*
X602673Y178385D01*
X603006Y178510D01*
X603298D01*
X603631Y178427D01*
X603881Y178260D01*
G01X606106Y176010D02*
Y178510D01*
X605606Y178010D01*
G01Y176010D02*
X606606D01*
G01X609706D02*
Y178510D01*
X608164Y176718D01*
X610248D01*
G01X590166Y198800D02*
X589916Y198925D01*
X589624Y199008D01*
X589291D01*
X588916Y198883D01*
X588624Y198675D01*
X588416Y198425D01*
X588249Y198008D01*
X588207Y197633D01*
X588291Y197258D01*
X588416Y197008D01*
X588666Y196758D01*
X588957Y196591D01*
X589249Y196508D01*
X589541D01*
X589832Y196591D01*
X590082Y196716D01*
X590291Y196883D01*
G01X592349Y196508D02*
Y199008D01*
X591849Y198508D01*
G01Y196508D02*
X592849D01*
G01X594657D02*
Y199008D01*
X596241D01*
G01X595657Y197800D02*
X594657D01*
G01X597757Y198591D02*
X598007Y198841D01*
X598299Y198966D01*
X598632Y199008D01*
X599049Y198925D01*
X599341Y198716D01*
X599424Y198466D01*
X599382Y198216D01*
X599216Y198008D01*
X598382Y197591D01*
X598007Y197300D01*
X597757Y196883D01*
X597674Y196508D01*
X599424D01*
G01X601566D02*
X601649Y197050D01*
X601774Y197508D01*
X601941Y197925D01*
X602149Y198383D01*
X602482Y199008D01*
X600816D01*
G01X591889Y173165D02*
X591764Y172915D01*
X591681Y172623D01*
Y172290D01*
X591806Y171915D01*
X592014Y171623D01*
X592264Y171415D01*
X592681Y171248D01*
X593056Y171206D01*
X593431Y171290D01*
X593681Y171415D01*
X593931Y171665D01*
X594098Y171956D01*
X594181Y172248D01*
Y172540D01*
X594098Y172831D01*
X593973Y173081D01*
X593806Y173290D01*
G01X594181Y175348D02*
X591681D01*
X592181Y174848D01*
G01X594181D02*
Y175848D01*
G01X592931Y178698D02*
Y179531D01*
X593681D01*
X593931Y179281D01*
X594098Y178990D01*
X594181Y178573D01*
X594098Y178156D01*
X593931Y177865D01*
X593681Y177615D01*
X593389Y177448D01*
X593056Y177365D01*
X592764D01*
X592514Y177448D01*
X592223Y177615D01*
X591973Y177865D01*
X591806Y178115D01*
X591681Y178448D01*
Y178740D01*
X591764Y179073D01*
X591931Y179323D01*
G01X592098Y180756D02*
X591848Y181006D01*
X591723Y181298D01*
X591681Y181631D01*
X591764Y182048D01*
X591973Y182340D01*
X592223Y182423D01*
X592473Y182381D01*
X592681Y182215D01*
X593098Y181381D01*
X593389Y181006D01*
X593806Y180756D01*
X594181Y180673D01*
Y182423D01*
G01Y184648D02*
X594139Y184940D01*
X594014Y185273D01*
X593806Y185481D01*
X593514Y185565D01*
X593223Y185481D01*
X592973Y185231D01*
X592848Y184856D01*
Y184440D01*
X592764Y184190D01*
X592556Y183981D01*
X592264Y183898D01*
X591973Y184023D01*
X591764Y184315D01*
X591681Y184648D01*
X591764Y184981D01*
X591973Y185273D01*
X592264Y185398D01*
X592556Y185315D01*
X592764Y185106D01*
X592848Y184856D01*
Y184440D01*
X592973Y184065D01*
X593223Y183815D01*
X593514Y183731D01*
X593806Y183815D01*
X594014Y184023D01*
X594139Y184356D01*
X594181Y184648D01*
G01X597561Y182716D02*
X597311Y182841D01*
X597019Y182924D01*
X596686D01*
X596311Y182799D01*
X596019Y182591D01*
X595811Y182341D01*
X595644Y181924D01*
X595602Y181549D01*
X595686Y181174D01*
X595811Y180924D01*
X596061Y180674D01*
X596352Y180507D01*
X596644Y180424D01*
X596936D01*
X597227Y180507D01*
X597477Y180632D01*
X597686Y180799D01*
G01X599744Y180424D02*
Y182924D01*
X599244Y182424D01*
G01Y180424D02*
X600244D01*
G01X603094Y181674D02*
X603927D01*
Y180924D01*
X603677Y180674D01*
X603386Y180507D01*
X602969Y180424D01*
X602552Y180507D01*
X602261Y180674D01*
X602011Y180924D01*
X601844Y181216D01*
X601761Y181549D01*
Y181841D01*
X601844Y182091D01*
X602011Y182382D01*
X602261Y182632D01*
X602511Y182799D01*
X602844Y182924D01*
X603136D01*
X603469Y182841D01*
X603719Y182674D01*
G01X605152Y182507D02*
X605402Y182757D01*
X605694Y182882D01*
X606027Y182924D01*
X606444Y182841D01*
X606736Y182632D01*
X606819Y182382D01*
X606777Y182132D01*
X606611Y181924D01*
X605777Y181507D01*
X605402Y181216D01*
X605152Y180799D01*
X605069Y180424D01*
X606819D01*
G01X608336Y180716D02*
X608627Y180507D01*
X608961Y180424D01*
X609294Y180507D01*
X609586Y180757D01*
X609794Y181132D01*
X609877Y181507D01*
Y181966D01*
X609794Y182341D01*
X609586Y182674D01*
X609336Y182841D01*
X609044Y182924D01*
X608711Y182841D01*
X608461Y182674D01*
X608294Y182424D01*
X608211Y182091D01*
X608294Y181799D01*
X608502Y181507D01*
X608752Y181341D01*
X609044Y181299D01*
X609377Y181382D01*
X609627Y181591D01*
X609877Y181966D01*
G01X590166Y194800D02*
X589916Y194925D01*
X589624Y195008D01*
X589291D01*
X588916Y194883D01*
X588624Y194675D01*
X588416Y194425D01*
X588249Y194008D01*
X588207Y193633D01*
X588291Y193258D01*
X588416Y193008D01*
X588666Y192758D01*
X588957Y192591D01*
X589249Y192508D01*
X589541D01*
X589832Y192591D01*
X590082Y192716D01*
X590291Y192883D01*
G01X592349Y192508D02*
Y195008D01*
X591849Y194508D01*
G01Y192508D02*
X592849D01*
G01X594657D02*
Y195008D01*
X596241D01*
G01X595657Y193800D02*
X594657D01*
G01X597757Y194591D02*
X598007Y194841D01*
X598299Y194966D01*
X598632Y195008D01*
X599049Y194925D01*
X599341Y194716D01*
X599424Y194466D01*
X599382Y194216D01*
X599216Y194008D01*
X598382Y193591D01*
X598007Y193300D01*
X597757Y192883D01*
X597674Y192508D01*
X599424D01*
G01X600857Y193550D02*
X601149Y193841D01*
X601399Y194008D01*
X601732Y194091D01*
X602024Y194008D01*
X602232Y193841D01*
X602399Y193591D01*
X602441Y193300D01*
X602399Y193050D01*
X602232Y192800D01*
X601982Y192591D01*
X601691Y192508D01*
X601357Y192591D01*
X601066Y192841D01*
X600899Y193216D01*
X600857Y193633D01*
X600941Y194175D01*
X601066Y194466D01*
X601274Y194758D01*
X601566Y194966D01*
X601857Y195008D01*
X602149Y194925D01*
X602357Y194716D01*
G01X597936Y173057D02*
X597686Y173182D01*
X597394Y173265D01*
X597061D01*
X596686Y173140D01*
X596394Y172932D01*
X596186Y172682D01*
X596019Y172265D01*
X595977Y171890D01*
X596061Y171515D01*
X596186Y171265D01*
X596436Y171015D01*
X596727Y170848D01*
X597019Y170765D01*
X597311D01*
X597602Y170848D01*
X597852Y170973D01*
X598061Y171140D01*
G01X600119Y173265D02*
Y170765D01*
G01X599161Y173265D02*
X601077D01*
G01X602302Y171265D02*
X602552Y170973D01*
X602886Y170807D01*
X603261Y170765D01*
X603594Y170807D01*
X603927Y171015D01*
X604136Y171265D01*
X604177Y171515D01*
X604094Y171807D01*
X603802Y172015D01*
X603511Y172098D01*
X603136D01*
G01X603511D02*
X603761Y172223D01*
X603969Y172432D01*
X604052Y172682D01*
X603969Y172932D01*
X603761Y173140D01*
X603386Y173265D01*
X603011Y173223D01*
X602636Y173057D01*
G01X606319Y170765D02*
Y173265D01*
X605819Y172765D01*
G01Y170765D02*
X606819D01*
G01X596713Y168802D02*
X596463Y168927D01*
X596171Y169010D01*
X595838D01*
X595463Y168885D01*
X595171Y168677D01*
X594963Y168427D01*
X594796Y168010D01*
X594754Y167635D01*
X594838Y167260D01*
X594963Y167010D01*
X595213Y166760D01*
X595504Y166593D01*
X595796Y166510D01*
X596088D01*
X596379Y166593D01*
X596629Y166718D01*
X596838Y166885D01*
G01X598896Y166510D02*
Y169010D01*
X598396Y168510D01*
G01Y166510D02*
X599396D01*
G01X602246Y167760D02*
X603079D01*
Y167010D01*
X602829Y166760D01*
X602538Y166593D01*
X602121Y166510D01*
X601704Y166593D01*
X601413Y166760D01*
X601163Y167010D01*
X600996Y167302D01*
X600913Y167635D01*
Y167927D01*
X600996Y168177D01*
X601163Y168468D01*
X601413Y168718D01*
X601663Y168885D01*
X601996Y169010D01*
X602288D01*
X602621Y168927D01*
X602871Y168760D01*
G01X605096Y166510D02*
Y169010D01*
X604596Y168510D01*
G01Y166510D02*
X605596D01*
G01X608196D02*
Y169010D01*
X607696Y168510D01*
G01Y166510D02*
X608696D01*
G01X581941Y218781D02*
X581749Y219091D01*
X581519Y219298D01*
X581251Y219401D01*
X580944Y219298D01*
X580714Y219091D01*
X580484Y218781D01*
X580407Y218368D01*
Y216301D01*
G01X582676Y203418D02*
X581718Y200318D01*
X580760Y203418D01*
G01X581105Y202333D02*
X582331D01*
G01X544031Y174409D02*
X543763Y174048D01*
X543533Y173841D01*
X543226Y173738D01*
X542958Y173841D01*
X542766Y174048D01*
X542613Y174358D01*
X542575Y174719D01*
X542613Y175029D01*
X542766Y175339D01*
X542996Y175598D01*
X543265Y175701D01*
X543571Y175598D01*
X543840Y175288D01*
X543993Y174823D01*
X544031Y174306D01*
X543955Y173634D01*
X543840Y173273D01*
X543648Y172911D01*
X543380Y172653D01*
X543111Y172601D01*
X542843Y172704D01*
X542651Y172963D01*
G01X549603Y175701D02*
Y172601D01*
X551021Y174823D01*
X549105D01*
G01X544143Y179180D02*
X543913Y179542D01*
X543607Y179748D01*
X543262Y179800D01*
X542955Y179748D01*
X542648Y179490D01*
X542457Y179180D01*
X542418Y178870D01*
X542495Y178508D01*
X542763Y178250D01*
X543032Y178147D01*
X543377D01*
G01X543032D02*
X542802Y177992D01*
X542610Y177733D01*
X542533Y177423D01*
X542610Y177113D01*
X542802Y176855D01*
X543147Y176700D01*
X543492Y176752D01*
X543837Y176958D01*
G01X557551Y173118D02*
X557321Y172808D01*
X557053Y172653D01*
X556746Y172601D01*
X556363Y172704D01*
X556095Y172963D01*
X556018Y173273D01*
X556056Y173583D01*
X556210Y173841D01*
X556976Y174358D01*
X557321Y174719D01*
X557551Y175236D01*
X557628Y175701D01*
X556018D01*
G01X545700Y179900D02*
Y176800D01*
X546160Y177420D01*
G01Y179900D02*
X545240D01*
G01X578755Y166546D02*
X581255D01*
Y168212D01*
G01Y170479D02*
X578755D01*
X579255Y169979D01*
G01X581255D02*
Y170979D01*
G01Y172787D02*
X578755D01*
Y174371D01*
G01X579963Y173787D02*
Y172787D01*
G01X581255Y176679D02*
X578755D01*
X579255Y176179D01*
G01X581255D02*
Y177179D01*
G01X573117Y162592D02*
X572867Y162717D01*
X572575Y162800D01*
X572242D01*
X571867Y162675D01*
X571575Y162467D01*
X571367Y162217D01*
X571200Y161800D01*
X571158Y161425D01*
X571242Y161050D01*
X571367Y160800D01*
X571617Y160550D01*
X571908Y160383D01*
X572200Y160300D01*
X572492D01*
X572783Y160383D01*
X573033Y160508D01*
X573242Y160675D01*
G01X575300Y160300D02*
Y162800D01*
X574800Y162300D01*
G01Y160300D02*
X575800D01*
G01X578650Y161550D02*
X579483D01*
Y160800D01*
X579233Y160550D01*
X578942Y160383D01*
X578525Y160300D01*
X578108Y160383D01*
X577817Y160550D01*
X577567Y160800D01*
X577400Y161092D01*
X577317Y161425D01*
Y161717D01*
X577400Y161967D01*
X577567Y162258D01*
X577817Y162508D01*
X578067Y162675D01*
X578400Y162800D01*
X578692D01*
X579025Y162717D01*
X579275Y162550D01*
G01X581500Y160300D02*
Y162800D01*
X581000Y162300D01*
G01Y160300D02*
X582000D01*
G01X583808Y162383D02*
X584058Y162633D01*
X584350Y162758D01*
X584683Y162800D01*
X585100Y162717D01*
X585392Y162508D01*
X585475Y162258D01*
X585433Y162008D01*
X585267Y161800D01*
X584433Y161383D01*
X584058Y161092D01*
X583808Y160675D01*
X583725Y160300D01*
X585475D01*
G01X593096Y267049D02*
X590596D01*
Y268090D01*
X590721Y268424D01*
X590888Y268632D01*
X591221Y268715D01*
X591554Y268632D01*
X591763Y268382D01*
X591888Y268090D01*
Y267049D01*
G01Y268090D02*
X593096Y268715D01*
G01X592596Y270065D02*
X592888Y270315D01*
X593054Y270649D01*
X593096Y271024D01*
X593054Y271357D01*
X592846Y271690D01*
X592596Y271899D01*
X592346Y271940D01*
X592054Y271857D01*
X591846Y271565D01*
X591763Y271274D01*
Y270899D01*
G01Y271274D02*
X591638Y271524D01*
X591429Y271732D01*
X591179Y271815D01*
X590929Y271732D01*
X590721Y271524D01*
X590596Y271149D01*
X590638Y270774D01*
X590804Y270399D01*
G01X593096Y273165D02*
X590596D01*
Y273999D01*
X590721Y274332D01*
X590888Y274582D01*
X591138Y274790D01*
X591429Y274957D01*
X591846Y274999D01*
X592263Y274957D01*
X592554Y274790D01*
X592804Y274582D01*
X592971Y274332D01*
X593096Y273999D01*
Y273165D01*
G01X591013Y276390D02*
X590763Y276640D01*
X590638Y276932D01*
X590596Y277265D01*
X590679Y277682D01*
X590888Y277974D01*
X591138Y278057D01*
X591388Y278015D01*
X591596Y277849D01*
X592013Y277015D01*
X592304Y276640D01*
X592721Y276390D01*
X593096Y276307D01*
Y278057D01*
G01X590596Y280282D02*
X590679Y279949D01*
X590888Y279699D01*
X591138Y279532D01*
X591471Y279407D01*
X591846Y279365D01*
X592221Y279407D01*
X592554Y279532D01*
X592804Y279699D01*
X593013Y279949D01*
X593096Y280282D01*
X593013Y280615D01*
X592804Y280865D01*
X592554Y281032D01*
X592221Y281157D01*
X591846Y281199D01*
X591471Y281157D01*
X591138Y281032D01*
X590888Y280865D01*
X590679Y280615D01*
X590596Y280282D01*
G01X597868Y278832D02*
Y281332D01*
X598909D01*
X599243Y281207D01*
X599451Y281040D01*
X599534Y280707D01*
X599451Y280374D01*
X599201Y280165D01*
X598909Y280040D01*
X597868D01*
G01X598909D02*
X599534Y278832D01*
G01X602301D02*
Y281332D01*
X600759Y279540D01*
X602843D01*
G01X603984Y278832D02*
Y281332D01*
X604818D01*
X605151Y281207D01*
X605401Y281040D01*
X605609Y280790D01*
X605776Y280499D01*
X605818Y280082D01*
X605776Y279665D01*
X605609Y279374D01*
X605401Y279124D01*
X605151Y278957D01*
X604818Y278832D01*
X603984D01*
G01X608501D02*
Y281332D01*
X606959Y279540D01*
X609043D01*
G01X610393Y279124D02*
X610684Y278915D01*
X611018Y278832D01*
X611351Y278915D01*
X611643Y279165D01*
X611851Y279540D01*
X611934Y279915D01*
Y280374D01*
X611851Y280749D01*
X611643Y281082D01*
X611393Y281249D01*
X611101Y281332D01*
X610768Y281249D01*
X610518Y281082D01*
X610351Y280832D01*
X610268Y280499D01*
X610351Y280207D01*
X610559Y279915D01*
X610809Y279749D01*
X611101Y279707D01*
X611434Y279790D01*
X611684Y279999D01*
X611934Y280374D01*
G01X597868Y268332D02*
Y270832D01*
X598909D01*
X599243Y270707D01*
X599451Y270540D01*
X599534Y270207D01*
X599451Y269874D01*
X599201Y269665D01*
X598909Y269540D01*
X597868D01*
G01X598909D02*
X599534Y268332D01*
G01X602301D02*
Y270832D01*
X600759Y269040D01*
X602843D01*
G01X603984Y268332D02*
Y270832D01*
X604818D01*
X605151Y270707D01*
X605401Y270540D01*
X605609Y270290D01*
X605776Y269999D01*
X605818Y269582D01*
X605776Y269165D01*
X605609Y268874D01*
X605401Y268624D01*
X605151Y268457D01*
X604818Y268332D01*
X603984D01*
G01X607084Y268707D02*
X607334Y268499D01*
X607626Y268374D01*
X608001Y268332D01*
X608376Y268415D01*
X608668Y268582D01*
X608876Y268874D01*
X608918Y269207D01*
X608834Y269540D01*
X608626Y269749D01*
X608334Y269915D01*
X608043Y269957D01*
X607751Y269915D01*
X607376Y269749D01*
X607501Y270832D01*
X608626D01*
G01X610309Y269374D02*
X610601Y269665D01*
X610851Y269832D01*
X611184Y269915D01*
X611476Y269832D01*
X611684Y269665D01*
X611851Y269415D01*
X611893Y269124D01*
X611851Y268874D01*
X611684Y268624D01*
X611434Y268415D01*
X611143Y268332D01*
X610809Y268415D01*
X610518Y268665D01*
X610351Y269040D01*
X610309Y269457D01*
X610393Y269999D01*
X610518Y270290D01*
X610726Y270582D01*
X611018Y270790D01*
X611309Y270832D01*
X611601Y270749D01*
X611809Y270540D01*
G01X597868Y275332D02*
Y277832D01*
X598909D01*
X599243Y277707D01*
X599451Y277540D01*
X599534Y277207D01*
X599451Y276874D01*
X599201Y276665D01*
X598909Y276540D01*
X597868D01*
G01X598909D02*
X599534Y275332D01*
G01X602301D02*
Y277832D01*
X600759Y276040D01*
X602843D01*
G01X603984Y275332D02*
Y277832D01*
X604818D01*
X605151Y277707D01*
X605401Y277540D01*
X605609Y277290D01*
X605776Y276999D01*
X605818Y276582D01*
X605776Y276165D01*
X605609Y275874D01*
X605401Y275624D01*
X605151Y275457D01*
X604818Y275332D01*
X603984D01*
G01X607084Y275707D02*
X607334Y275499D01*
X607626Y275374D01*
X608001Y275332D01*
X608376Y275415D01*
X608668Y275582D01*
X608876Y275874D01*
X608918Y276207D01*
X608834Y276540D01*
X608626Y276749D01*
X608334Y276915D01*
X608043Y276957D01*
X607751Y276915D01*
X607376Y276749D01*
X607501Y277832D01*
X608626D01*
G01X611101Y275332D02*
Y277832D01*
X610601Y277332D01*
G01Y275332D02*
X611601D01*
G01X597868Y271832D02*
Y274332D01*
X598909D01*
X599243Y274207D01*
X599451Y274040D01*
X599534Y273707D01*
X599451Y273374D01*
X599201Y273165D01*
X598909Y273040D01*
X597868D01*
G01X598909D02*
X599534Y271832D01*
G01X602301D02*
Y274332D01*
X600759Y272540D01*
X602843D01*
G01X603984Y271832D02*
Y274332D01*
X604818D01*
X605151Y274207D01*
X605401Y274040D01*
X605609Y273790D01*
X605776Y273499D01*
X605818Y273082D01*
X605776Y272665D01*
X605609Y272374D01*
X605401Y272124D01*
X605151Y271957D01*
X604818Y271832D01*
X603984D01*
G01X607084Y272207D02*
X607334Y271999D01*
X607626Y271874D01*
X608001Y271832D01*
X608376Y271915D01*
X608668Y272082D01*
X608876Y272374D01*
X608918Y272707D01*
X608834Y273040D01*
X608626Y273249D01*
X608334Y273415D01*
X608043Y273457D01*
X607751Y273415D01*
X607376Y273249D01*
X607501Y274332D01*
X608626D01*
G01X611601Y271832D02*
Y274332D01*
X610059Y272540D01*
X612143D01*
G01X589773Y261694D02*
Y264194D01*
X590814D01*
X591148Y264069D01*
X591356Y263902D01*
X591439Y263569D01*
X591356Y263236D01*
X591106Y263027D01*
X590814Y262902D01*
X589773D01*
G01X590814D02*
X591439Y261694D01*
G01X592789Y262194D02*
X593039Y261902D01*
X593373Y261736D01*
X593748Y261694D01*
X594081Y261736D01*
X594414Y261944D01*
X594623Y262194D01*
X594664Y262444D01*
X594581Y262736D01*
X594289Y262944D01*
X593998Y263027D01*
X593623D01*
G01X593998D02*
X594248Y263152D01*
X594456Y263361D01*
X594539Y263611D01*
X594456Y263861D01*
X594248Y264069D01*
X593873Y264194D01*
X593498Y264152D01*
X593123Y263986D01*
G01X595889Y261694D02*
Y264194D01*
X596723D01*
X597056Y264069D01*
X597306Y263902D01*
X597514Y263652D01*
X597681Y263361D01*
X597723Y262944D01*
X597681Y262527D01*
X597514Y262236D01*
X597306Y261986D01*
X597056Y261819D01*
X596723Y261694D01*
X595889D01*
G01X599114Y263777D02*
X599364Y264027D01*
X599656Y264152D01*
X599989Y264194D01*
X600406Y264111D01*
X600698Y263902D01*
X600781Y263652D01*
X600739Y263402D01*
X600573Y263194D01*
X599739Y262777D01*
X599364Y262486D01*
X599114Y262069D01*
X599031Y261694D01*
X600781D01*
G01X603006D02*
X603298Y261736D01*
X603631Y261861D01*
X603839Y262069D01*
X603923Y262361D01*
X603839Y262652D01*
X603589Y262902D01*
X603214Y263027D01*
X602798D01*
X602548Y263111D01*
X602339Y263319D01*
X602256Y263611D01*
X602381Y263902D01*
X602673Y264111D01*
X603006Y264194D01*
X603339Y264111D01*
X603631Y263902D01*
X603756Y263611D01*
X603673Y263319D01*
X603464Y263111D01*
X603214Y263027D01*
X602798D01*
X602423Y262902D01*
X602173Y262652D01*
X602089Y262361D01*
X602173Y262069D01*
X602381Y261861D01*
X602714Y261736D01*
X603006Y261694D01*
G01X589603Y247524D02*
X589478Y247274D01*
X589395Y246982D01*
Y246649D01*
X589520Y246274D01*
X589728Y245982D01*
X589978Y245774D01*
X590395Y245607D01*
X590770Y245565D01*
X591145Y245649D01*
X591395Y245774D01*
X591645Y246024D01*
X591812Y246315D01*
X591895Y246607D01*
Y246899D01*
X591812Y247190D01*
X591687Y247440D01*
X591520Y247649D01*
G01X591395Y248790D02*
X591687Y249040D01*
X591853Y249374D01*
X591895Y249749D01*
X591853Y250082D01*
X591645Y250415D01*
X591395Y250624D01*
X591145Y250665D01*
X590853Y250582D01*
X590645Y250290D01*
X590562Y249999D01*
Y249624D01*
G01Y249999D02*
X590437Y250249D01*
X590228Y250457D01*
X589978Y250540D01*
X589728Y250457D01*
X589520Y250249D01*
X589395Y249874D01*
X589437Y249499D01*
X589603Y249124D01*
G01X591895Y251890D02*
X589395D01*
Y252724D01*
X589520Y253057D01*
X589687Y253307D01*
X589937Y253515D01*
X590228Y253682D01*
X590645Y253724D01*
X591062Y253682D01*
X591353Y253515D01*
X591603Y253307D01*
X591770Y253057D01*
X591895Y252724D01*
Y251890D01*
G01X589812Y255115D02*
X589562Y255365D01*
X589437Y255657D01*
X589395Y255990D01*
X589478Y256407D01*
X589687Y256699D01*
X589937Y256782D01*
X590187Y256740D01*
X590395Y256574D01*
X590812Y255740D01*
X591103Y255365D01*
X591520Y255115D01*
X591895Y255032D01*
Y256782D01*
G01Y258924D02*
X591353Y259007D01*
X590895Y259132D01*
X590478Y259299D01*
X590020Y259507D01*
X589395Y259840D01*
Y258174D01*
G01X582417Y280148D02*
X582264Y279993D01*
X582149Y279734D01*
X582072Y279373D01*
X582149Y279063D01*
X582302Y278856D01*
X582571Y278701D01*
X583606D01*
Y281801D01*
X582341D01*
X582072Y281594D01*
X581919Y281284D01*
X581842Y280923D01*
X581919Y280561D01*
X582149Y280251D01*
X582417Y280148D01*
X583606D01*
G01X580582Y281801D02*
X579624Y278701D01*
X578666Y281801D01*
G01X579011Y280716D02*
X580237D01*
G01X583682Y266201D02*
X582724Y263101D01*
X581766Y266201D01*
G01X582111Y265116D02*
X583337D01*
G01X580506Y266201D02*
Y263101D01*
X578742Y266201D01*
Y263101D01*
G01X583682Y250601D02*
X582724Y247501D01*
X581766Y250601D01*
G01X582111Y249516D02*
X583337D01*
G01X578857Y250601D02*
X580391D01*
Y247501D01*
X578857D01*
G01X579471Y248999D02*
X580391D01*
G01X582017Y231901D02*
Y234123D01*
X581864Y234588D01*
X581557Y234898D01*
X581174Y235001D01*
X580791Y234898D01*
X580484Y234588D01*
X580331Y234123D01*
Y231901D01*
G01X593731Y253627D02*
X594064Y253419D01*
X594439Y253294D01*
X594773D01*
X595106Y253419D01*
X595356Y253627D01*
X595481Y253919D01*
X595398Y254211D01*
X595189Y254461D01*
X594814Y254627D01*
X594314Y254711D01*
X594023Y254877D01*
X593898Y255169D01*
X593981Y255461D01*
X594189Y255669D01*
X594481Y255794D01*
X594773D01*
X595064Y255711D01*
X595314Y255502D01*
G01X596831Y253294D02*
Y255794D01*
G01X598581D02*
Y253294D01*
G01Y254544D02*
X596831D01*
G01X599889Y253794D02*
X600139Y253502D01*
X600473Y253336D01*
X600848Y253294D01*
X601181Y253336D01*
X601514Y253544D01*
X601723Y253794D01*
X601764Y254044D01*
X601681Y254336D01*
X601389Y254544D01*
X601098Y254627D01*
X600723D01*
G01X601098D02*
X601348Y254752D01*
X601556Y254961D01*
X601639Y255211D01*
X601556Y255461D01*
X601348Y255669D01*
X600973Y255794D01*
X600598Y255752D01*
X600223Y255586D01*
G01X602989Y253294D02*
Y255794D01*
X603823D01*
X604156Y255669D01*
X604406Y255502D01*
X604614Y255252D01*
X604781Y254961D01*
X604823Y254544D01*
X604781Y254127D01*
X604614Y253836D01*
X604406Y253586D01*
X604156Y253419D01*
X603823Y253294D01*
X602989D01*
G01X606214Y255377D02*
X606464Y255627D01*
X606756Y255752D01*
X607089Y255794D01*
X607506Y255711D01*
X607798Y255502D01*
X607881Y255252D01*
X607839Y255002D01*
X607673Y254794D01*
X606839Y254377D01*
X606464Y254086D01*
X606214Y253669D01*
X606131Y253294D01*
X607881D01*
G01X593731Y257127D02*
X594064Y256919D01*
X594439Y256794D01*
X594773D01*
X595106Y256919D01*
X595356Y257127D01*
X595481Y257419D01*
X595398Y257711D01*
X595189Y257961D01*
X594814Y258127D01*
X594314Y258211D01*
X594023Y258377D01*
X593898Y258669D01*
X593981Y258961D01*
X594189Y259169D01*
X594481Y259294D01*
X594773D01*
X595064Y259211D01*
X595314Y259002D01*
G01X596831Y256794D02*
Y259294D01*
G01X598581D02*
Y256794D01*
G01Y258044D02*
X596831D01*
G01X599889Y257294D02*
X600139Y257002D01*
X600473Y256836D01*
X600848Y256794D01*
X601181Y256836D01*
X601514Y257044D01*
X601723Y257294D01*
X601764Y257544D01*
X601681Y257836D01*
X601389Y258044D01*
X601098Y258127D01*
X600723D01*
G01X601098D02*
X601348Y258252D01*
X601556Y258461D01*
X601639Y258711D01*
X601556Y258961D01*
X601348Y259169D01*
X600973Y259294D01*
X600598Y259252D01*
X600223Y259086D01*
G01X602989Y256794D02*
Y259294D01*
X603823D01*
X604156Y259169D01*
X604406Y259002D01*
X604614Y258752D01*
X604781Y258461D01*
X604823Y258044D01*
X604781Y257627D01*
X604614Y257336D01*
X604406Y257086D01*
X604156Y256919D01*
X603823Y256794D01*
X602989D01*
G01X607006D02*
Y259294D01*
X606506Y258794D01*
G01Y256794D02*
X607506D01*
G01X589717Y304959D02*
X589467Y305084D01*
X589175Y305167D01*
X588842D01*
X588467Y305042D01*
X588175Y304834D01*
X587967Y304584D01*
X587800Y304167D01*
X587758Y303792D01*
X587842Y303417D01*
X587967Y303167D01*
X588217Y302917D01*
X588508Y302750D01*
X588800Y302667D01*
X589092D01*
X589383Y302750D01*
X589633Y302875D01*
X589842Y303042D01*
G01X590983Y303167D02*
X591233Y302875D01*
X591567Y302709D01*
X591942Y302667D01*
X592275Y302709D01*
X592608Y302917D01*
X592817Y303167D01*
X592858Y303417D01*
X592775Y303709D01*
X592483Y303917D01*
X592192Y304000D01*
X591817D01*
G01X592192D02*
X592442Y304125D01*
X592650Y304334D01*
X592733Y304584D01*
X592650Y304834D01*
X592442Y305042D01*
X592067Y305167D01*
X591692Y305125D01*
X591317Y304959D01*
G01X594083Y302667D02*
Y305167D01*
X594917D01*
X595250Y305042D01*
X595500Y304875D01*
X595708Y304625D01*
X595875Y304334D01*
X595917Y303917D01*
X595875Y303500D01*
X595708Y303209D01*
X595500Y302959D01*
X595250Y302792D01*
X594917Y302667D01*
X594083D01*
G01X597308Y304750D02*
X597558Y305000D01*
X597850Y305125D01*
X598183Y305167D01*
X598600Y305084D01*
X598892Y304875D01*
X598975Y304625D01*
X598933Y304375D01*
X598767Y304167D01*
X597933Y303750D01*
X597558Y303459D01*
X597308Y303042D01*
X597225Y302667D01*
X598975D01*
G01X600408Y304750D02*
X600658Y305000D01*
X600950Y305125D01*
X601283Y305167D01*
X601700Y305084D01*
X601992Y304875D01*
X602075Y304625D01*
X602033Y304375D01*
X601867Y304167D01*
X601033Y303750D01*
X600658Y303459D01*
X600408Y303042D01*
X600325Y302667D01*
X602075D01*
G01X590424Y283265D02*
Y285765D01*
X591465D01*
X591799Y285640D01*
X592007Y285473D01*
X592090Y285140D01*
X592007Y284807D01*
X591757Y284598D01*
X591465Y284473D01*
X590424D01*
G01X591465D02*
X592090Y283265D01*
G01X593440Y283765D02*
X593690Y283473D01*
X594024Y283307D01*
X594399Y283265D01*
X594732Y283307D01*
X595065Y283515D01*
X595274Y283765D01*
X595315Y284015D01*
X595232Y284307D01*
X594940Y284515D01*
X594649Y284598D01*
X594274D01*
G01X594649D02*
X594899Y284723D01*
X595107Y284932D01*
X595190Y285182D01*
X595107Y285432D01*
X594899Y285640D01*
X594524Y285765D01*
X594149Y285723D01*
X593774Y285557D01*
G01X596540Y283265D02*
Y285765D01*
X597374D01*
X597707Y285640D01*
X597957Y285473D01*
X598165Y285223D01*
X598332Y284932D01*
X598374Y284515D01*
X598332Y284098D01*
X598165Y283807D01*
X597957Y283557D01*
X597707Y283390D01*
X597374Y283265D01*
X596540D01*
G01X599765Y285348D02*
X600015Y285598D01*
X600307Y285723D01*
X600640Y285765D01*
X601057Y285682D01*
X601349Y285473D01*
X601432Y285223D01*
X601390Y284973D01*
X601224Y284765D01*
X600390Y284348D01*
X600015Y284057D01*
X599765Y283640D01*
X599682Y283265D01*
X601432D01*
G01X603657D02*
Y285765D01*
X603157Y285265D01*
G01Y283265D02*
X604157D01*
G01X588566Y280612D02*
X586066D01*
Y281653D01*
X586191Y281987D01*
X586358Y282195D01*
X586691Y282278D01*
X587024Y282195D01*
X587233Y281945D01*
X587358Y281653D01*
Y280612D01*
G01Y281653D02*
X588566Y282278D01*
G01X588066Y283628D02*
X588358Y283878D01*
X588524Y284212D01*
X588566Y284587D01*
X588524Y284920D01*
X588316Y285253D01*
X588066Y285462D01*
X587816Y285503D01*
X587524Y285420D01*
X587316Y285128D01*
X587233Y284837D01*
Y284462D01*
G01Y284837D02*
X587108Y285087D01*
X586899Y285295D01*
X586649Y285378D01*
X586399Y285295D01*
X586191Y285087D01*
X586066Y284712D01*
X586108Y284337D01*
X586274Y283962D01*
G01X588566Y286728D02*
X586066D01*
Y287562D01*
X586191Y287895D01*
X586358Y288145D01*
X586608Y288353D01*
X586899Y288520D01*
X587316Y288562D01*
X587733Y288520D01*
X588024Y288353D01*
X588274Y288145D01*
X588441Y287895D01*
X588566Y287562D01*
Y286728D01*
G01Y290745D02*
X586066D01*
X586566Y290245D01*
G01X588566D02*
Y291245D01*
G01Y293845D02*
X588524Y294137D01*
X588399Y294470D01*
X588191Y294678D01*
X587899Y294762D01*
X587608Y294678D01*
X587358Y294428D01*
X587233Y294053D01*
Y293637D01*
X587149Y293387D01*
X586941Y293178D01*
X586649Y293095D01*
X586358Y293220D01*
X586149Y293512D01*
X586066Y293845D01*
X586149Y294178D01*
X586358Y294470D01*
X586649Y294595D01*
X586941Y294512D01*
X587149Y294303D01*
X587233Y294053D01*
Y293637D01*
X587358Y293262D01*
X587608Y293012D01*
X587899Y292928D01*
X588191Y293012D01*
X588399Y293220D01*
X588524Y293553D01*
X588566Y293845D01*
G01X597069Y311062D02*
X594569D01*
Y312103D01*
X594694Y312437D01*
X594861Y312645D01*
X595194Y312728D01*
X595527Y312645D01*
X595736Y312395D01*
X595861Y312103D01*
Y311062D01*
G01Y312103D02*
X597069Y312728D01*
G01Y315495D02*
X594569D01*
X596361Y313953D01*
Y316037D01*
G01X597069Y317178D02*
X594569D01*
Y318012D01*
X594694Y318345D01*
X594861Y318595D01*
X595111Y318803D01*
X595402Y318970D01*
X595819Y319012D01*
X596236Y318970D01*
X596527Y318803D01*
X596777Y318595D01*
X596944Y318345D01*
X597069Y318012D01*
Y317178D01*
G01Y321695D02*
X594569D01*
X596361Y320153D01*
Y322237D01*
G01X594569Y324295D02*
X594652Y323962D01*
X594861Y323712D01*
X595111Y323545D01*
X595444Y323420D01*
X595819Y323378D01*
X596194Y323420D01*
X596527Y323545D01*
X596777Y323712D01*
X596986Y323962D01*
X597069Y324295D01*
X596986Y324628D01*
X596777Y324878D01*
X596527Y325045D01*
X596194Y325170D01*
X595819Y325212D01*
X595444Y325170D01*
X595111Y325045D01*
X594861Y324878D01*
X594652Y324628D01*
X594569Y324295D01*
G01X600658Y309079D02*
X598158D01*
Y310120D01*
X598283Y310454D01*
X598450Y310662D01*
X598783Y310745D01*
X599116Y310662D01*
X599325Y310412D01*
X599450Y310120D01*
Y309079D01*
G01Y310120D02*
X600658Y310745D01*
G01Y313512D02*
X598158D01*
X599950Y311970D01*
Y314054D01*
G01X600658Y315195D02*
X598158D01*
Y316029D01*
X598283Y316362D01*
X598450Y316612D01*
X598700Y316820D01*
X598991Y316987D01*
X599408Y317029D01*
X599825Y316987D01*
X600116Y316820D01*
X600366Y316612D01*
X600533Y316362D01*
X600658Y316029D01*
Y315195D01*
G01Y319712D02*
X598158D01*
X599950Y318170D01*
Y320254D01*
G01X600658Y322312D02*
X598158D01*
X598658Y321812D01*
G01X600658D02*
Y322812D01*
G01X585250Y327855D02*
Y330355D01*
X586291D01*
X586625Y330230D01*
X586833Y330063D01*
X586916Y329730D01*
X586833Y329397D01*
X586583Y329188D01*
X586291Y329063D01*
X585250D01*
G01X586291D02*
X586916Y327855D01*
G01X588266Y328355D02*
X588516Y328063D01*
X588850Y327897D01*
X589225Y327855D01*
X589558Y327897D01*
X589891Y328105D01*
X590100Y328355D01*
X590141Y328605D01*
X590058Y328897D01*
X589766Y329105D01*
X589475Y329188D01*
X589100D01*
G01X589475D02*
X589725Y329313D01*
X589933Y329522D01*
X590016Y329772D01*
X589933Y330022D01*
X589725Y330230D01*
X589350Y330355D01*
X588975Y330313D01*
X588600Y330147D01*
G01X591366Y327855D02*
Y330355D01*
X592200D01*
X592533Y330230D01*
X592783Y330063D01*
X592991Y329813D01*
X593158Y329522D01*
X593200Y329105D01*
X593158Y328688D01*
X592991Y328397D01*
X592783Y328147D01*
X592533Y327980D01*
X592200Y327855D01*
X591366D01*
G01X595383D02*
Y330355D01*
X594883Y329855D01*
G01Y327855D02*
X595883D01*
G01X598983D02*
Y330355D01*
X597441Y328563D01*
X599525D01*
G01X591277Y312812D02*
X591152Y312562D01*
X591069Y312270D01*
Y311937D01*
X591194Y311562D01*
X591402Y311270D01*
X591652Y311062D01*
X592069Y310895D01*
X592444Y310853D01*
X592819Y310937D01*
X593069Y311062D01*
X593319Y311312D01*
X593486Y311603D01*
X593569Y311895D01*
Y312187D01*
X593486Y312478D01*
X593361Y312728D01*
X593194Y312937D01*
G01X593569Y315495D02*
X591069D01*
X592861Y313953D01*
Y316037D01*
G01X593569Y317178D02*
X591069D01*
Y318012D01*
X591194Y318345D01*
X591361Y318595D01*
X591611Y318803D01*
X591902Y318970D01*
X592319Y319012D01*
X592736Y318970D01*
X593027Y318803D01*
X593277Y318595D01*
X593444Y318345D01*
X593569Y318012D01*
Y317178D01*
G01X591486Y320403D02*
X591236Y320653D01*
X591111Y320945D01*
X591069Y321278D01*
X591152Y321695D01*
X591361Y321987D01*
X591611Y322070D01*
X591861Y322028D01*
X592069Y321862D01*
X592486Y321028D01*
X592777Y320653D01*
X593194Y320403D01*
X593569Y320320D01*
Y322070D01*
G01Y324795D02*
X591069D01*
X592861Y323253D01*
Y325337D01*
G01X587777Y312812D02*
X587652Y312562D01*
X587569Y312270D01*
Y311937D01*
X587694Y311562D01*
X587902Y311270D01*
X588152Y311062D01*
X588569Y310895D01*
X588944Y310853D01*
X589319Y310937D01*
X589569Y311062D01*
X589819Y311312D01*
X589986Y311603D01*
X590069Y311895D01*
Y312187D01*
X589986Y312478D01*
X589861Y312728D01*
X589694Y312937D01*
G01X590069Y315495D02*
X587569D01*
X589361Y313953D01*
Y316037D01*
G01X590069Y317178D02*
X587569D01*
Y318012D01*
X587694Y318345D01*
X587861Y318595D01*
X588111Y318803D01*
X588402Y318970D01*
X588819Y319012D01*
X589236Y318970D01*
X589527Y318803D01*
X589777Y318595D01*
X589944Y318345D01*
X590069Y318012D01*
Y317178D01*
G01X587986Y320403D02*
X587736Y320653D01*
X587611Y320945D01*
X587569Y321278D01*
X587652Y321695D01*
X587861Y321987D01*
X588111Y322070D01*
X588361Y322028D01*
X588569Y321862D01*
X588986Y321028D01*
X589277Y320653D01*
X589694Y320403D01*
X590069Y320320D01*
Y322070D01*
G01X589569Y323378D02*
X589861Y323628D01*
X590027Y323962D01*
X590069Y324337D01*
X590027Y324670D01*
X589819Y325003D01*
X589569Y325212D01*
X589319Y325253D01*
X589027Y325170D01*
X588819Y324878D01*
X588736Y324587D01*
Y324212D01*
G01Y324587D02*
X588611Y324837D01*
X588402Y325045D01*
X588152Y325128D01*
X587902Y325045D01*
X587694Y324837D01*
X587569Y324462D01*
X587611Y324087D01*
X587777Y323712D01*
G01X581881Y341359D02*
X582111Y341204D01*
X582379Y341101D01*
X582686D01*
X583031Y341256D01*
X583299Y341514D01*
X583491Y341824D01*
X583644Y342341D01*
X583682Y342806D01*
X583606Y343271D01*
X583491Y343581D01*
X583261Y343891D01*
X582992Y344098D01*
X582724Y344201D01*
X582456D01*
X582187Y344098D01*
X581957Y343943D01*
X581766Y343736D01*
G01X580506Y344201D02*
Y341101D01*
X578742Y344201D01*
Y341101D01*
G01X581881Y325759D02*
X582111Y325604D01*
X582379Y325501D01*
X582686D01*
X583031Y325656D01*
X583299Y325914D01*
X583491Y326224D01*
X583644Y326741D01*
X583682Y327206D01*
X583606Y327671D01*
X583491Y327981D01*
X583261Y328291D01*
X582992Y328498D01*
X582724Y328601D01*
X582456D01*
X582187Y328498D01*
X581957Y328343D01*
X581766Y328136D01*
G01X578857Y328601D02*
X580391D01*
Y325501D01*
X578857D01*
G01X579471Y326999D02*
X580391D01*
G01X581717Y311348D02*
X581564Y311193D01*
X581449Y310934D01*
X581372Y310573D01*
X581449Y310263D01*
X581602Y310056D01*
X581871Y309901D01*
X582906D01*
Y313001D01*
X581641D01*
X581372Y312794D01*
X581219Y312484D01*
X581142Y312123D01*
X581219Y311761D01*
X581449Y311451D01*
X581717Y311348D01*
X582906D01*
G01X579767Y309901D02*
Y312123D01*
X579614Y312588D01*
X579307Y312898D01*
X578924Y313001D01*
X578541Y312898D01*
X578234Y312588D01*
X578081Y312123D01*
Y309901D01*
G01X582417Y295748D02*
X582264Y295593D01*
X582149Y295334D01*
X582072Y294973D01*
X582149Y294663D01*
X582302Y294456D01*
X582571Y294301D01*
X583606D01*
Y297401D01*
X582341D01*
X582072Y297194D01*
X581919Y296884D01*
X581842Y296523D01*
X581919Y296161D01*
X582149Y295851D01*
X582417Y295748D01*
X583606D01*
G01X580391Y296781D02*
X580199Y297091D01*
X579969Y297298D01*
X579701Y297401D01*
X579394Y297298D01*
X579164Y297091D01*
X578934Y296781D01*
X578857Y296368D01*
Y294301D01*
G01X590328Y379632D02*
X588933D01*
X587228Y378865D01*
G01Y380399D02*
X588933Y379632D01*
G01X590328Y383499D02*
Y381965D01*
X587228D01*
Y383499D01*
G01X588726Y382885D02*
Y381965D01*
G01X587228Y385065D02*
X590328D01*
Y386599D01*
G01X587228Y388165D02*
X590328D01*
Y389699D01*
G01Y392032D02*
X590276Y391725D01*
X590070Y391457D01*
X589760Y391227D01*
X589398Y391074D01*
X588985Y390997D01*
X588571D01*
X588158Y391074D01*
X587796Y391227D01*
X587486Y391457D01*
X587280Y391725D01*
X587228Y392032D01*
X587280Y392339D01*
X587486Y392607D01*
X587796Y392837D01*
X588158Y392990D01*
X588571Y393067D01*
X588985D01*
X589398Y392990D01*
X589760Y392837D01*
X590070Y392607D01*
X590276Y392339D01*
X590328Y392032D01*
G01X587228Y393982D02*
X590328Y394519D01*
X587228Y395132D01*
X590328Y395745D01*
X587228Y396282D01*
G01Y400565D02*
X590328D01*
Y402099D01*
G01Y403474D02*
X587228Y404432D01*
X590328Y405390D01*
G01X589243Y405045D02*
Y403819D01*
G01X587228Y407532D02*
X590328D01*
G01X587228Y406650D02*
Y408414D01*
G01X587486Y411475D02*
X587331Y411245D01*
X587228Y410977D01*
Y410670D01*
X587383Y410325D01*
X587641Y410057D01*
X587951Y409865D01*
X588468Y409712D01*
X588933Y409674D01*
X589398Y409750D01*
X589708Y409865D01*
X590018Y410095D01*
X590225Y410364D01*
X590328Y410632D01*
Y410900D01*
X590225Y411169D01*
X590070Y411399D01*
X589863Y411590D01*
G01X590328Y412927D02*
X587228D01*
G01Y414537D02*
X590328D01*
G01X588778D02*
Y412927D01*
G01X586300Y404100D02*
Y415600D01*
X591500D01*
Y377800D01*
X586300D01*
Y404100D01*
G01X583596Y396859D02*
Y393759D01*
X582830D01*
X582523Y393914D01*
X582293Y394121D01*
X582101Y394431D01*
X581948Y394792D01*
X581910Y395309D01*
X581948Y395826D01*
X582101Y396187D01*
X582293Y396497D01*
X582523Y396704D01*
X582830Y396859D01*
X583596D01*
G01X579653D02*
Y395464D01*
X580420Y393759D01*
G01X578886D02*
X579653Y395464D01*
G01X583567Y391001D02*
Y387901D01*
X582801D01*
X582494Y388056D01*
X582264Y388263D01*
X582072Y388573D01*
X581919Y388934D01*
X581881Y389451D01*
X581919Y389968D01*
X582072Y390329D01*
X582264Y390639D01*
X582494Y390846D01*
X582801Y391001D01*
X583567D01*
G01X580467Y387901D02*
Y390123D01*
X580314Y390588D01*
X580007Y390898D01*
X579624Y391001D01*
X579241Y390898D01*
X578934Y390588D01*
X578781Y390123D01*
Y387901D01*
G01X583567Y375401D02*
Y372301D01*
X582801D01*
X582494Y372456D01*
X582264Y372663D01*
X582072Y372973D01*
X581919Y373334D01*
X581881Y373851D01*
X581919Y374368D01*
X582072Y374729D01*
X582264Y375039D01*
X582494Y375246D01*
X582801Y375401D01*
X583567D01*
G01X580391Y374781D02*
X580199Y375091D01*
X579969Y375298D01*
X579701Y375401D01*
X579394Y375298D01*
X579164Y375091D01*
X578934Y374781D01*
X578857Y374368D01*
Y372301D01*
G01X583567Y359801D02*
Y356701D01*
X582801D01*
X582494Y356856D01*
X582264Y357063D01*
X582072Y357373D01*
X581919Y357734D01*
X581881Y358251D01*
X581919Y358768D01*
X582072Y359129D01*
X582264Y359439D01*
X582494Y359646D01*
X582801Y359801D01*
X583567D01*
G01X580582D02*
X579624Y356701D01*
X578666Y359801D01*
G01X579011Y358716D02*
X580237D01*
G01X569000Y464000D02*
X591575D01*
G01X569000D02*
Y466698D01*
G01X604364Y466700D02*
Y463138D01*
X591568D01*
Y466700D01*
G01X580509Y407122D02*
X582043D01*
Y404022D01*
X580509D01*
G01X581123Y405520D02*
X582043D01*
G01X577409Y407122D02*
X578943D01*
Y404022D01*
X577409D01*
G01X578023Y405520D02*
X578943D01*
G01X580573Y485798D02*
X580323Y485923D01*
X580031Y486006D01*
X579698D01*
X579323Y485881D01*
X579031Y485673D01*
X578823Y485423D01*
X578656Y485006D01*
X578614Y484631D01*
X578698Y484256D01*
X578823Y484006D01*
X579073Y483756D01*
X579364Y483589D01*
X579656Y483506D01*
X579948D01*
X580239Y483589D01*
X580489Y483714D01*
X580698Y483881D01*
G01X581839Y484006D02*
X582089Y483714D01*
X582423Y483548D01*
X582798Y483506D01*
X583131Y483548D01*
X583464Y483756D01*
X583673Y484006D01*
X583714Y484256D01*
X583631Y484548D01*
X583339Y484756D01*
X583048Y484839D01*
X582673D01*
G01X583048D02*
X583298Y484964D01*
X583506Y485173D01*
X583589Y485423D01*
X583506Y485673D01*
X583298Y485881D01*
X582923Y486006D01*
X582548Y485964D01*
X582173Y485798D01*
G01X586189Y484839D02*
X586356Y484964D01*
X586481Y485173D01*
X586564Y485464D01*
X586481Y485714D01*
X586314Y485881D01*
X586023Y486006D01*
X584898D01*
Y483506D01*
X586273D01*
X586564Y483673D01*
X586731Y483923D01*
X586814Y484214D01*
X586731Y484506D01*
X586481Y484756D01*
X586189Y484839D01*
X584898D01*
G01X588164Y484548D02*
X588456Y484839D01*
X588706Y485006D01*
X589039Y485089D01*
X589331Y485006D01*
X589539Y484839D01*
X589706Y484589D01*
X589748Y484298D01*
X589706Y484048D01*
X589539Y483798D01*
X589289Y483589D01*
X588998Y483506D01*
X588664Y483589D01*
X588373Y483839D01*
X588206Y484214D01*
X588164Y484631D01*
X588248Y485173D01*
X588373Y485464D01*
X588581Y485756D01*
X588873Y485964D01*
X589164Y486006D01*
X589456Y485923D01*
X589664Y485714D01*
G01X569000Y482000D02*
X591572D01*
G01X569000D02*
Y479305D01*
G01X604364Y479300D02*
Y483091D01*
X591568D01*
Y479300D01*
G01X565293Y496420D02*
X565168Y496170D01*
X565085Y495878D01*
Y495545D01*
X565210Y495170D01*
X565418Y494878D01*
X565668Y494670D01*
X566085Y494503D01*
X566460Y494461D01*
X566835Y494545D01*
X567085Y494670D01*
X567335Y494920D01*
X567502Y495211D01*
X567585Y495503D01*
Y495795D01*
X567502Y496086D01*
X567377Y496336D01*
X567210Y496545D01*
G01X567085Y497686D02*
X567377Y497936D01*
X567543Y498270D01*
X567585Y498645D01*
X567543Y498978D01*
X567335Y499311D01*
X567085Y499520D01*
X566835Y499561D01*
X566543Y499478D01*
X566335Y499186D01*
X566252Y498895D01*
Y498520D01*
G01Y498895D02*
X566127Y499145D01*
X565918Y499353D01*
X565668Y499436D01*
X565418Y499353D01*
X565210Y499145D01*
X565085Y498770D01*
X565127Y498395D01*
X565293Y498020D01*
G01X566252Y502036D02*
X566127Y502203D01*
X565918Y502328D01*
X565627Y502411D01*
X565377Y502328D01*
X565210Y502161D01*
X565085Y501870D01*
Y500745D01*
X567585D01*
Y502120D01*
X567418Y502411D01*
X567168Y502578D01*
X566877Y502661D01*
X566585Y502578D01*
X566335Y502328D01*
X566252Y502036D01*
Y500745D01*
G01X567085Y503886D02*
X567377Y504136D01*
X567543Y504470D01*
X567585Y504845D01*
X567543Y505178D01*
X567335Y505511D01*
X567085Y505720D01*
X566835Y505761D01*
X566543Y505678D01*
X566335Y505386D01*
X566252Y505095D01*
Y504720D01*
G01Y505095D02*
X566127Y505345D01*
X565918Y505553D01*
X565668Y505636D01*
X565418Y505553D01*
X565210Y505345D01*
X565085Y504970D01*
X565127Y504595D01*
X565293Y504220D01*
G01X610900Y492300D02*
Y491100D01*
X598900D01*
Y492300D01*
G01X610900Y505900D02*
Y507100D01*
X598900D01*
Y505900D01*
G01X605850Y507100D02*
Y508150D01*
X575950D01*
Y505900D01*
G01Y492300D02*
Y490050D01*
X605850D01*
Y491100D01*
G01X586608Y586067D02*
X586483Y585817D01*
X586400Y585525D01*
Y585192D01*
X586525Y584817D01*
X586733Y584525D01*
X586983Y584317D01*
X587400Y584150D01*
X587775Y584108D01*
X588150Y584192D01*
X588400Y584317D01*
X588650Y584567D01*
X588817Y584858D01*
X588900Y585150D01*
Y585442D01*
X588817Y585733D01*
X588692Y585983D01*
X588525Y586192D01*
G01X588400Y587333D02*
X588692Y587583D01*
X588858Y587917D01*
X588900Y588292D01*
X588858Y588625D01*
X588650Y588958D01*
X588400Y589167D01*
X588150Y589208D01*
X587858Y589125D01*
X587650Y588833D01*
X587567Y588542D01*
Y588167D01*
G01Y588542D02*
X587442Y588792D01*
X587233Y589000D01*
X586983Y589083D01*
X586733Y589000D01*
X586525Y588792D01*
X586400Y588417D01*
X586442Y588042D01*
X586608Y587667D01*
G01X588900Y590308D02*
X586400Y591350D01*
X588900Y592392D01*
G01X588025Y592017D02*
Y590683D01*
G01X588900Y594950D02*
X586400D01*
X588192Y593408D01*
Y595492D01*
G01X581708Y548067D02*
X581583Y547817D01*
X581500Y547525D01*
Y547192D01*
X581625Y546817D01*
X581833Y546525D01*
X582083Y546317D01*
X582500Y546150D01*
X582875Y546108D01*
X583250Y546192D01*
X583500Y546317D01*
X583750Y546567D01*
X583917Y546858D01*
X584000Y547150D01*
Y547442D01*
X583917Y547733D01*
X583792Y547983D01*
X583625Y548192D01*
G01X583500Y549333D02*
X583792Y549583D01*
X583958Y549917D01*
X584000Y550292D01*
X583958Y550625D01*
X583750Y550958D01*
X583500Y551167D01*
X583250Y551208D01*
X582958Y551125D01*
X582750Y550833D01*
X582667Y550542D01*
Y550167D01*
G01Y550542D02*
X582542Y550792D01*
X582333Y551000D01*
X582083Y551083D01*
X581833Y551000D01*
X581625Y550792D01*
X581500Y550417D01*
X581542Y550042D01*
X581708Y549667D01*
G01X584000Y552308D02*
X581500Y553350D01*
X584000Y554392D01*
G01X583125Y554017D02*
Y552683D01*
G01X584000Y556450D02*
X583958Y556742D01*
X583833Y557075D01*
X583625Y557283D01*
X583333Y557367D01*
X583042Y557283D01*
X582792Y557033D01*
X582667Y556658D01*
Y556242D01*
X582583Y555992D01*
X582375Y555783D01*
X582083Y555700D01*
X581792Y555825D01*
X581583Y556117D01*
X581500Y556450D01*
X581583Y556783D01*
X581792Y557075D01*
X582083Y557200D01*
X582375Y557117D01*
X582583Y556908D01*
X582667Y556658D01*
Y556242D01*
X582792Y555867D01*
X583042Y555617D01*
X583333Y555533D01*
X583625Y555617D01*
X583833Y555825D01*
X583958Y556158D01*
X584000Y556450D01*
G01X576808Y548267D02*
X576683Y548017D01*
X576600Y547725D01*
Y547392D01*
X576725Y547017D01*
X576933Y546725D01*
X577183Y546517D01*
X577600Y546350D01*
X577975Y546308D01*
X578350Y546392D01*
X578600Y546517D01*
X578850Y546767D01*
X579017Y547058D01*
X579100Y547350D01*
Y547642D01*
X579017Y547933D01*
X578892Y548183D01*
X578725Y548392D01*
G01X578600Y549533D02*
X578892Y549783D01*
X579058Y550117D01*
X579100Y550492D01*
X579058Y550825D01*
X578850Y551158D01*
X578600Y551367D01*
X578350Y551408D01*
X578058Y551325D01*
X577850Y551033D01*
X577767Y550742D01*
Y550367D01*
G01Y550742D02*
X577642Y550992D01*
X577433Y551200D01*
X577183Y551283D01*
X576933Y551200D01*
X576725Y550992D01*
X576600Y550617D01*
X576642Y550242D01*
X576808Y549867D01*
G01X579100Y552508D02*
X576600Y553550D01*
X579100Y554592D01*
G01X578225Y554217D02*
Y552883D01*
G01X579100Y556567D02*
X578558Y556650D01*
X578100Y556775D01*
X577683Y556942D01*
X577225Y557150D01*
X576600Y557483D01*
Y555817D01*
G01X581647Y586095D02*
X581522Y585845D01*
X581439Y585553D01*
Y585220D01*
X581564Y584845D01*
X581772Y584553D01*
X582022Y584345D01*
X582439Y584178D01*
X582814Y584136D01*
X583189Y584220D01*
X583439Y584345D01*
X583689Y584595D01*
X583856Y584886D01*
X583939Y585178D01*
Y585470D01*
X583856Y585761D01*
X583731Y586011D01*
X583564Y586220D01*
G01X583439Y587361D02*
X583731Y587611D01*
X583897Y587945D01*
X583939Y588320D01*
X583897Y588653D01*
X583689Y588986D01*
X583439Y589195D01*
X583189Y589236D01*
X582897Y589153D01*
X582689Y588861D01*
X582606Y588570D01*
Y588195D01*
G01Y588570D02*
X582481Y588820D01*
X582272Y589028D01*
X582022Y589111D01*
X581772Y589028D01*
X581564Y588820D01*
X581439Y588445D01*
X581481Y588070D01*
X581647Y587695D01*
G01X583939Y590336D02*
X581439Y591378D01*
X583939Y592420D01*
G01X583064Y592045D02*
Y590711D01*
G01X583439Y593561D02*
X583731Y593811D01*
X583897Y594145D01*
X583939Y594520D01*
X583897Y594853D01*
X583689Y595186D01*
X583439Y595395D01*
X583189Y595436D01*
X582897Y595353D01*
X582689Y595061D01*
X582606Y594770D01*
Y594395D01*
G01Y594770D02*
X582481Y595020D01*
X582272Y595228D01*
X582022Y595311D01*
X581772Y595228D01*
X581564Y595020D01*
X581439Y594645D01*
X581481Y594270D01*
X581647Y593895D01*
G01X600572Y639880D02*
X567872D01*
Y658580D01*
X600572D01*
Y639880D01*
G01X627700Y-54160D02*
Y-57160D01*
X629700D01*
G01X632300D02*
Y-54160D01*
X631700Y-54760D01*
G01Y-57160D02*
X632900D01*
G01X638500Y-54160D02*
Y-57160D01*
X640500D01*
G01X642000Y-56560D02*
X642300Y-56910D01*
X642700Y-57110D01*
X643150Y-57160D01*
X643550Y-57110D01*
X643950Y-56860D01*
X644200Y-56560D01*
X644250Y-56260D01*
X644150Y-55910D01*
X643800Y-55660D01*
X643450Y-55560D01*
X643000D01*
G01X643450D02*
X643750Y-55410D01*
X644000Y-55160D01*
X644100Y-54860D01*
X644000Y-54560D01*
X643750Y-54310D01*
X643300Y-54160D01*
X642850Y-54210D01*
X642400Y-54410D01*
G01X649300Y-54160D02*
Y-57160D01*
X651300D01*
G01X652800Y-56710D02*
X653100Y-56960D01*
X653450Y-57110D01*
X653900Y-57160D01*
X654350Y-57060D01*
X654700Y-56860D01*
X654950Y-56510D01*
X655000Y-56110D01*
X654900Y-55710D01*
X654650Y-55460D01*
X654300Y-55260D01*
X653950Y-55210D01*
X653600Y-55260D01*
X653150Y-55460D01*
X653300Y-54160D01*
X654650D01*
G01X660100D02*
Y-57160D01*
X662100D01*
G01X664700D02*
Y-54160D01*
X664100Y-54760D01*
G01Y-57160D02*
X665300D01*
G01X668300Y-54160D02*
X667900Y-54260D01*
X667600Y-54510D01*
X667400Y-54810D01*
X667250Y-55210D01*
X667200Y-55660D01*
X667250Y-56110D01*
X667400Y-56510D01*
X667600Y-56810D01*
X667900Y-57060D01*
X668300Y-57160D01*
X668700Y-57060D01*
X669000Y-56810D01*
X669200Y-56510D01*
X669350Y-56110D01*
X669400Y-55660D01*
X669350Y-55210D01*
X669200Y-54810D01*
X669000Y-54510D01*
X668700Y-54260D01*
X668300Y-54160D01*
G01X674500D02*
Y-57160D01*
X676500D01*
G01X679100D02*
Y-54160D01*
X678500Y-54760D01*
G01Y-57160D02*
X679700D01*
G01X681750Y-54660D02*
X682050Y-54360D01*
X682400Y-54210D01*
X682800Y-54160D01*
X683300Y-54260D01*
X683650Y-54510D01*
X683750Y-54810D01*
X683700Y-55110D01*
X683500Y-55360D01*
X682500Y-55860D01*
X682050Y-56210D01*
X681750Y-56710D01*
X681650Y-57160D01*
X683750D01*
G01X688900Y-54160D02*
Y-57160D01*
X690900D01*
G01X693500D02*
Y-54160D01*
X692900Y-54760D01*
G01Y-57160D02*
X694100D01*
G01X697700D02*
Y-54160D01*
X695850Y-56310D01*
X698350D01*
G01X699200Y-58160D02*
X702200D01*
G01X704200Y-57160D02*
X704300Y-56510D01*
X704450Y-55960D01*
X704650Y-55460D01*
X704900Y-54910D01*
X705300Y-54160D01*
X703300D01*
G01X706800Y-56560D02*
X707100Y-56910D01*
X707500Y-57110D01*
X707950Y-57160D01*
X708350Y-57110D01*
X708750Y-56860D01*
X709000Y-56560D01*
X709050Y-56260D01*
X708950Y-55910D01*
X708600Y-55660D01*
X708250Y-55560D01*
X707800D01*
G01X708250D02*
X708550Y-55410D01*
X708800Y-55160D01*
X708900Y-54860D01*
X708800Y-54560D01*
X708550Y-54310D01*
X708100Y-54160D01*
X707650Y-54210D01*
X707200Y-54410D01*
G01X711500Y-57160D02*
X711100Y-57110D01*
X710750Y-56910D01*
X710450Y-56610D01*
X710250Y-56260D01*
X710150Y-55860D01*
Y-55460D01*
X710250Y-55060D01*
X710450Y-54710D01*
X710750Y-54410D01*
X711100Y-54210D01*
X711500Y-54160D01*
X711900Y-54210D01*
X712250Y-54410D01*
X712550Y-54710D01*
X712750Y-55060D01*
X712850Y-55460D01*
Y-55860D01*
X712750Y-56260D01*
X712550Y-56610D01*
X712250Y-56910D01*
X711900Y-57110D01*
X711500Y-57160D01*
G01X714250D02*
Y-54160D01*
G01Y-55610D02*
X714500Y-55360D01*
X714750Y-55210D01*
X715150Y-55160D01*
X715450Y-55210D01*
X715800Y-55410D01*
X715950Y-55710D01*
Y-57160D01*
G01X717200D02*
Y-55160D01*
G01Y-55710D02*
X717350Y-55460D01*
X717600Y-55260D01*
X717950Y-55160D01*
X718300Y-55260D01*
X718550Y-55460D01*
X718700Y-55710D01*
Y-57160D01*
G01Y-55710D02*
X718850Y-55460D01*
X719100Y-55260D01*
X719450Y-55160D01*
X719800Y-55260D01*
X720050Y-55460D01*
X720200Y-55760D01*
Y-57160D01*
G01X720800Y-58160D02*
X723800D01*
G01X724800Y-57160D02*
Y-54160D01*
X725800D01*
X726200Y-54310D01*
X726500Y-54510D01*
X726750Y-54810D01*
X726950Y-55160D01*
X727000Y-55660D01*
X726950Y-56160D01*
X726750Y-56510D01*
X726500Y-56810D01*
X726200Y-57010D01*
X725800Y-57160D01*
X724800D01*
G01X656600Y30100D02*
X649601D01*
X649600Y30099D01*
Y21501D01*
X649601Y21500D01*
X659400D01*
G01X678300Y24900D02*
X661001D01*
X661000Y24899D01*
Y23000D01*
G01X660500Y30100D02*
X662299D01*
X662300Y30101D01*
Y31900D01*
G01X661042Y9217D02*
X660917Y8967D01*
X660834Y8675D01*
Y8342D01*
X660959Y7967D01*
X661167Y7675D01*
X661417Y7467D01*
X661834Y7300D01*
X662209Y7258D01*
X662584Y7342D01*
X662834Y7467D01*
X663084Y7717D01*
X663251Y8008D01*
X663334Y8300D01*
Y8592D01*
X663251Y8883D01*
X663126Y9133D01*
X662959Y9342D01*
G01X663334Y11900D02*
X660834D01*
X662626Y10358D01*
Y12442D01*
G01X662084Y14750D02*
Y15583D01*
X662834D01*
X663084Y15333D01*
X663251Y15042D01*
X663334Y14625D01*
X663251Y14208D01*
X663084Y13917D01*
X662834Y13667D01*
X662542Y13500D01*
X662209Y13417D01*
X661917D01*
X661667Y13500D01*
X661376Y13667D01*
X661126Y13917D01*
X660959Y14167D01*
X660834Y14500D01*
Y14792D01*
X660917Y15125D01*
X661084Y15375D01*
G01X661251Y16808D02*
X661001Y17058D01*
X660876Y17350D01*
X660834Y17683D01*
X660917Y18100D01*
X661126Y18392D01*
X661376Y18475D01*
X661626Y18433D01*
X661834Y18267D01*
X662251Y17433D01*
X662542Y17058D01*
X662959Y16808D01*
X663334Y16725D01*
Y18475D01*
G01X660834Y20700D02*
X660917Y20367D01*
X661126Y20117D01*
X661376Y19950D01*
X661709Y19825D01*
X662084Y19783D01*
X662459Y19825D01*
X662792Y19950D01*
X663042Y20117D01*
X663251Y20367D01*
X663334Y20700D01*
X663251Y21033D01*
X663042Y21283D01*
X662792Y21450D01*
X662459Y21575D01*
X662084Y21617D01*
X661709Y21575D01*
X661376Y21450D01*
X661126Y21283D01*
X660917Y21033D01*
X660834Y20700D01*
G01X652334Y32017D02*
X649834D01*
Y33058D01*
X649959Y33392D01*
X650126Y33600D01*
X650459Y33683D01*
X650792Y33600D01*
X651001Y33350D01*
X651126Y33058D01*
Y32017D01*
G01Y33058D02*
X652334Y33683D01*
G01Y36450D02*
X649834D01*
X651626Y34908D01*
Y36992D01*
G01X651084Y39300D02*
Y40133D01*
X651834D01*
X652084Y39883D01*
X652251Y39592D01*
X652334Y39175D01*
X652251Y38758D01*
X652084Y38467D01*
X651834Y38217D01*
X651542Y38050D01*
X651209Y37967D01*
X650917D01*
X650667Y38050D01*
X650376Y38217D01*
X650126Y38467D01*
X649959Y38717D01*
X649834Y39050D01*
Y39342D01*
X649917Y39675D01*
X650084Y39925D01*
G01X652334Y42150D02*
X652292Y42442D01*
X652167Y42775D01*
X651959Y42983D01*
X651667Y43067D01*
X651376Y42983D01*
X651126Y42733D01*
X651001Y42358D01*
Y41942D01*
X650917Y41692D01*
X650709Y41483D01*
X650417Y41400D01*
X650126Y41525D01*
X649917Y41817D01*
X649834Y42150D01*
X649917Y42483D01*
X650126Y42775D01*
X650417Y42900D01*
X650709Y42817D01*
X650917Y42608D01*
X651001Y42358D01*
Y41942D01*
X651126Y41567D01*
X651376Y41317D01*
X651667Y41233D01*
X651959Y41317D01*
X652167Y41525D01*
X652292Y41858D01*
X652334Y42150D01*
G01X661936Y-12400D02*
X663728D01*
X664103Y-12233D01*
X664353Y-11900D01*
X664436Y-11483D01*
X664353Y-11066D01*
X664103Y-10733D01*
X663728Y-10566D01*
X661936D01*
G01X664436Y-7883D02*
X661936D01*
X663728Y-9425D01*
Y-7341D01*
G01X663186Y-5033D02*
Y-4200D01*
X663936D01*
X664186Y-4450D01*
X664353Y-4741D01*
X664436Y-5158D01*
X664353Y-5575D01*
X664186Y-5866D01*
X663936Y-6116D01*
X663644Y-6283D01*
X663311Y-6366D01*
X663019D01*
X662769Y-6283D01*
X662478Y-6116D01*
X662228Y-5866D01*
X662061Y-5616D01*
X661936Y-5283D01*
Y-4991D01*
X662019Y-4658D01*
X662186Y-4408D01*
G01X664436Y-2183D02*
X661936D01*
X662436Y-2683D01*
G01X664436D02*
Y-1683D01*
G01X659510Y-9628D02*
Y-2256D01*
G01X647310Y-9627D02*
Y-2239D01*
G01X660016Y-19174D02*
Y-21674D01*
G01X659058Y-19174D02*
X660974D01*
G01X662241Y-21674D02*
Y-19174D01*
G01X663991D02*
Y-21674D01*
G01Y-20424D02*
X662241D01*
G01X666716Y-21674D02*
Y-19174D01*
X665174Y-20966D01*
X667258D01*
G01X669566Y-20424D02*
X670399D01*
Y-21174D01*
X670149Y-21424D01*
X669858Y-21591D01*
X669441Y-21674D01*
X669024Y-21591D01*
X668733Y-21424D01*
X668483Y-21174D01*
X668316Y-20882D01*
X668233Y-20549D01*
Y-20257D01*
X668316Y-20007D01*
X668483Y-19716D01*
X668733Y-19466D01*
X668983Y-19299D01*
X669316Y-19174D01*
X669608D01*
X669941Y-19257D01*
X670191Y-19424D01*
G01X672416Y-21674D02*
Y-19174D01*
X671916Y-19674D01*
G01Y-21674D02*
X672916D01*
G01X613750Y-22230D02*
Y-19130D01*
X613290Y-19750D01*
G01Y-22230D02*
X614210D01*
G01X617310D02*
Y-19130D01*
X615892Y-21352D01*
X617808D01*
G01X620410Y-22230D02*
Y-19130D01*
X618992Y-21352D01*
X620908D01*
G01X621822Y10883D02*
X622052Y11193D01*
X622320Y11348D01*
X622627Y11400D01*
X623010Y11297D01*
X623278Y11038D01*
X623355Y10728D01*
X623317Y10418D01*
X623163Y10160D01*
X622397Y9643D01*
X622052Y9282D01*
X621822Y8765D01*
X621745Y8300D01*
X623355D01*
G01X625650D02*
X625918Y8352D01*
X626225Y8507D01*
X626417Y8765D01*
X626493Y9127D01*
X626417Y9488D01*
X626187Y9798D01*
X625842Y9953D01*
X625458D01*
X625228Y10057D01*
X625037Y10315D01*
X624960Y10677D01*
X625075Y11038D01*
X625343Y11297D01*
X625650Y11400D01*
X625957Y11297D01*
X626225Y11038D01*
X626340Y10677D01*
X626263Y10315D01*
X626072Y10057D01*
X625842Y9953D01*
X625458D01*
X625113Y9798D01*
X624883Y9488D01*
X624807Y9127D01*
X624883Y8765D01*
X625075Y8507D01*
X625382Y8352D01*
X625650Y8300D01*
G01X628750D02*
X629018Y8352D01*
X629325Y8507D01*
X629517Y8765D01*
X629593Y9127D01*
X629517Y9488D01*
X629287Y9798D01*
X628942Y9953D01*
X628558D01*
X628328Y10057D01*
X628137Y10315D01*
X628060Y10677D01*
X628175Y11038D01*
X628443Y11297D01*
X628750Y11400D01*
X629057Y11297D01*
X629325Y11038D01*
X629440Y10677D01*
X629363Y10315D01*
X629172Y10057D01*
X628942Y9953D01*
X628558D01*
X628213Y9798D01*
X627983Y9488D01*
X627907Y9127D01*
X627983Y8765D01*
X628175Y8507D01*
X628482Y8352D01*
X628750Y8300D01*
G01X621376Y6973D02*
X645766D01*
Y-18617D01*
X621376D01*
G01X622250Y14300D02*
Y17400D01*
X621790Y16780D01*
G01Y14300D02*
X622710D01*
G01X625810D02*
Y17400D01*
X624392Y15178D01*
X626308D01*
G01X628910Y14300D02*
Y17400D01*
X627492Y15178D01*
X629408D01*
G01X621376Y44773D02*
X645766D01*
Y19183D01*
X621376D01*
G01X665001Y43000D02*
X662301D01*
Y36200D01*
X662300Y36199D01*
Y34200D01*
G01X646854Y66507D02*
X649354D01*
Y68173D01*
G01Y70940D02*
X646854D01*
X648646Y69398D01*
Y71482D01*
G01X648104Y73790D02*
Y74623D01*
X648854D01*
X649104Y74373D01*
X649271Y74082D01*
X649354Y73665D01*
X649271Y73248D01*
X649104Y72957D01*
X648854Y72707D01*
X648562Y72540D01*
X648229Y72457D01*
X647937D01*
X647687Y72540D01*
X647396Y72707D01*
X647146Y72957D01*
X646979Y73207D01*
X646854Y73540D01*
Y73832D01*
X646937Y74165D01*
X647104Y74415D01*
G01X649354Y76640D02*
X646854D01*
X647354Y76140D01*
G01X649354D02*
Y77140D01*
G01X679650Y47300D02*
Y44000D01*
X652850D01*
Y47300D01*
G01Y67500D02*
Y70800D01*
X679650D01*
Y67500D01*
G01X649134Y35317D02*
X646634D01*
Y36358D01*
X646759Y36692D01*
X646926Y36900D01*
X647259Y36983D01*
X647592Y36900D01*
X647801Y36650D01*
X647926Y36358D01*
Y35317D01*
G01Y36358D02*
X649134Y36983D01*
G01Y39750D02*
X646634D01*
X648426Y38208D01*
Y40292D01*
G01X647884Y42600D02*
Y43433D01*
X648634D01*
X648884Y43183D01*
X649051Y42892D01*
X649134Y42475D01*
X649051Y42058D01*
X648884Y41767D01*
X648634Y41517D01*
X648342Y41350D01*
X648009Y41267D01*
X647717D01*
X647467Y41350D01*
X647176Y41517D01*
X646926Y41767D01*
X646759Y42017D01*
X646634Y42350D01*
Y42642D01*
X646717Y42975D01*
X646884Y43225D01*
G01X648092Y44658D02*
X647801Y44950D01*
X647634Y45200D01*
X647551Y45533D01*
X647634Y45825D01*
X647801Y46033D01*
X648051Y46200D01*
X648342Y46242D01*
X648592Y46200D01*
X648842Y46033D01*
X649051Y45783D01*
X649134Y45492D01*
X649051Y45158D01*
X648801Y44867D01*
X648426Y44700D01*
X648009Y44658D01*
X647467Y44742D01*
X647176Y44867D01*
X646884Y45075D01*
X646676Y45367D01*
X646634Y45658D01*
X646717Y45950D01*
X646926Y46158D01*
G01X609586Y96138D02*
X609336Y96263D01*
X609044Y96346D01*
X608711D01*
X608336Y96221D01*
X608044Y96013D01*
X607836Y95763D01*
X607669Y95346D01*
X607627Y94971D01*
X607711Y94596D01*
X607836Y94346D01*
X608086Y94096D01*
X608377Y93929D01*
X608669Y93846D01*
X608961D01*
X609252Y93929D01*
X609502Y94054D01*
X609711Y94221D01*
G01X610852Y94346D02*
X611102Y94054D01*
X611436Y93888D01*
X611811Y93846D01*
X612144Y93888D01*
X612477Y94096D01*
X612686Y94346D01*
X612727Y94596D01*
X612644Y94888D01*
X612352Y95096D01*
X612061Y95179D01*
X611686D01*
G01X612061D02*
X612311Y95304D01*
X612519Y95513D01*
X612602Y95763D01*
X612519Y96013D01*
X612311Y96221D01*
X611936Y96346D01*
X611561Y96304D01*
X611186Y96138D01*
G01X614077Y93846D02*
Y96346D01*
X615661D01*
G01X615077Y95138D02*
X614077D01*
G01X618469Y93846D02*
Y96346D01*
X616927Y94554D01*
X619011D01*
G01X650800Y88800D02*
Y90000D01*
X662800D01*
Y88800D01*
G01X650800Y75200D02*
Y74000D01*
X662800D01*
Y75200D01*
G01X655850Y74000D02*
Y72950D01*
X685750D01*
Y75200D01*
G01Y88800D02*
Y91050D01*
X655850D01*
Y90000D01*
G01X653950Y95050D02*
Y94000D01*
X683850D01*
Y96250D01*
G01X622250Y51800D02*
Y54900D01*
X621790Y54280D01*
G01Y51800D02*
X622710D01*
G01X625810D02*
Y54900D01*
X624392Y52678D01*
X626308D01*
G01X628910Y51800D02*
Y54900D01*
X627492Y52678D01*
X629408D01*
G01X620122Y86183D02*
X620352Y86493D01*
X620620Y86648D01*
X620927Y86700D01*
X621310Y86597D01*
X621578Y86338D01*
X621655Y86028D01*
X621617Y85718D01*
X621463Y85460D01*
X620697Y84943D01*
X620352Y84582D01*
X620122Y84065D01*
X620045Y83600D01*
X621655D01*
G01X623950D02*
X624218Y83652D01*
X624525Y83807D01*
X624717Y84065D01*
X624793Y84427D01*
X624717Y84788D01*
X624487Y85098D01*
X624142Y85253D01*
X623758D01*
X623528Y85357D01*
X623337Y85615D01*
X623260Y85977D01*
X623375Y86338D01*
X623643Y86597D01*
X623950Y86700D01*
X624257Y86597D01*
X624525Y86338D01*
X624640Y85977D01*
X624563Y85615D01*
X624372Y85357D01*
X624142Y85253D01*
X623758D01*
X623413Y85098D01*
X623183Y84788D01*
X623107Y84427D01*
X623183Y84065D01*
X623375Y83807D01*
X623682Y83652D01*
X623950Y83600D01*
G01X627050D02*
X627318Y83652D01*
X627625Y83807D01*
X627817Y84065D01*
X627893Y84427D01*
X627817Y84788D01*
X627587Y85098D01*
X627242Y85253D01*
X626858D01*
X626628Y85357D01*
X626437Y85615D01*
X626360Y85977D01*
X626475Y86338D01*
X626743Y86597D01*
X627050Y86700D01*
X627357Y86597D01*
X627625Y86338D01*
X627740Y85977D01*
X627663Y85615D01*
X627472Y85357D01*
X627242Y85253D01*
X626858D01*
X626513Y85098D01*
X626283Y84788D01*
X626207Y84427D01*
X626283Y84065D01*
X626475Y83807D01*
X626782Y83652D01*
X627050Y83600D01*
G01X621376Y82573D02*
X645766D01*
Y56983D01*
X621376D01*
G01X621522Y48683D02*
X621752Y48993D01*
X622020Y49148D01*
X622327Y49200D01*
X622710Y49097D01*
X622978Y48838D01*
X623055Y48528D01*
X623017Y48218D01*
X622863Y47960D01*
X622097Y47443D01*
X621752Y47082D01*
X621522Y46565D01*
X621445Y46100D01*
X623055D01*
G01X625350D02*
X625618Y46152D01*
X625925Y46307D01*
X626117Y46565D01*
X626193Y46927D01*
X626117Y47288D01*
X625887Y47598D01*
X625542Y47753D01*
X625158D01*
X624928Y47857D01*
X624737Y48115D01*
X624660Y48477D01*
X624775Y48838D01*
X625043Y49097D01*
X625350Y49200D01*
X625657Y49097D01*
X625925Y48838D01*
X626040Y48477D01*
X625963Y48115D01*
X625772Y47857D01*
X625542Y47753D01*
X625158D01*
X624813Y47598D01*
X624583Y47288D01*
X624507Y46927D01*
X624583Y46565D01*
X624775Y46307D01*
X625082Y46152D01*
X625350Y46100D01*
G01X628450D02*
X628718Y46152D01*
X629025Y46307D01*
X629217Y46565D01*
X629293Y46927D01*
X629217Y47288D01*
X628987Y47598D01*
X628642Y47753D01*
X628258D01*
X628028Y47857D01*
X627837Y48115D01*
X627760Y48477D01*
X627875Y48838D01*
X628143Y49097D01*
X628450Y49200D01*
X628757Y49097D01*
X629025Y48838D01*
X629140Y48477D01*
X629063Y48115D01*
X628872Y47857D01*
X628642Y47753D01*
X628258D01*
X627913Y47598D01*
X627683Y47288D01*
X627607Y46927D01*
X627683Y46565D01*
X627875Y46307D01*
X628182Y46152D01*
X628450Y46100D01*
G01X604206Y129792D02*
Y132292D01*
X605247D01*
X605581Y132167D01*
X605789Y132000D01*
X605872Y131667D01*
X605789Y131334D01*
X605539Y131125D01*
X605247Y131000D01*
X604206D01*
G01X605247D02*
X605872Y129792D01*
G01X607222Y130292D02*
X607472Y130000D01*
X607806Y129834D01*
X608181Y129792D01*
X608514Y129834D01*
X608847Y130042D01*
X609056Y130292D01*
X609097Y130542D01*
X609014Y130834D01*
X608722Y131042D01*
X608431Y131125D01*
X608056D01*
G01X608431D02*
X608681Y131250D01*
X608889Y131459D01*
X608972Y131709D01*
X608889Y131959D01*
X608681Y132167D01*
X608306Y132292D01*
X607931Y132250D01*
X607556Y132084D01*
G01X610447Y129792D02*
Y132292D01*
X612031D01*
G01X611447Y131084D02*
X610447D01*
G01X613422Y130167D02*
X613672Y129959D01*
X613964Y129834D01*
X614339Y129792D01*
X614714Y129875D01*
X615006Y130042D01*
X615214Y130334D01*
X615256Y130667D01*
X615172Y131000D01*
X614964Y131209D01*
X614672Y131375D01*
X614381Y131417D01*
X614089Y131375D01*
X613714Y131209D01*
X613839Y132292D01*
X614964D01*
G01X603906Y105392D02*
Y107892D01*
X604947D01*
X605281Y107767D01*
X605489Y107600D01*
X605572Y107267D01*
X605489Y106934D01*
X605239Y106725D01*
X604947Y106600D01*
X603906D01*
G01X604947D02*
X605572Y105392D01*
G01X606922Y105892D02*
X607172Y105600D01*
X607506Y105434D01*
X607881Y105392D01*
X608214Y105434D01*
X608547Y105642D01*
X608756Y105892D01*
X608797Y106142D01*
X608714Y106434D01*
X608422Y106642D01*
X608131Y106725D01*
X607756D01*
G01X608131D02*
X608381Y106850D01*
X608589Y107059D01*
X608672Y107309D01*
X608589Y107559D01*
X608381Y107767D01*
X608006Y107892D01*
X607631Y107850D01*
X607256Y107684D01*
G01X610147Y105392D02*
Y107892D01*
X611731D01*
G01X611147Y106684D02*
X610147D01*
G01X614539Y105392D02*
Y107892D01*
X612997Y106100D01*
X615081D01*
G01X618700Y124057D02*
X616200D01*
Y125098D01*
X616325Y125432D01*
X616492Y125640D01*
X616825Y125723D01*
X617158Y125640D01*
X617367Y125390D01*
X617492Y125098D01*
Y124057D01*
G01Y125098D02*
X618700Y125723D01*
G01X618200Y127073D02*
X618492Y127323D01*
X618658Y127657D01*
X618700Y128032D01*
X618658Y128365D01*
X618450Y128698D01*
X618200Y128907D01*
X617950Y128948D01*
X617658Y128865D01*
X617450Y128573D01*
X617367Y128282D01*
Y127907D01*
G01Y128282D02*
X617242Y128532D01*
X617033Y128740D01*
X616783Y128823D01*
X616533Y128740D01*
X616325Y128532D01*
X616200Y128157D01*
X616242Y127782D01*
X616408Y127407D01*
G01X618700Y130298D02*
X616200D01*
Y131882D01*
G01X617408Y131298D02*
Y130298D01*
G01X618700Y134190D02*
X616200D01*
X616700Y133690D01*
G01X618700D02*
Y134690D01*
G01X604206Y126292D02*
Y128792D01*
X605247D01*
X605581Y128667D01*
X605789Y128500D01*
X605872Y128167D01*
X605789Y127834D01*
X605539Y127625D01*
X605247Y127500D01*
X604206D01*
G01X605247D02*
X605872Y126292D01*
G01X607222Y126792D02*
X607472Y126500D01*
X607806Y126334D01*
X608181Y126292D01*
X608514Y126334D01*
X608847Y126542D01*
X609056Y126792D01*
X609097Y127042D01*
X609014Y127334D01*
X608722Y127542D01*
X608431Y127625D01*
X608056D01*
G01X608431D02*
X608681Y127750D01*
X608889Y127959D01*
X608972Y128209D01*
X608889Y128459D01*
X608681Y128667D01*
X608306Y128792D01*
X607931Y128750D01*
X607556Y128584D01*
G01X610447Y126292D02*
Y128792D01*
X612031D01*
G01X611447Y127584D02*
X610447D01*
G01X613547Y128375D02*
X613797Y128625D01*
X614089Y128750D01*
X614422Y128792D01*
X614839Y128709D01*
X615131Y128500D01*
X615214Y128250D01*
X615172Y128000D01*
X615006Y127792D01*
X614172Y127375D01*
X613797Y127084D01*
X613547Y126667D01*
X613464Y126292D01*
X615214D01*
G01X605906Y101492D02*
Y103992D01*
X606947D01*
X607281Y103867D01*
X607489Y103700D01*
X607572Y103367D01*
X607489Y103034D01*
X607239Y102825D01*
X606947Y102700D01*
X605906D01*
G01X606947D02*
X607572Y101492D01*
G01X608922Y101992D02*
X609172Y101700D01*
X609506Y101534D01*
X609881Y101492D01*
X610214Y101534D01*
X610547Y101742D01*
X610756Y101992D01*
X610797Y102242D01*
X610714Y102534D01*
X610422Y102742D01*
X610131Y102825D01*
X609756D01*
G01X610131D02*
X610381Y102950D01*
X610589Y103159D01*
X610672Y103409D01*
X610589Y103659D01*
X610381Y103867D01*
X610006Y103992D01*
X609631Y103950D01*
X609256Y103784D01*
G01X612147Y101492D02*
Y103992D01*
X613731D01*
G01X613147Y102784D02*
X612147D01*
G01X615247Y102534D02*
X615539Y102825D01*
X615789Y102992D01*
X616122Y103075D01*
X616414Y102992D01*
X616622Y102825D01*
X616789Y102575D01*
X616831Y102284D01*
X616789Y102034D01*
X616622Y101784D01*
X616372Y101575D01*
X616081Y101492D01*
X615747Y101575D01*
X615456Y101825D01*
X615289Y102200D01*
X615247Y102617D01*
X615331Y103159D01*
X615456Y103450D01*
X615664Y103742D01*
X615956Y103950D01*
X616247Y103992D01*
X616539Y103909D01*
X616747Y103700D01*
G01X620560Y101747D02*
X618060D01*
Y102788D01*
X618185Y103122D01*
X618352Y103330D01*
X618685Y103413D01*
X619018Y103330D01*
X619227Y103080D01*
X619352Y102788D01*
Y101747D01*
G01Y102788D02*
X620560Y103413D01*
G01X620060Y104763D02*
X620352Y105013D01*
X620518Y105347D01*
X620560Y105722D01*
X620518Y106055D01*
X620310Y106388D01*
X620060Y106597D01*
X619810Y106638D01*
X619518Y106555D01*
X619310Y106263D01*
X619227Y105972D01*
Y105597D01*
G01Y105972D02*
X619102Y106222D01*
X618893Y106430D01*
X618643Y106513D01*
X618393Y106430D01*
X618185Y106222D01*
X618060Y105847D01*
X618102Y105472D01*
X618268Y105097D01*
G01X620560Y107988D02*
X618060D01*
Y109572D01*
G01X619268Y108988D02*
Y107988D01*
G01X620060Y110963D02*
X620352Y111213D01*
X620518Y111547D01*
X620560Y111922D01*
X620518Y112255D01*
X620310Y112588D01*
X620060Y112797D01*
X619810Y112838D01*
X619518Y112755D01*
X619310Y112463D01*
X619227Y112172D01*
Y111797D01*
G01Y112172D02*
X619102Y112422D01*
X618893Y112630D01*
X618643Y112713D01*
X618393Y112630D01*
X618185Y112422D01*
X618060Y112047D01*
X618102Y111672D01*
X618268Y111297D01*
G01X604340Y150778D02*
X604090Y150903D01*
X603798Y150986D01*
X603465D01*
X603090Y150861D01*
X602798Y150653D01*
X602590Y150403D01*
X602423Y149986D01*
X602381Y149611D01*
X602465Y149236D01*
X602590Y148986D01*
X602840Y148736D01*
X603131Y148569D01*
X603423Y148486D01*
X603715D01*
X604006Y148569D01*
X604256Y148694D01*
X604465Y148861D01*
G01X606523Y148486D02*
Y150986D01*
X606023Y150486D01*
G01Y148486D02*
X607023D01*
G01X609873Y149736D02*
X610706D01*
Y148986D01*
X610456Y148736D01*
X610165Y148569D01*
X609748Y148486D01*
X609331Y148569D01*
X609040Y148736D01*
X608790Y148986D01*
X608623Y149278D01*
X608540Y149611D01*
Y149903D01*
X608623Y150153D01*
X608790Y150444D01*
X609040Y150694D01*
X609290Y150861D01*
X609623Y150986D01*
X609915D01*
X610248Y150903D01*
X610498Y150736D01*
G01X611931Y149528D02*
X612223Y149819D01*
X612473Y149986D01*
X612806Y150069D01*
X613098Y149986D01*
X613306Y149819D01*
X613473Y149569D01*
X613515Y149278D01*
X613473Y149028D01*
X613306Y148778D01*
X613056Y148569D01*
X612765Y148486D01*
X612431Y148569D01*
X612140Y148819D01*
X611973Y149194D01*
X611931Y149611D01*
X612015Y150153D01*
X612140Y150444D01*
X612348Y150736D01*
X612640Y150944D01*
X612931Y150986D01*
X613223Y150903D01*
X613431Y150694D01*
G01X612340Y155278D02*
X612090Y155403D01*
X611798Y155486D01*
X611465D01*
X611090Y155361D01*
X610798Y155153D01*
X610590Y154903D01*
X610423Y154486D01*
X610381Y154111D01*
X610465Y153736D01*
X610590Y153486D01*
X610840Y153236D01*
X611131Y153069D01*
X611423Y152986D01*
X611715D01*
X612006Y153069D01*
X612256Y153194D01*
X612465Y153361D01*
G01X614523Y152986D02*
Y155486D01*
X614023Y154986D01*
G01Y152986D02*
X615023D01*
G01X617873Y154236D02*
X618706D01*
Y153486D01*
X618456Y153236D01*
X618165Y153069D01*
X617748Y152986D01*
X617331Y153069D01*
X617040Y153236D01*
X616790Y153486D01*
X616623Y153778D01*
X616540Y154111D01*
Y154403D01*
X616623Y154653D01*
X616790Y154944D01*
X617040Y155194D01*
X617290Y155361D01*
X617623Y155486D01*
X617915D01*
X618248Y155403D01*
X618498Y155236D01*
G01X619806Y153361D02*
X620056Y153153D01*
X620348Y153028D01*
X620723Y152986D01*
X621098Y153069D01*
X621390Y153236D01*
X621598Y153528D01*
X621640Y153861D01*
X621556Y154194D01*
X621348Y154403D01*
X621056Y154569D01*
X620765Y154611D01*
X620473Y154569D01*
X620098Y154403D01*
X620223Y155486D01*
X621348D01*
G01X655067Y131659D02*
X654817Y131784D01*
X654525Y131867D01*
X654192D01*
X653817Y131742D01*
X653525Y131534D01*
X653317Y131284D01*
X653150Y130867D01*
X653108Y130492D01*
X653192Y130117D01*
X653317Y129867D01*
X653567Y129617D01*
X653858Y129450D01*
X654150Y129367D01*
X654442D01*
X654733Y129450D01*
X654983Y129575D01*
X655192Y129742D01*
G01X657750Y129367D02*
Y131867D01*
X656208Y130075D01*
X658292D01*
G01X659558Y129367D02*
Y131867D01*
X661142D01*
G01X660558Y130659D02*
X659558D01*
G01X662533Y129867D02*
X662783Y129575D01*
X663117Y129409D01*
X663492Y129367D01*
X663825Y129409D01*
X664158Y129617D01*
X664367Y129867D01*
X664408Y130117D01*
X664325Y130409D01*
X664033Y130617D01*
X663742Y130700D01*
X663367D01*
G01X663742D02*
X663992Y130825D01*
X664200Y131034D01*
X664283Y131284D01*
X664200Y131534D01*
X663992Y131742D01*
X663617Y131867D01*
X663242Y131825D01*
X662867Y131659D01*
G01X654267Y142259D02*
X654017Y142384D01*
X653725Y142467D01*
X653392D01*
X653017Y142342D01*
X652725Y142134D01*
X652517Y141884D01*
X652350Y141467D01*
X652308Y141092D01*
X652392Y140717D01*
X652517Y140467D01*
X652767Y140217D01*
X653058Y140050D01*
X653350Y139967D01*
X653642D01*
X653933Y140050D01*
X654183Y140175D01*
X654392Y140342D01*
G01X656950Y139967D02*
Y142467D01*
X655408Y140675D01*
X657492D01*
G01X658758Y139967D02*
Y142467D01*
X660342D01*
G01X659758Y141259D02*
X658758D01*
G01X662650Y139967D02*
Y142467D01*
X662150Y141967D01*
G01Y139967D02*
X663150D01*
G01X683850Y109850D02*
Y112100D01*
X653950D01*
Y111050D01*
G01X648900Y96250D02*
Y95050D01*
X660900D01*
Y96250D01*
G01X648900Y109850D02*
Y111050D01*
X660900D01*
Y109850D01*
G01X630722Y142967D02*
Y146067D01*
X632178D01*
G01X631642Y144569D02*
X630722D01*
G01X634550Y142967D02*
Y146067D01*
X634090Y145447D01*
G01Y142967D02*
X635010D01*
G01X633091Y170945D02*
Y148945D01*
X636091D01*
Y143795D01*
X759091D01*
Y176095D01*
X641383D01*
G01X631812Y130448D02*
X631687Y130198D01*
X631604Y129906D01*
Y129573D01*
X631729Y129198D01*
X631937Y128906D01*
X632187Y128698D01*
X632604Y128531D01*
X632979Y128489D01*
X633354Y128573D01*
X633604Y128698D01*
X633854Y128948D01*
X634021Y129239D01*
X634104Y129531D01*
Y129823D01*
X634021Y130114D01*
X633896Y130364D01*
X633729Y130573D01*
G01X633604Y131714D02*
X633896Y131964D01*
X634062Y132298D01*
X634104Y132673D01*
X634062Y133006D01*
X633854Y133339D01*
X633604Y133548D01*
X633354Y133589D01*
X633062Y133506D01*
X632854Y133214D01*
X632771Y132923D01*
Y132548D01*
G01Y132923D02*
X632646Y133173D01*
X632437Y133381D01*
X632187Y133464D01*
X631937Y133381D01*
X631729Y133173D01*
X631604Y132798D01*
X631646Y132423D01*
X631812Y132048D01*
G01X634104Y134939D02*
X631604D01*
Y136523D01*
G01X632812Y135939D02*
Y134939D01*
G01X634104Y138831D02*
X631604D01*
X632104Y138331D01*
G01X634104D02*
Y139331D01*
G01X636254Y130431D02*
X636129Y130181D01*
X636046Y129889D01*
Y129556D01*
X636171Y129181D01*
X636379Y128889D01*
X636629Y128681D01*
X637046Y128514D01*
X637421Y128472D01*
X637796Y128556D01*
X638046Y128681D01*
X638296Y128931D01*
X638463Y129222D01*
X638546Y129514D01*
Y129806D01*
X638463Y130097D01*
X638338Y130347D01*
X638171Y130556D01*
G01X638546Y133114D02*
X636046D01*
X637838Y131572D01*
Y133656D01*
G01X638546Y134922D02*
X636046D01*
Y136506D01*
G01X637254Y135922D02*
Y134922D01*
G01X636463Y138022D02*
X636213Y138272D01*
X636088Y138564D01*
X636046Y138897D01*
X636129Y139314D01*
X636338Y139606D01*
X636588Y139689D01*
X636838Y139647D01*
X637046Y139481D01*
X637463Y138647D01*
X637754Y138272D01*
X638171Y138022D01*
X638546Y137939D01*
Y139689D01*
G01X616361Y147924D02*
Y150424D01*
X617402D01*
X617736Y150299D01*
X617944Y150132D01*
X618027Y149799D01*
X617944Y149466D01*
X617694Y149257D01*
X617402Y149132D01*
X616361D01*
G01X617402D02*
X618027Y147924D01*
G01X620294Y150424D02*
Y147924D01*
G01X619336Y150424D02*
X621252D01*
G01X622602Y150007D02*
X622852Y150257D01*
X623144Y150382D01*
X623477Y150424D01*
X623894Y150341D01*
X624186Y150132D01*
X624269Y149882D01*
X624227Y149632D01*
X624061Y149424D01*
X623227Y149007D01*
X622852Y148716D01*
X622602Y148299D01*
X622519Y147924D01*
X624269D01*
G01X626494Y150424D02*
X626161Y150341D01*
X625911Y150132D01*
X625744Y149882D01*
X625619Y149549D01*
X625577Y149174D01*
X625619Y148799D01*
X625744Y148466D01*
X625911Y148216D01*
X626161Y148007D01*
X626494Y147924D01*
X626827Y148007D01*
X627077Y148216D01*
X627244Y148466D01*
X627369Y148799D01*
X627411Y149174D01*
X627369Y149549D01*
X627244Y149882D01*
X627077Y150132D01*
X626827Y150341D01*
X626494Y150424D01*
G01X610559Y195895D02*
X610309Y196020D01*
X610017Y196103D01*
X609684D01*
X609309Y195978D01*
X609017Y195770D01*
X608809Y195520D01*
X608642Y195103D01*
X608600Y194728D01*
X608684Y194353D01*
X608809Y194103D01*
X609059Y193853D01*
X609350Y193686D01*
X609642Y193603D01*
X609934D01*
X610225Y193686D01*
X610475Y193811D01*
X610684Y193978D01*
G01X612742Y193603D02*
Y196103D01*
X612242Y195603D01*
G01Y193603D02*
X613242D01*
G01X615050D02*
Y196103D01*
X616634D01*
G01X616050Y194895D02*
X615050D01*
G01X618150Y195686D02*
X618400Y195936D01*
X618692Y196061D01*
X619025Y196103D01*
X619442Y196020D01*
X619734Y195811D01*
X619817Y195561D01*
X619775Y195311D01*
X619609Y195103D01*
X618775Y194686D01*
X618400Y194395D01*
X618150Y193978D01*
X618067Y193603D01*
X619817D01*
G01X622042D02*
X622334Y193645D01*
X622667Y193770D01*
X622875Y193978D01*
X622959Y194270D01*
X622875Y194561D01*
X622625Y194811D01*
X622250Y194936D01*
X621834D01*
X621584Y195020D01*
X621375Y195228D01*
X621292Y195520D01*
X621417Y195811D01*
X621709Y196020D01*
X622042Y196103D01*
X622375Y196020D01*
X622667Y195811D01*
X622792Y195520D01*
X622709Y195228D01*
X622500Y195020D01*
X622250Y194936D01*
X621834D01*
X621459Y194811D01*
X621209Y194561D01*
X621125Y194270D01*
X621209Y193978D01*
X621417Y193770D01*
X621750Y193645D01*
X622042Y193603D01*
G01X625375Y161241D02*
X625250Y160991D01*
X625167Y160699D01*
Y160366D01*
X625292Y159991D01*
X625500Y159699D01*
X625750Y159491D01*
X626167Y159324D01*
X626542Y159282D01*
X626917Y159366D01*
X627167Y159491D01*
X627417Y159741D01*
X627584Y160032D01*
X627667Y160324D01*
Y160616D01*
X627584Y160907D01*
X627459Y161157D01*
X627292Y161366D01*
G01X625167Y163424D02*
X627667D01*
G01X625167Y162466D02*
Y164382D01*
G01X625584Y165732D02*
X625334Y165982D01*
X625209Y166274D01*
X625167Y166607D01*
X625250Y167024D01*
X625459Y167316D01*
X625709Y167399D01*
X625959Y167357D01*
X626167Y167191D01*
X626584Y166357D01*
X626875Y165982D01*
X627292Y165732D01*
X627667Y165649D01*
Y167399D01*
G01X627375Y168916D02*
X627584Y169207D01*
X627667Y169541D01*
X627584Y169874D01*
X627334Y170166D01*
X626959Y170374D01*
X626584Y170457D01*
X626125D01*
X625750Y170374D01*
X625417Y170166D01*
X625250Y169916D01*
X625167Y169624D01*
X625250Y169291D01*
X625417Y169041D01*
X625667Y168874D01*
X626000Y168791D01*
X626292Y168874D01*
X626584Y169082D01*
X626750Y169332D01*
X626792Y169624D01*
X626709Y169957D01*
X626500Y170207D01*
X626125Y170457D01*
G01X625284Y175611D02*
X625159Y175361D01*
X625076Y175069D01*
Y174736D01*
X625201Y174361D01*
X625409Y174069D01*
X625659Y173861D01*
X626076Y173694D01*
X626451Y173652D01*
X626826Y173736D01*
X627076Y173861D01*
X627326Y174111D01*
X627493Y174402D01*
X627576Y174694D01*
Y174986D01*
X627493Y175277D01*
X627368Y175527D01*
X627201Y175736D01*
G01X625076Y177794D02*
X627576D01*
G01X625076Y176836D02*
Y178752D01*
G01X627076Y179977D02*
X627368Y180227D01*
X627534Y180561D01*
X627576Y180936D01*
X627534Y181269D01*
X627326Y181602D01*
X627076Y181811D01*
X626826Y181852D01*
X626534Y181769D01*
X626326Y181477D01*
X626243Y181186D01*
Y180811D01*
G01Y181186D02*
X626118Y181436D01*
X625909Y181644D01*
X625659Y181727D01*
X625409Y181644D01*
X625201Y181436D01*
X625076Y181061D01*
X625118Y180686D01*
X625284Y180311D01*
G01X627076Y183077D02*
X627368Y183327D01*
X627534Y183661D01*
X627576Y184036D01*
X627534Y184369D01*
X627326Y184702D01*
X627076Y184911D01*
X626826Y184952D01*
X626534Y184869D01*
X626326Y184577D01*
X626243Y184286D01*
Y183911D01*
G01Y184286D02*
X626118Y184536D01*
X625909Y184744D01*
X625659Y184827D01*
X625409Y184744D01*
X625201Y184536D01*
X625076Y184161D01*
X625118Y183786D01*
X625284Y183411D01*
G01X632889Y190274D02*
X632764Y190024D01*
X632681Y189732D01*
Y189399D01*
X632806Y189024D01*
X633014Y188732D01*
X633264Y188524D01*
X633681Y188357D01*
X634056Y188315D01*
X634431Y188399D01*
X634681Y188524D01*
X634931Y188774D01*
X635098Y189065D01*
X635181Y189357D01*
Y189649D01*
X635098Y189940D01*
X634973Y190190D01*
X634806Y190399D01*
G01X635181Y192957D02*
X632681D01*
X634473Y191415D01*
Y193499D01*
G01X635181Y196390D02*
Y194724D01*
X632681D01*
Y196390D01*
G01X633889Y195724D02*
Y194724D01*
G01X633098Y197865D02*
X632848Y198115D01*
X632723Y198407D01*
X632681Y198740D01*
X632764Y199157D01*
X632973Y199449D01*
X633223Y199532D01*
X633473Y199490D01*
X633681Y199324D01*
X634098Y198490D01*
X634389Y198115D01*
X634806Y197865D01*
X635181Y197782D01*
Y199532D01*
G01X634889Y201049D02*
X635098Y201340D01*
X635181Y201674D01*
X635098Y202007D01*
X634848Y202299D01*
X634473Y202507D01*
X634098Y202590D01*
X633639D01*
X633264Y202507D01*
X632931Y202299D01*
X632764Y202049D01*
X632681Y201757D01*
X632764Y201424D01*
X632931Y201174D01*
X633181Y201007D01*
X633514Y200924D01*
X633806Y201007D01*
X634098Y201215D01*
X634264Y201465D01*
X634306Y201757D01*
X634223Y202090D01*
X634014Y202340D01*
X633639Y202590D01*
G01X672500Y197500D02*
X649925D01*
G01X672500Y179500D02*
X649928D01*
G01X637136Y194800D02*
Y198362D01*
X649932D01*
Y194800D01*
G01X637136Y182200D02*
Y178409D01*
X649932D01*
Y182200D01*
G01X634885Y176547D02*
X631785D01*
Y178003D01*
G01X633283Y177467D02*
Y176547D01*
G01X632302Y179647D02*
X631992Y179877D01*
X631837Y180145D01*
X631785Y180452D01*
X631888Y180835D01*
X632147Y181103D01*
X632457Y181180D01*
X632767Y181142D01*
X633025Y180988D01*
X633542Y180222D01*
X633903Y179877D01*
X634420Y179647D01*
X634885Y179570D01*
Y181180D01*
G01X631785Y183475D02*
X631888Y183168D01*
X632147Y182938D01*
X632457Y182785D01*
X632870Y182670D01*
X633335Y182632D01*
X633800Y182670D01*
X634213Y182785D01*
X634523Y182938D01*
X634782Y183168D01*
X634885Y183475D01*
X634782Y183782D01*
X634523Y184012D01*
X634213Y184165D01*
X633800Y184280D01*
X633335Y184318D01*
X632870Y184280D01*
X632457Y184165D01*
X632147Y184012D01*
X631888Y183782D01*
X631785Y183475D01*
G01X631719Y159683D02*
X631969Y159891D01*
X632136Y160141D01*
X632219Y160433D01*
X632136Y160766D01*
X631969Y161016D01*
X631719Y161266D01*
X631386Y161349D01*
X629719D01*
G01X632219Y164116D02*
X629719D01*
X631511Y162574D01*
Y164658D01*
G01X632219Y167549D02*
Y165883D01*
X629719D01*
Y167549D01*
G01X630927Y166883D02*
Y165883D01*
G01X632219Y169816D02*
X629719D01*
X630219Y169316D01*
G01X632219D02*
Y170316D01*
G01X611361Y178424D02*
Y180924D01*
X612402D01*
X612736Y180799D01*
X612944Y180632D01*
X613027Y180299D01*
X612944Y179966D01*
X612694Y179757D01*
X612402Y179632D01*
X611361D01*
G01X612402D02*
X613027Y178424D01*
G01X615294Y180924D02*
Y178424D01*
G01X614336Y180924D02*
X616252D01*
G01X617602Y180507D02*
X617852Y180757D01*
X618144Y180882D01*
X618477Y180924D01*
X618894Y180841D01*
X619186Y180632D01*
X619269Y180382D01*
X619227Y180132D01*
X619061Y179924D01*
X618227Y179507D01*
X617852Y179216D01*
X617602Y178799D01*
X617519Y178424D01*
X619269D01*
G01X620702Y180507D02*
X620952Y180757D01*
X621244Y180882D01*
X621577Y180924D01*
X621994Y180841D01*
X622286Y180632D01*
X622369Y180382D01*
X622327Y180132D01*
X622161Y179924D01*
X621327Y179507D01*
X620952Y179216D01*
X620702Y178799D01*
X620619Y178424D01*
X622369D01*
G01X612763Y199731D02*
X612513Y199856D01*
X612221Y199939D01*
X611888D01*
X611513Y199814D01*
X611221Y199606D01*
X611013Y199356D01*
X610846Y198939D01*
X610804Y198564D01*
X610888Y198189D01*
X611013Y197939D01*
X611263Y197689D01*
X611554Y197522D01*
X611846Y197439D01*
X612138D01*
X612429Y197522D01*
X612679Y197647D01*
X612888Y197814D01*
G01X614946Y197439D02*
Y199939D01*
X614446Y199439D01*
G01Y197439D02*
X615446D01*
G01X618296Y198689D02*
X619129D01*
Y197939D01*
X618879Y197689D01*
X618588Y197522D01*
X618171Y197439D01*
X617754Y197522D01*
X617463Y197689D01*
X617213Y197939D01*
X617046Y198231D01*
X616963Y198564D01*
Y198856D01*
X617046Y199106D01*
X617213Y199397D01*
X617463Y199647D01*
X617713Y199814D01*
X618046Y199939D01*
X618338D01*
X618671Y199856D01*
X618921Y199689D01*
G01X620354Y199522D02*
X620604Y199772D01*
X620896Y199897D01*
X621229Y199939D01*
X621646Y199856D01*
X621938Y199647D01*
X622021Y199397D01*
X621979Y199147D01*
X621813Y198939D01*
X620979Y198522D01*
X620604Y198231D01*
X620354Y197814D01*
X620271Y197439D01*
X622021D01*
G01X610475Y187103D02*
X608809D01*
Y189603D01*
X610475D01*
G01X609809Y188395D02*
X608809D01*
G01X611825Y189603D02*
Y187811D01*
X611992Y187436D01*
X612325Y187186D01*
X612742Y187103D01*
X613159Y187186D01*
X613492Y187436D01*
X613659Y187811D01*
Y189603D01*
G01X615842Y187103D02*
Y189603D01*
X615342Y189103D01*
G01Y187103D02*
X616342D01*
G01X618150D02*
Y189603D01*
X619734D01*
G01X619150Y188395D02*
X618150D01*
G01X622042Y187103D02*
Y189603D01*
X621542Y189103D01*
G01Y187103D02*
X622542D01*
G01X611033Y162400D02*
X609367D01*
Y164900D01*
X611033D01*
G01X610367Y163692D02*
X609367D01*
G01X612383Y164900D02*
Y163108D01*
X612550Y162733D01*
X612883Y162483D01*
X613300Y162400D01*
X613717Y162483D01*
X614050Y162733D01*
X614217Y163108D01*
Y164900D01*
G01X616400Y162400D02*
Y164900D01*
X615900Y164400D01*
G01Y162400D02*
X616900D01*
G01X619750Y163650D02*
X620583D01*
Y162900D01*
X620333Y162650D01*
X620042Y162483D01*
X619625Y162400D01*
X619208Y162483D01*
X618917Y162650D01*
X618667Y162900D01*
X618500Y163192D01*
X618417Y163525D01*
Y163817D01*
X618500Y164067D01*
X618667Y164358D01*
X618917Y164608D01*
X619167Y164775D01*
X619500Y164900D01*
X619792D01*
X620125Y164817D01*
X620375Y164650D01*
G01X622600Y162400D02*
Y164900D01*
X622100Y164400D01*
G01Y162400D02*
X623100D01*
G01X633478Y208097D02*
X635978D01*
Y209763D01*
G01Y212530D02*
X633478D01*
X635270Y210988D01*
Y213072D01*
G01X635978Y215963D02*
Y214297D01*
X633478D01*
Y215963D01*
G01X634686Y215297D02*
Y214297D01*
G01X633895Y217438D02*
X633645Y217688D01*
X633520Y217980D01*
X633478Y218313D01*
X633561Y218730D01*
X633770Y219022D01*
X634020Y219105D01*
X634270Y219063D01*
X634478Y218897D01*
X634895Y218063D01*
X635186Y217688D01*
X635603Y217438D01*
X635978Y217355D01*
Y219105D01*
G01X678634Y200397D02*
X641234D01*
Y206445D01*
G01X617860Y261255D02*
Y263755D01*
X618901D01*
X619235Y263630D01*
X619443Y263463D01*
X619526Y263130D01*
X619443Y262797D01*
X619193Y262588D01*
X618901Y262463D01*
X617860D01*
G01X618901D02*
X619526Y261255D01*
G01X622293D02*
Y263755D01*
X620751Y261963D01*
X622835D01*
G01X623976Y261255D02*
Y263755D01*
X624810D01*
X625143Y263630D01*
X625393Y263463D01*
X625601Y263213D01*
X625768Y262922D01*
X625810Y262505D01*
X625768Y262088D01*
X625601Y261797D01*
X625393Y261547D01*
X625143Y261380D01*
X624810Y261255D01*
X623976D01*
G01X627201Y262297D02*
X627493Y262588D01*
X627743Y262755D01*
X628076Y262838D01*
X628368Y262755D01*
X628576Y262588D01*
X628743Y262338D01*
X628785Y262047D01*
X628743Y261797D01*
X628576Y261547D01*
X628326Y261338D01*
X628035Y261255D01*
X627701Y261338D01*
X627410Y261588D01*
X627243Y261963D01*
X627201Y262380D01*
X627285Y262922D01*
X627410Y263213D01*
X627618Y263505D01*
X627910Y263713D01*
X628201Y263755D01*
X628493Y263672D01*
X628701Y263463D01*
G01X631593Y261255D02*
Y263755D01*
X630051Y261963D01*
X632135D01*
G01X618460Y254162D02*
Y256662D01*
X619501D01*
X619835Y256537D01*
X620043Y256370D01*
X620126Y256037D01*
X620043Y255704D01*
X619793Y255495D01*
X619501Y255370D01*
X618460D01*
G01X619501D02*
X620126Y254162D01*
G01X622893D02*
Y256662D01*
X621351Y254870D01*
X623435D01*
G01X626326Y254162D02*
X624660D01*
Y256662D01*
X626326D01*
G01X625660Y255454D02*
X624660D01*
G01X627801Y256245D02*
X628051Y256495D01*
X628343Y256620D01*
X628676Y256662D01*
X629093Y256579D01*
X629385Y256370D01*
X629468Y256120D01*
X629426Y255870D01*
X629260Y255662D01*
X628426Y255245D01*
X628051Y254954D01*
X627801Y254537D01*
X627718Y254162D01*
X629468D01*
G01X617860Y268255D02*
Y270755D01*
X618901D01*
X619235Y270630D01*
X619443Y270463D01*
X619526Y270130D01*
X619443Y269797D01*
X619193Y269588D01*
X618901Y269463D01*
X617860D01*
G01X618901D02*
X619526Y268255D01*
G01X622293D02*
Y270755D01*
X620751Y268963D01*
X622835D01*
G01X623976Y268255D02*
Y270755D01*
X624810D01*
X625143Y270630D01*
X625393Y270463D01*
X625601Y270213D01*
X625768Y269922D01*
X625810Y269505D01*
X625768Y269088D01*
X625601Y268797D01*
X625393Y268547D01*
X625143Y268380D01*
X624810Y268255D01*
X623976D01*
G01X627076Y268630D02*
X627326Y268422D01*
X627618Y268297D01*
X627993Y268255D01*
X628368Y268338D01*
X628660Y268505D01*
X628868Y268797D01*
X628910Y269130D01*
X628826Y269463D01*
X628618Y269672D01*
X628326Y269838D01*
X628035Y269880D01*
X627743Y269838D01*
X627368Y269672D01*
X627493Y270755D01*
X628618D01*
G01X631010Y268255D02*
X631093Y268797D01*
X631218Y269255D01*
X631385Y269672D01*
X631593Y270130D01*
X631926Y270755D01*
X630260D01*
G01X617860Y264852D02*
Y267352D01*
X618901D01*
X619235Y267227D01*
X619443Y267060D01*
X619526Y266727D01*
X619443Y266394D01*
X619193Y266185D01*
X618901Y266060D01*
X617860D01*
G01X618901D02*
X619526Y264852D01*
G01X622293D02*
Y267352D01*
X620751Y265560D01*
X622835D01*
G01X623976Y264852D02*
Y267352D01*
X624810D01*
X625143Y267227D01*
X625393Y267060D01*
X625601Y266810D01*
X625768Y266519D01*
X625810Y266102D01*
X625768Y265685D01*
X625601Y265394D01*
X625393Y265144D01*
X625143Y264977D01*
X624810Y264852D01*
X623976D01*
G01X627201Y265894D02*
X627493Y266185D01*
X627743Y266352D01*
X628076Y266435D01*
X628368Y266352D01*
X628576Y266185D01*
X628743Y265935D01*
X628785Y265644D01*
X628743Y265394D01*
X628576Y265144D01*
X628326Y264935D01*
X628035Y264852D01*
X627701Y264935D01*
X627410Y265185D01*
X627243Y265560D01*
X627201Y265977D01*
X627285Y266519D01*
X627410Y266810D01*
X627618Y267102D01*
X627910Y267310D01*
X628201Y267352D01*
X628493Y267269D01*
X628701Y267060D01*
G01X631093Y267352D02*
X630760Y267269D01*
X630510Y267060D01*
X630343Y266810D01*
X630218Y266477D01*
X630176Y266102D01*
X630218Y265727D01*
X630343Y265394D01*
X630510Y265144D01*
X630760Y264935D01*
X631093Y264852D01*
X631426Y264935D01*
X631676Y265144D01*
X631843Y265394D01*
X631968Y265727D01*
X632010Y266102D01*
X631968Y266477D01*
X631843Y266810D01*
X631676Y267060D01*
X631426Y267269D01*
X631093Y267352D01*
G01X626913Y242065D02*
X624413D01*
Y243106D01*
X624538Y243440D01*
X624705Y243648D01*
X625038Y243731D01*
X625371Y243648D01*
X625580Y243398D01*
X625705Y243106D01*
Y242065D01*
G01Y243106D02*
X626913Y243731D01*
G01X626413Y245081D02*
X626705Y245331D01*
X626871Y245665D01*
X626913Y246040D01*
X626871Y246373D01*
X626663Y246706D01*
X626413Y246915D01*
X626163Y246956D01*
X625871Y246873D01*
X625663Y246581D01*
X625580Y246290D01*
Y245915D01*
G01Y246290D02*
X625455Y246540D01*
X625246Y246748D01*
X624996Y246831D01*
X624746Y246748D01*
X624538Y246540D01*
X624413Y246165D01*
X624455Y245790D01*
X624621Y245415D01*
G01X626913Y249931D02*
Y248265D01*
X624413D01*
Y249931D01*
G01X625621Y249265D02*
Y248265D01*
G01X626913Y252198D02*
X624413D01*
X624913Y251698D01*
G01X626913D02*
Y252698D01*
G01X612474Y250947D02*
X609974D01*
Y251988D01*
X610099Y252322D01*
X610266Y252530D01*
X610599Y252613D01*
X610932Y252530D01*
X611141Y252280D01*
X611266Y251988D01*
Y250947D01*
G01Y251988D02*
X612474Y252613D01*
G01Y255380D02*
X609974D01*
X611766Y253838D01*
Y255922D01*
G01X612474Y258813D02*
Y257147D01*
X609974D01*
Y258813D01*
G01X611182Y258147D02*
Y257147D01*
G01X612474Y260997D02*
X611932Y261080D01*
X611474Y261205D01*
X611057Y261372D01*
X610599Y261580D01*
X609974Y261913D01*
Y260247D01*
G01X620088Y242770D02*
X619963Y242520D01*
X619880Y242228D01*
Y241895D01*
X620005Y241520D01*
X620213Y241228D01*
X620463Y241020D01*
X620880Y240853D01*
X621255Y240811D01*
X621630Y240895D01*
X621880Y241020D01*
X622130Y241270D01*
X622297Y241561D01*
X622380Y241853D01*
Y242145D01*
X622297Y242436D01*
X622172Y242686D01*
X622005Y242895D01*
G01X622380Y244870D02*
X621838Y244953D01*
X621380Y245078D01*
X620963Y245245D01*
X620505Y245453D01*
X619880Y245786D01*
Y244120D01*
G01X622380Y247220D02*
X619880D01*
Y248261D01*
X620005Y248595D01*
X620172Y248803D01*
X620505Y248886D01*
X620838Y248803D01*
X621047Y248553D01*
X621172Y248261D01*
Y247220D01*
G01Y248261D02*
X622380Y248886D01*
G01Y251153D02*
X619880D01*
X620380Y250653D01*
G01X622380D02*
Y251653D01*
G01X617399Y230211D02*
X617274Y229961D01*
X617191Y229669D01*
Y229336D01*
X617316Y228961D01*
X617524Y228669D01*
X617774Y228461D01*
X618191Y228294D01*
X618566Y228252D01*
X618941Y228336D01*
X619191Y228461D01*
X619441Y228711D01*
X619608Y229002D01*
X619691Y229294D01*
Y229586D01*
X619608Y229877D01*
X619483Y230127D01*
X619316Y230336D01*
G01X619191Y231477D02*
X619483Y231727D01*
X619649Y232061D01*
X619691Y232436D01*
X619649Y232769D01*
X619441Y233102D01*
X619191Y233311D01*
X618941Y233352D01*
X618649Y233269D01*
X618441Y232977D01*
X618358Y232686D01*
Y232311D01*
G01Y232686D02*
X618233Y232936D01*
X618024Y233144D01*
X617774Y233227D01*
X617524Y233144D01*
X617316Y232936D01*
X617191Y232561D01*
X617233Y232186D01*
X617399Y231811D01*
G01X619691Y236327D02*
Y234661D01*
X617191D01*
Y236327D01*
G01X618399Y235661D02*
Y234661D01*
G01X619691Y238594D02*
X617191D01*
X617691Y238094D01*
G01X619691D02*
Y239094D01*
G01X620110Y281047D02*
X619860Y281172D01*
X619568Y281255D01*
X619235D01*
X618860Y281130D01*
X618568Y280922D01*
X618360Y280672D01*
X618193Y280255D01*
X618151Y279880D01*
X618235Y279505D01*
X618360Y279255D01*
X618610Y279005D01*
X618901Y278838D01*
X619193Y278755D01*
X619485D01*
X619776Y278838D01*
X620026Y278963D01*
X620235Y279130D01*
G01X622793Y278755D02*
Y281255D01*
X621251Y279463D01*
X623335D01*
G01X624476Y278755D02*
Y281255D01*
X625310D01*
X625643Y281130D01*
X625893Y280963D01*
X626101Y280713D01*
X626268Y280422D01*
X626310Y280005D01*
X626268Y279588D01*
X626101Y279297D01*
X625893Y279047D01*
X625643Y278880D01*
X625310Y278755D01*
X624476D01*
G01X627576Y279255D02*
X627826Y278963D01*
X628160Y278797D01*
X628535Y278755D01*
X628868Y278797D01*
X629201Y279005D01*
X629410Y279255D01*
X629451Y279505D01*
X629368Y279797D01*
X629076Y280005D01*
X628785Y280088D01*
X628410D01*
G01X628785D02*
X629035Y280213D01*
X629243Y280422D01*
X629326Y280672D01*
X629243Y280922D01*
X629035Y281130D01*
X628660Y281255D01*
X628285Y281213D01*
X627910Y281047D01*
G01X630801Y279797D02*
X631093Y280088D01*
X631343Y280255D01*
X631676Y280338D01*
X631968Y280255D01*
X632176Y280088D01*
X632343Y279838D01*
X632385Y279547D01*
X632343Y279297D01*
X632176Y279047D01*
X631926Y278838D01*
X631635Y278755D01*
X631301Y278838D01*
X631010Y279088D01*
X630843Y279463D01*
X630801Y279880D01*
X630885Y280422D01*
X631010Y280713D01*
X631218Y281005D01*
X631510Y281213D01*
X631801Y281255D01*
X632093Y281172D01*
X632301Y280963D01*
G01X619610Y277547D02*
X619360Y277672D01*
X619068Y277755D01*
X618735D01*
X618360Y277630D01*
X618068Y277422D01*
X617860Y277172D01*
X617693Y276755D01*
X617651Y276380D01*
X617735Y276005D01*
X617860Y275755D01*
X618110Y275505D01*
X618401Y275338D01*
X618693Y275255D01*
X618985D01*
X619276Y275338D01*
X619526Y275463D01*
X619735Y275630D01*
G01X622293Y275255D02*
Y277755D01*
X620751Y275963D01*
X622835D01*
G01X623976Y275255D02*
Y277755D01*
X624810D01*
X625143Y277630D01*
X625393Y277463D01*
X625601Y277213D01*
X625768Y276922D01*
X625810Y276505D01*
X625768Y276088D01*
X625601Y275797D01*
X625393Y275547D01*
X625143Y275380D01*
X624810Y275255D01*
X623976D01*
G01X627076Y275755D02*
X627326Y275463D01*
X627660Y275297D01*
X628035Y275255D01*
X628368Y275297D01*
X628701Y275505D01*
X628910Y275755D01*
X628951Y276005D01*
X628868Y276297D01*
X628576Y276505D01*
X628285Y276588D01*
X627910D01*
G01X628285D02*
X628535Y276713D01*
X628743Y276922D01*
X628826Y277172D01*
X628743Y277422D01*
X628535Y277630D01*
X628160Y277755D01*
X627785Y277713D01*
X627410Y277547D01*
G01X631093Y275255D02*
X631385Y275297D01*
X631718Y275422D01*
X631926Y275630D01*
X632010Y275922D01*
X631926Y276213D01*
X631676Y276463D01*
X631301Y276588D01*
X630885D01*
X630635Y276672D01*
X630426Y276880D01*
X630343Y277172D01*
X630468Y277463D01*
X630760Y277672D01*
X631093Y277755D01*
X631426Y277672D01*
X631718Y277463D01*
X631843Y277172D01*
X631760Y276880D01*
X631551Y276672D01*
X631301Y276588D01*
X630885D01*
X630510Y276463D01*
X630260Y276213D01*
X630176Y275922D01*
X630260Y275630D01*
X630468Y275422D01*
X630801Y275297D01*
X631093Y275255D01*
G01X619610Y274047D02*
X619360Y274172D01*
X619068Y274255D01*
X618735D01*
X618360Y274130D01*
X618068Y273922D01*
X617860Y273672D01*
X617693Y273255D01*
X617651Y272880D01*
X617735Y272505D01*
X617860Y272255D01*
X618110Y272005D01*
X618401Y271838D01*
X618693Y271755D01*
X618985D01*
X619276Y271838D01*
X619526Y271963D01*
X619735Y272130D01*
G01X622293Y271755D02*
Y274255D01*
X620751Y272463D01*
X622835D01*
G01X623976Y271755D02*
Y274255D01*
X624810D01*
X625143Y274130D01*
X625393Y273963D01*
X625601Y273713D01*
X625768Y273422D01*
X625810Y273005D01*
X625768Y272588D01*
X625601Y272297D01*
X625393Y272047D01*
X625143Y271880D01*
X624810Y271755D01*
X623976D01*
G01X628493D02*
Y274255D01*
X626951Y272463D01*
X629035D01*
G01X631093Y274255D02*
X630760Y274172D01*
X630510Y273963D01*
X630343Y273713D01*
X630218Y273380D01*
X630176Y273005D01*
X630218Y272630D01*
X630343Y272297D01*
X630510Y272047D01*
X630760Y271838D01*
X631093Y271755D01*
X631426Y271838D01*
X631676Y272047D01*
X631843Y272297D01*
X631968Y272630D01*
X632010Y273005D01*
X631968Y273380D01*
X631843Y273713D01*
X631676Y273963D01*
X631426Y274172D01*
X631093Y274255D01*
G01X658642Y228976D02*
X658392Y229101D01*
X658100Y229184D01*
X657767D01*
X657392Y229059D01*
X657100Y228851D01*
X656892Y228601D01*
X656725Y228184D01*
X656683Y227809D01*
X656767Y227434D01*
X656892Y227184D01*
X657142Y226934D01*
X657433Y226767D01*
X657725Y226684D01*
X658017D01*
X658308Y226767D01*
X658558Y226892D01*
X658767Y227059D01*
G01X660825Y229184D02*
Y226684D01*
G01X659867Y229184D02*
X661783D01*
G01X663133Y227726D02*
X663425Y228017D01*
X663675Y228184D01*
X664008Y228267D01*
X664300Y228184D01*
X664508Y228017D01*
X664675Y227767D01*
X664717Y227476D01*
X664675Y227226D01*
X664508Y226976D01*
X664258Y226767D01*
X663967Y226684D01*
X663633Y226767D01*
X663342Y227017D01*
X663175Y227392D01*
X663133Y227809D01*
X663217Y228351D01*
X663342Y228642D01*
X663550Y228934D01*
X663842Y229142D01*
X664133Y229184D01*
X664425Y229101D01*
X664633Y228892D01*
G01X666233Y228767D02*
X666483Y229017D01*
X666775Y229142D01*
X667108Y229184D01*
X667525Y229101D01*
X667817Y228892D01*
X667900Y228642D01*
X667858Y228392D01*
X667692Y228184D01*
X666858Y227767D01*
X666483Y227476D01*
X666233Y227059D01*
X666150Y226684D01*
X667900D01*
G01X614131Y248617D02*
X614006Y248367D01*
X613923Y248075D01*
Y247742D01*
X614048Y247367D01*
X614256Y247075D01*
X614506Y246867D01*
X614923Y246700D01*
X615298Y246658D01*
X615673Y246742D01*
X615923Y246867D01*
X616173Y247117D01*
X616340Y247408D01*
X616423Y247700D01*
Y247992D01*
X616340Y248283D01*
X616215Y248533D01*
X616048Y248742D01*
G01X616423Y251300D02*
X613923D01*
X615715Y249758D01*
Y251842D01*
G01X616423Y252983D02*
X613923D01*
Y253817D01*
X614048Y254150D01*
X614215Y254400D01*
X614465Y254608D01*
X614756Y254775D01*
X615173Y254817D01*
X615590Y254775D01*
X615881Y254608D01*
X616131Y254400D01*
X616298Y254150D01*
X616423Y253817D01*
Y252983D01*
G01Y257500D02*
X613923D01*
X615715Y255958D01*
Y258042D01*
G01X616423Y260600D02*
X613923D01*
X615715Y259058D01*
Y261142D01*
G01X619610Y260047D02*
X619360Y260172D01*
X619068Y260255D01*
X618735D01*
X618360Y260130D01*
X618068Y259922D01*
X617860Y259672D01*
X617693Y259255D01*
X617651Y258880D01*
X617735Y258505D01*
X617860Y258255D01*
X618110Y258005D01*
X618401Y257838D01*
X618693Y257755D01*
X618985D01*
X619276Y257838D01*
X619526Y257963D01*
X619735Y258130D01*
G01X622293Y257755D02*
Y260255D01*
X620751Y258463D01*
X622835D01*
G01X623643Y260255D02*
X624226Y257755D01*
X624893Y260255D01*
X625560Y257755D01*
X626143Y260255D01*
G01X627201Y259838D02*
X627451Y260088D01*
X627743Y260213D01*
X628076Y260255D01*
X628493Y260172D01*
X628785Y259963D01*
X628868Y259713D01*
X628826Y259463D01*
X628660Y259255D01*
X627826Y258838D01*
X627451Y258547D01*
X627201Y258130D01*
X627118Y257755D01*
X628868D01*
G01X624646Y239348D02*
X624396Y239473D01*
X624104Y239556D01*
X623771D01*
X623396Y239431D01*
X623104Y239223D01*
X622896Y238973D01*
X622729Y238556D01*
X622687Y238181D01*
X622771Y237806D01*
X622896Y237556D01*
X623146Y237306D01*
X623437Y237139D01*
X623729Y237056D01*
X624021D01*
X624312Y237139D01*
X624562Y237264D01*
X624771Y237431D01*
G01X627329Y237056D02*
Y239556D01*
X625787Y237764D01*
X627871D01*
G01X630762Y237056D02*
X629096D01*
Y239556D01*
X630762D01*
G01X630096Y238348D02*
X629096D01*
G01X632946Y237056D02*
X633029Y237598D01*
X633154Y238056D01*
X633321Y238473D01*
X633529Y238931D01*
X633862Y239556D01*
X632196D01*
G01X643136Y233600D02*
Y229809D01*
X655932D01*
Y233600D01*
G01X643136Y246200D02*
Y249762D01*
X655932D01*
Y246200D01*
G01X678500Y230900D02*
X655928D01*
G01X678500Y248900D02*
X655925D01*
G01X615826Y269675D02*
Y268009D01*
X613326D01*
Y269675D01*
G01X614534Y269009D02*
Y268009D01*
G01X613326Y271025D02*
X615118D01*
X615493Y271192D01*
X615743Y271525D01*
X615826Y271942D01*
X615743Y272359D01*
X615493Y272692D01*
X615118Y272859D01*
X613326D01*
G01X615826Y275542D02*
X613326D01*
X615118Y274000D01*
Y276084D01*
G01X615826Y277225D02*
X613326D01*
Y278059D01*
X613451Y278392D01*
X613618Y278642D01*
X613868Y278850D01*
X614159Y279017D01*
X614576Y279059D01*
X614993Y279017D01*
X615284Y278850D01*
X615534Y278642D01*
X615701Y278392D01*
X615826Y278059D01*
Y277225D01*
G01X615451Y280325D02*
X615659Y280575D01*
X615784Y280867D01*
X615826Y281242D01*
X615743Y281617D01*
X615576Y281909D01*
X615284Y282117D01*
X614951Y282159D01*
X614618Y282075D01*
X614409Y281867D01*
X614243Y281575D01*
X614201Y281284D01*
X614243Y280992D01*
X614409Y280617D01*
X613326Y280742D01*
Y281867D01*
G01X678150Y275050D02*
Y250950D01*
X654050D01*
Y275050D01*
X678150D01*
G01X656061Y271967D02*
Y273039D01*
G01X657307Y252961D02*
X656061D01*
Y254143D01*
G01Y273039D02*
X657174D01*
G01X641234Y219545D02*
Y225593D01*
X678634D01*
Y219545D01*
G01X611000Y372200D02*
X618400D01*
Y353600D01*
X626200D01*
Y336100D01*
X636100D01*
Y350741D01*
X636101Y350742D01*
X640106D01*
Y363340D01*
X658441D01*
G01X623643Y307928D02*
X621143D01*
Y308969D01*
X621268Y309303D01*
X621435Y309511D01*
X621768Y309594D01*
X622101Y309511D01*
X622310Y309261D01*
X622435Y308969D01*
Y307928D01*
G01Y308969D02*
X623643Y309594D01*
G01Y312361D02*
X621143D01*
X622935Y310819D01*
Y312903D01*
G01X623643Y314044D02*
X621143D01*
Y314878D01*
X621268Y315211D01*
X621435Y315461D01*
X621685Y315669D01*
X621976Y315836D01*
X622393Y315878D01*
X622810Y315836D01*
X623101Y315669D01*
X623351Y315461D01*
X623518Y315211D01*
X623643Y314878D01*
Y314044D01*
G01X623143Y317144D02*
X623435Y317394D01*
X623601Y317728D01*
X623643Y318103D01*
X623601Y318436D01*
X623393Y318769D01*
X623143Y318978D01*
X622893Y319019D01*
X622601Y318936D01*
X622393Y318644D01*
X622310Y318353D01*
Y317978D01*
G01Y318353D02*
X622185Y318603D01*
X621976Y318811D01*
X621726Y318894D01*
X621476Y318811D01*
X621268Y318603D01*
X621143Y318228D01*
X621185Y317853D01*
X621351Y317478D01*
G01X623268Y320244D02*
X623476Y320494D01*
X623601Y320786D01*
X623643Y321161D01*
X623560Y321536D01*
X623393Y321828D01*
X623101Y322036D01*
X622768Y322078D01*
X622435Y321994D01*
X622226Y321786D01*
X622060Y321494D01*
X622018Y321203D01*
X622060Y320911D01*
X622226Y320536D01*
X621143Y320661D01*
Y321786D01*
G01X635598Y306267D02*
X633098D01*
Y307308D01*
X633223Y307642D01*
X633390Y307850D01*
X633723Y307933D01*
X634056Y307850D01*
X634265Y307600D01*
X634390Y307308D01*
Y306267D01*
G01Y307308D02*
X635598Y307933D01*
G01Y310700D02*
X633098D01*
X634890Y309158D01*
Y311242D01*
G01X635598Y312383D02*
X633098D01*
Y313217D01*
X633223Y313550D01*
X633390Y313800D01*
X633640Y314008D01*
X633931Y314175D01*
X634348Y314217D01*
X634765Y314175D01*
X635056Y314008D01*
X635306Y313800D01*
X635473Y313550D01*
X635598Y313217D01*
Y312383D01*
G01X635098Y315483D02*
X635390Y315733D01*
X635556Y316067D01*
X635598Y316442D01*
X635556Y316775D01*
X635348Y317108D01*
X635098Y317317D01*
X634848Y317358D01*
X634556Y317275D01*
X634348Y316983D01*
X634265Y316692D01*
Y316317D01*
G01Y316692D02*
X634140Y316942D01*
X633931Y317150D01*
X633681Y317233D01*
X633431Y317150D01*
X633223Y316942D01*
X633098Y316567D01*
X633140Y316192D01*
X633306Y315817D01*
G01X635598Y319500D02*
X635556Y319792D01*
X635431Y320125D01*
X635223Y320333D01*
X634931Y320417D01*
X634640Y320333D01*
X634390Y320083D01*
X634265Y319708D01*
Y319292D01*
X634181Y319042D01*
X633973Y318833D01*
X633681Y318750D01*
X633390Y318875D01*
X633181Y319167D01*
X633098Y319500D01*
X633181Y319833D01*
X633390Y320125D01*
X633681Y320250D01*
X633973Y320167D01*
X634181Y319958D01*
X634265Y319708D01*
Y319292D01*
X634390Y318917D01*
X634640Y318667D01*
X634931Y318583D01*
X635223Y318667D01*
X635431Y318875D01*
X635556Y319208D01*
X635598Y319500D01*
G01X618360Y282255D02*
Y284755D01*
X619401D01*
X619735Y284630D01*
X619943Y284463D01*
X620026Y284130D01*
X619943Y283797D01*
X619693Y283588D01*
X619401Y283463D01*
X618360D01*
G01X619401D02*
X620026Y282255D01*
G01X622793D02*
Y284755D01*
X621251Y282963D01*
X623335D01*
G01X624476Y282255D02*
Y284755D01*
X625310D01*
X625643Y284630D01*
X625893Y284463D01*
X626101Y284213D01*
X626268Y283922D01*
X626310Y283505D01*
X626268Y283088D01*
X626101Y282797D01*
X625893Y282547D01*
X625643Y282380D01*
X625310Y282255D01*
X624476D01*
G01X628993D02*
Y284755D01*
X627451Y282963D01*
X629535D01*
G01X631510Y282255D02*
X631593Y282797D01*
X631718Y283255D01*
X631885Y283672D01*
X632093Y284130D01*
X632426Y284755D01*
X630760D01*
G01X603321Y324077D02*
Y326577D01*
X604362D01*
X604696Y326452D01*
X604904Y326285D01*
X604987Y325952D01*
X604904Y325619D01*
X604654Y325410D01*
X604362Y325285D01*
X603321D01*
G01X604362D02*
X604987Y324077D01*
G01X607754D02*
Y326577D01*
X606212Y324785D01*
X608296D01*
G01X609437Y324077D02*
Y326577D01*
X610271D01*
X610604Y326452D01*
X610854Y326285D01*
X611062Y326035D01*
X611229Y325744D01*
X611271Y325327D01*
X611229Y324910D01*
X611062Y324619D01*
X610854Y324369D01*
X610604Y324202D01*
X610271Y324077D01*
X609437D01*
G01X612662Y326160D02*
X612912Y326410D01*
X613204Y326535D01*
X613537Y326577D01*
X613954Y326494D01*
X614246Y326285D01*
X614329Y326035D01*
X614287Y325785D01*
X614121Y325577D01*
X613287Y325160D01*
X612912Y324869D01*
X612662Y324452D01*
X612579Y324077D01*
X614329D01*
G01X616554D02*
X616846Y324119D01*
X617179Y324244D01*
X617387Y324452D01*
X617471Y324744D01*
X617387Y325035D01*
X617137Y325285D01*
X616762Y325410D01*
X616346D01*
X616096Y325494D01*
X615887Y325702D01*
X615804Y325994D01*
X615929Y326285D01*
X616221Y326494D01*
X616554Y326577D01*
X616887Y326494D01*
X617179Y326285D01*
X617304Y325994D01*
X617221Y325702D01*
X617012Y325494D01*
X616762Y325410D01*
X616346D01*
X615971Y325285D01*
X615721Y325035D01*
X615637Y324744D01*
X615721Y324452D01*
X615929Y324244D01*
X616262Y324119D01*
X616554Y324077D01*
G01X603321Y338077D02*
Y340577D01*
X604362D01*
X604696Y340452D01*
X604904Y340285D01*
X604987Y339952D01*
X604904Y339619D01*
X604654Y339410D01*
X604362Y339285D01*
X603321D01*
G01X604362D02*
X604987Y338077D01*
G01X607754D02*
Y340577D01*
X606212Y338785D01*
X608296D01*
G01X609437Y338077D02*
Y340577D01*
X610271D01*
X610604Y340452D01*
X610854Y340285D01*
X611062Y340035D01*
X611229Y339744D01*
X611271Y339327D01*
X611229Y338910D01*
X611062Y338619D01*
X610854Y338369D01*
X610604Y338202D01*
X610271Y338077D01*
X609437D01*
G01X613454D02*
Y340577D01*
X612954Y340077D01*
G01Y338077D02*
X613954D01*
G01X615762Y339119D02*
X616054Y339410D01*
X616304Y339577D01*
X616637Y339660D01*
X616929Y339577D01*
X617137Y339410D01*
X617304Y339160D01*
X617346Y338869D01*
X617304Y338619D01*
X617137Y338369D01*
X616887Y338160D01*
X616596Y338077D01*
X616262Y338160D01*
X615971Y338410D01*
X615804Y338785D01*
X615762Y339202D01*
X615846Y339744D01*
X615971Y340035D01*
X616179Y340327D01*
X616471Y340535D01*
X616762Y340577D01*
X617054Y340494D01*
X617262Y340285D01*
G01X603321Y341577D02*
Y344077D01*
X604362D01*
X604696Y343952D01*
X604904Y343785D01*
X604987Y343452D01*
X604904Y343119D01*
X604654Y342910D01*
X604362Y342785D01*
X603321D01*
G01X604362D02*
X604987Y341577D01*
G01X607754D02*
Y344077D01*
X606212Y342285D01*
X608296D01*
G01X609437Y341577D02*
Y344077D01*
X610271D01*
X610604Y343952D01*
X610854Y343785D01*
X611062Y343535D01*
X611229Y343244D01*
X611271Y342827D01*
X611229Y342410D01*
X611062Y342119D01*
X610854Y341869D01*
X610604Y341702D01*
X610271Y341577D01*
X609437D01*
G01X613454D02*
Y344077D01*
X612954Y343577D01*
G01Y341577D02*
X613954D01*
G01X615637Y342077D02*
X615887Y341785D01*
X616221Y341619D01*
X616596Y341577D01*
X616929Y341619D01*
X617262Y341827D01*
X617471Y342077D01*
X617512Y342327D01*
X617429Y342619D01*
X617137Y342827D01*
X616846Y342910D01*
X616471D01*
G01X616846D02*
X617096Y343035D01*
X617304Y343244D01*
X617387Y343494D01*
X617304Y343744D01*
X617096Y343952D01*
X616721Y344077D01*
X616346Y344035D01*
X615971Y343869D01*
G01X608364Y287384D02*
X605864D01*
Y288425D01*
X605989Y288759D01*
X606156Y288967D01*
X606489Y289050D01*
X606822Y288967D01*
X607031Y288717D01*
X607156Y288425D01*
Y287384D01*
G01Y288425D02*
X608364Y289050D01*
G01Y291817D02*
X605864D01*
X607656Y290275D01*
Y292359D01*
G01X608364Y293500D02*
X605864D01*
Y294334D01*
X605989Y294667D01*
X606156Y294917D01*
X606406Y295125D01*
X606697Y295292D01*
X607114Y295334D01*
X607531Y295292D01*
X607822Y295125D01*
X608072Y294917D01*
X608239Y294667D01*
X608364Y294334D01*
Y293500D01*
G01Y298017D02*
X605864D01*
X607656Y296475D01*
Y298559D01*
G01X607322Y299825D02*
X607031Y300117D01*
X606864Y300367D01*
X606781Y300700D01*
X606864Y300992D01*
X607031Y301200D01*
X607281Y301367D01*
X607572Y301409D01*
X607822Y301367D01*
X608072Y301200D01*
X608281Y300950D01*
X608364Y300659D01*
X608281Y300325D01*
X608031Y300034D01*
X607656Y299867D01*
X607239Y299825D01*
X606697Y299909D01*
X606406Y300034D01*
X606114Y300242D01*
X605906Y300534D01*
X605864Y300825D01*
X605947Y301117D01*
X606156Y301325D01*
G01X611864Y287384D02*
X609364D01*
Y288425D01*
X609489Y288759D01*
X609656Y288967D01*
X609989Y289050D01*
X610322Y288967D01*
X610531Y288717D01*
X610656Y288425D01*
Y287384D01*
G01Y288425D02*
X611864Y289050D01*
G01Y291817D02*
X609364D01*
X611156Y290275D01*
Y292359D01*
G01X611864Y293500D02*
X609364D01*
Y294334D01*
X609489Y294667D01*
X609656Y294917D01*
X609906Y295125D01*
X610197Y295292D01*
X610614Y295334D01*
X611031Y295292D01*
X611322Y295125D01*
X611572Y294917D01*
X611739Y294667D01*
X611864Y294334D01*
Y293500D01*
G01Y298017D02*
X609364D01*
X611156Y296475D01*
Y298559D01*
G01X609781Y299825D02*
X609531Y300075D01*
X609406Y300367D01*
X609364Y300700D01*
X609447Y301117D01*
X609656Y301409D01*
X609906Y301492D01*
X610156Y301450D01*
X610364Y301284D01*
X610781Y300450D01*
X611072Y300075D01*
X611489Y299825D01*
X611864Y299742D01*
Y301492D01*
G01X603321Y334577D02*
Y337077D01*
X604362D01*
X604696Y336952D01*
X604904Y336785D01*
X604987Y336452D01*
X604904Y336119D01*
X604654Y335910D01*
X604362Y335785D01*
X603321D01*
G01X604362D02*
X604987Y334577D01*
G01X607754D02*
Y337077D01*
X606212Y335285D01*
X608296D01*
G01X609437Y334577D02*
Y337077D01*
X610271D01*
X610604Y336952D01*
X610854Y336785D01*
X611062Y336535D01*
X611229Y336244D01*
X611271Y335827D01*
X611229Y335410D01*
X611062Y335119D01*
X610854Y334869D01*
X610604Y334702D01*
X610271Y334577D01*
X609437D01*
G01X613454D02*
Y337077D01*
X612954Y336577D01*
G01Y334577D02*
X613954D01*
G01X615846Y334869D02*
X616137Y334660D01*
X616471Y334577D01*
X616804Y334660D01*
X617096Y334910D01*
X617304Y335285D01*
X617387Y335660D01*
Y336119D01*
X617304Y336494D01*
X617096Y336827D01*
X616846Y336994D01*
X616554Y337077D01*
X616221Y336994D01*
X615971Y336827D01*
X615804Y336577D01*
X615721Y336244D01*
X615804Y335952D01*
X616012Y335660D01*
X616262Y335494D01*
X616554Y335452D01*
X616887Y335535D01*
X617137Y335744D01*
X617387Y336119D01*
G01X603321Y327577D02*
Y330077D01*
X604362D01*
X604696Y329952D01*
X604904Y329785D01*
X604987Y329452D01*
X604904Y329119D01*
X604654Y328910D01*
X604362Y328785D01*
X603321D01*
G01X604362D02*
X604987Y327577D01*
G01X607754D02*
Y330077D01*
X606212Y328285D01*
X608296D01*
G01X609437Y327577D02*
Y330077D01*
X610271D01*
X610604Y329952D01*
X610854Y329785D01*
X611062Y329535D01*
X611229Y329244D01*
X611271Y328827D01*
X611229Y328410D01*
X611062Y328119D01*
X610854Y327869D01*
X610604Y327702D01*
X610271Y327577D01*
X609437D01*
G01X612662Y329660D02*
X612912Y329910D01*
X613204Y330035D01*
X613537Y330077D01*
X613954Y329994D01*
X614246Y329785D01*
X614329Y329535D01*
X614287Y329285D01*
X614121Y329077D01*
X613287Y328660D01*
X612912Y328369D01*
X612662Y327952D01*
X612579Y327577D01*
X614329D01*
G01X615637Y328077D02*
X615887Y327785D01*
X616221Y327619D01*
X616596Y327577D01*
X616929Y327619D01*
X617262Y327827D01*
X617471Y328077D01*
X617512Y328327D01*
X617429Y328619D01*
X617137Y328827D01*
X616846Y328910D01*
X616471D01*
G01X616846D02*
X617096Y329035D01*
X617304Y329244D01*
X617387Y329494D01*
X617304Y329744D01*
X617096Y329952D01*
X616721Y330077D01*
X616346Y330035D01*
X615971Y329869D01*
G01X603321Y331077D02*
Y333577D01*
X604362D01*
X604696Y333452D01*
X604904Y333285D01*
X604987Y332952D01*
X604904Y332619D01*
X604654Y332410D01*
X604362Y332285D01*
X603321D01*
G01X604362D02*
X604987Y331077D01*
G01X607754D02*
Y333577D01*
X606212Y331785D01*
X608296D01*
G01X609437Y331077D02*
Y333577D01*
X610271D01*
X610604Y333452D01*
X610854Y333285D01*
X611062Y333035D01*
X611229Y332744D01*
X611271Y332327D01*
X611229Y331910D01*
X611062Y331619D01*
X610854Y331369D01*
X610604Y331202D01*
X610271Y331077D01*
X609437D01*
G01X612662Y333160D02*
X612912Y333410D01*
X613204Y333535D01*
X613537Y333577D01*
X613954Y333494D01*
X614246Y333285D01*
X614329Y333035D01*
X614287Y332785D01*
X614121Y332577D01*
X613287Y332160D01*
X612912Y331869D01*
X612662Y331452D01*
X612579Y331077D01*
X614329D01*
G01X616554D02*
Y333577D01*
X616054Y333077D01*
G01Y331077D02*
X617054D01*
G01X631197Y311617D02*
X628697D01*
Y312658D01*
X628822Y312992D01*
X628989Y313200D01*
X629322Y313283D01*
X629655Y313200D01*
X629864Y312950D01*
X629989Y312658D01*
Y311617D01*
G01Y312658D02*
X631197Y313283D01*
G01Y316050D02*
X628697D01*
X630489Y314508D01*
Y316592D01*
G01X628697Y317400D02*
X631197Y317983D01*
X628697Y318650D01*
X631197Y319317D01*
X628697Y319900D01*
G01X631197Y322250D02*
X628697D01*
X630489Y320708D01*
Y322792D01*
G01X627198Y311617D02*
X624698D01*
Y312658D01*
X624823Y312992D01*
X624990Y313200D01*
X625323Y313283D01*
X625656Y313200D01*
X625865Y312950D01*
X625990Y312658D01*
Y311617D01*
G01Y312658D02*
X627198Y313283D01*
G01Y316050D02*
X624698D01*
X626490Y314508D01*
Y316592D01*
G01X624698Y317400D02*
X627198Y317983D01*
X624698Y318650D01*
X627198Y319317D01*
X624698Y319900D01*
G01X626698Y320833D02*
X626990Y321083D01*
X627156Y321417D01*
X627198Y321792D01*
X627156Y322125D01*
X626948Y322458D01*
X626698Y322667D01*
X626448Y322708D01*
X626156Y322625D01*
X625948Y322333D01*
X625865Y322042D01*
Y321667D01*
G01Y322042D02*
X625740Y322292D01*
X625531Y322500D01*
X625281Y322583D01*
X625031Y322500D01*
X624823Y322292D01*
X624698Y321917D01*
X624740Y321542D01*
X624906Y321167D01*
G01X604358Y311129D02*
X601858D01*
Y312170D01*
X601983Y312504D01*
X602150Y312712D01*
X602483Y312795D01*
X602816Y312712D01*
X603025Y312462D01*
X603150Y312170D01*
Y311129D01*
G01Y312170D02*
X604358Y312795D01*
G01Y315562D02*
X601858D01*
X603650Y314020D01*
Y316104D01*
G01X601858Y316912D02*
X604358Y317495D01*
X601858Y318162D01*
X604358Y318829D01*
X601858Y319412D01*
G01X603983Y320345D02*
X604191Y320595D01*
X604316Y320887D01*
X604358Y321262D01*
X604275Y321637D01*
X604108Y321929D01*
X603816Y322137D01*
X603483Y322179D01*
X603150Y322095D01*
X602941Y321887D01*
X602775Y321595D01*
X602733Y321304D01*
X602775Y321012D01*
X602941Y320637D01*
X601858Y320762D01*
Y321887D01*
G01X619472Y289334D02*
X619347Y289084D01*
X619264Y288792D01*
Y288459D01*
X619389Y288084D01*
X619597Y287792D01*
X619847Y287584D01*
X620264Y287417D01*
X620639Y287375D01*
X621014Y287459D01*
X621264Y287584D01*
X621514Y287834D01*
X621681Y288125D01*
X621764Y288417D01*
Y288709D01*
X621681Y289000D01*
X621556Y289250D01*
X621389Y289459D01*
G01X621764Y292017D02*
X619264D01*
X621056Y290475D01*
Y292559D01*
G01X621764Y293700D02*
X619264D01*
Y294534D01*
X619389Y294867D01*
X619556Y295117D01*
X619806Y295325D01*
X620097Y295492D01*
X620514Y295534D01*
X620931Y295492D01*
X621222Y295325D01*
X621472Y295117D01*
X621639Y294867D01*
X621764Y294534D01*
Y293700D01*
G01X621264Y296800D02*
X621556Y297050D01*
X621722Y297384D01*
X621764Y297759D01*
X621722Y298092D01*
X621514Y298425D01*
X621264Y298634D01*
X621014Y298675D01*
X620722Y298592D01*
X620514Y298300D01*
X620431Y298009D01*
Y297634D01*
G01Y298009D02*
X620306Y298259D01*
X620097Y298467D01*
X619847Y298550D01*
X619597Y298467D01*
X619389Y298259D01*
X619264Y297884D01*
X619306Y297509D01*
X619472Y297134D01*
G01X619681Y300025D02*
X619431Y300275D01*
X619306Y300567D01*
X619264Y300900D01*
X619347Y301317D01*
X619556Y301609D01*
X619806Y301692D01*
X620056Y301650D01*
X620264Y301484D01*
X620681Y300650D01*
X620972Y300275D01*
X621389Y300025D01*
X621764Y299942D01*
Y301692D01*
G01X607617Y319424D02*
X607367Y319549D01*
X607075Y319632D01*
X606742D01*
X606367Y319507D01*
X606075Y319299D01*
X605867Y319049D01*
X605700Y318632D01*
X605658Y318257D01*
X605742Y317882D01*
X605867Y317632D01*
X606117Y317382D01*
X606408Y317215D01*
X606700Y317132D01*
X606992D01*
X607283Y317215D01*
X607533Y317340D01*
X607742Y317507D01*
G01X610300Y317132D02*
Y319632D01*
X608758Y317840D01*
X610842D01*
G01X611983Y317132D02*
Y319632D01*
X612817D01*
X613150Y319507D01*
X613400Y319340D01*
X613608Y319090D01*
X613775Y318799D01*
X613817Y318382D01*
X613775Y317965D01*
X613608Y317674D01*
X613400Y317424D01*
X613150Y317257D01*
X612817Y317132D01*
X611983D01*
G01X615208Y319215D02*
X615458Y319465D01*
X615750Y319590D01*
X616083Y319632D01*
X616500Y319549D01*
X616792Y319340D01*
X616875Y319090D01*
X616833Y318840D01*
X616667Y318632D01*
X615833Y318215D01*
X615458Y317924D01*
X615208Y317507D01*
X615125Y317132D01*
X616875D01*
G01X618308Y319215D02*
X618558Y319465D01*
X618850Y319590D01*
X619183Y319632D01*
X619600Y319549D01*
X619892Y319340D01*
X619975Y319090D01*
X619933Y318840D01*
X619767Y318632D01*
X618933Y318215D01*
X618558Y317924D01*
X618308Y317507D01*
X618225Y317132D01*
X619975D01*
G01X607417Y315423D02*
X607167Y315548D01*
X606875Y315631D01*
X606542D01*
X606167Y315506D01*
X605875Y315298D01*
X605667Y315048D01*
X605500Y314631D01*
X605458Y314256D01*
X605542Y313881D01*
X605667Y313631D01*
X605917Y313381D01*
X606208Y313214D01*
X606500Y313131D01*
X606792D01*
X607083Y313214D01*
X607333Y313339D01*
X607542Y313506D01*
G01X610100Y313131D02*
Y315631D01*
X608558Y313839D01*
X610642D01*
G01X611783Y313131D02*
Y315631D01*
X612617D01*
X612950Y315506D01*
X613200Y315339D01*
X613408Y315089D01*
X613575Y314798D01*
X613617Y314381D01*
X613575Y313964D01*
X613408Y313673D01*
X613200Y313423D01*
X612950Y313256D01*
X612617Y313131D01*
X611783D01*
G01X615008Y315214D02*
X615258Y315464D01*
X615550Y315589D01*
X615883Y315631D01*
X616300Y315548D01*
X616592Y315339D01*
X616675Y315089D01*
X616633Y314839D01*
X616467Y314631D01*
X615633Y314214D01*
X615258Y313923D01*
X615008Y313506D01*
X614925Y313131D01*
X616675D01*
G01X618817D02*
X618900Y313673D01*
X619025Y314131D01*
X619192Y314548D01*
X619400Y315006D01*
X619733Y315631D01*
X618067D01*
G01X615972Y289334D02*
X615847Y289084D01*
X615764Y288792D01*
Y288459D01*
X615889Y288084D01*
X616097Y287792D01*
X616347Y287584D01*
X616764Y287417D01*
X617139Y287375D01*
X617514Y287459D01*
X617764Y287584D01*
X618014Y287834D01*
X618181Y288125D01*
X618264Y288417D01*
Y288709D01*
X618181Y289000D01*
X618056Y289250D01*
X617889Y289459D01*
G01X618264Y292017D02*
X615764D01*
X617556Y290475D01*
Y292559D01*
G01X618264Y293700D02*
X615764D01*
Y294534D01*
X615889Y294867D01*
X616056Y295117D01*
X616306Y295325D01*
X616597Y295492D01*
X617014Y295534D01*
X617431Y295492D01*
X617722Y295325D01*
X617972Y295117D01*
X618139Y294867D01*
X618264Y294534D01*
Y293700D01*
G01X617764Y296800D02*
X618056Y297050D01*
X618222Y297384D01*
X618264Y297759D01*
X618222Y298092D01*
X618014Y298425D01*
X617764Y298634D01*
X617514Y298675D01*
X617222Y298592D01*
X617014Y298300D01*
X616931Y298009D01*
Y297634D01*
G01Y298009D02*
X616806Y298259D01*
X616597Y298467D01*
X616347Y298550D01*
X616097Y298467D01*
X615889Y298259D01*
X615764Y297884D01*
X615806Y297509D01*
X615972Y297134D01*
G01X618264Y300817D02*
X615764D01*
X616264Y300317D01*
G01X618264D02*
Y301317D01*
G01X602572Y289134D02*
X602447Y288884D01*
X602364Y288592D01*
Y288259D01*
X602489Y287884D01*
X602697Y287592D01*
X602947Y287384D01*
X603364Y287217D01*
X603739Y287175D01*
X604114Y287259D01*
X604364Y287384D01*
X604614Y287634D01*
X604781Y287925D01*
X604864Y288217D01*
Y288509D01*
X604781Y288800D01*
X604656Y289050D01*
X604489Y289259D01*
G01X604864Y291817D02*
X602364D01*
X604156Y290275D01*
Y292359D01*
G01X604864Y293500D02*
X602364D01*
Y294334D01*
X602489Y294667D01*
X602656Y294917D01*
X602906Y295125D01*
X603197Y295292D01*
X603614Y295334D01*
X604031Y295292D01*
X604322Y295125D01*
X604572Y294917D01*
X604739Y294667D01*
X604864Y294334D01*
Y293500D01*
G01X604364Y296600D02*
X604656Y296850D01*
X604822Y297184D01*
X604864Y297559D01*
X604822Y297892D01*
X604614Y298225D01*
X604364Y298434D01*
X604114Y298475D01*
X603822Y298392D01*
X603614Y298100D01*
X603531Y297809D01*
Y297434D01*
G01Y297809D02*
X603406Y298059D01*
X603197Y298267D01*
X602947Y298350D01*
X602697Y298267D01*
X602489Y298059D01*
X602364Y297684D01*
X602406Y297309D01*
X602572Y296934D01*
G01X604364Y299700D02*
X604656Y299950D01*
X604822Y300284D01*
X604864Y300659D01*
X604822Y300992D01*
X604614Y301325D01*
X604364Y301534D01*
X604114Y301575D01*
X603822Y301492D01*
X603614Y301200D01*
X603531Y300909D01*
Y300534D01*
G01Y300909D02*
X603406Y301159D01*
X603197Y301367D01*
X602947Y301450D01*
X602697Y301367D01*
X602489Y301159D01*
X602364Y300784D01*
X602406Y300409D01*
X602572Y300034D01*
G01X629333Y299850D02*
X629291Y299517D01*
X629125Y299225D01*
X628875Y298975D01*
X628583Y298808D01*
X628250Y298725D01*
X627916D01*
X627583Y298808D01*
X627291Y298975D01*
X627041Y299225D01*
X626875Y299517D01*
X626833Y299850D01*
X626875Y300183D01*
X627041Y300475D01*
X627291Y300725D01*
X627583Y300892D01*
X627916Y300975D01*
X628250D01*
X628583Y300892D01*
X628875Y300725D01*
X629125Y300475D01*
X629291Y300183D01*
X629333Y299850D01*
G01X628666Y300183D02*
X629333Y300683D01*
G01Y303450D02*
X626833D01*
X628625Y301908D01*
Y303992D01*
G01X626833Y304800D02*
X629333Y305383D01*
X626833Y306050D01*
X629333Y306717D01*
X626833Y307300D01*
G01X629333Y309150D02*
X626833D01*
X627333Y308650D01*
G01X629333D02*
Y309650D01*
G01X632242Y338767D02*
X632117Y338517D01*
X632034Y338225D01*
Y337892D01*
X632159Y337517D01*
X632367Y337225D01*
X632617Y337017D01*
X633034Y336850D01*
X633409Y336808D01*
X633784Y336892D01*
X634034Y337017D01*
X634284Y337267D01*
X634451Y337558D01*
X634534Y337850D01*
Y338142D01*
X634451Y338433D01*
X634326Y338683D01*
X634159Y338892D01*
G01X632451Y340158D02*
X632201Y340408D01*
X632076Y340700D01*
X632034Y341033D01*
X632117Y341450D01*
X632326Y341742D01*
X632576Y341825D01*
X632826Y341783D01*
X633034Y341617D01*
X633451Y340783D01*
X633742Y340408D01*
X634159Y340158D01*
X634534Y340075D01*
Y341825D01*
G01X632451Y343258D02*
X632201Y343508D01*
X632076Y343800D01*
X632034Y344133D01*
X632117Y344550D01*
X632326Y344842D01*
X632576Y344925D01*
X632826Y344883D01*
X633034Y344717D01*
X633451Y343883D01*
X633742Y343508D01*
X634159Y343258D01*
X634534Y343175D01*
Y344925D01*
G01X632034Y345900D02*
X634534Y346483D01*
X632034Y347150D01*
X634534Y347817D01*
X632034Y348400D01*
G01X634534Y350250D02*
X632034D01*
X632534Y349750D01*
G01X634534D02*
Y350750D01*
G01X634034Y352433D02*
X634326Y352683D01*
X634492Y353017D01*
X634534Y353392D01*
X634492Y353725D01*
X634284Y354058D01*
X634034Y354267D01*
X633784Y354308D01*
X633492Y354225D01*
X633284Y353933D01*
X633201Y353642D01*
Y353267D01*
G01Y353642D02*
X633076Y353892D01*
X632867Y354100D01*
X632617Y354183D01*
X632367Y354100D01*
X632159Y353892D01*
X632034Y353517D01*
X632076Y353142D01*
X632242Y352767D01*
G01X628636Y341778D02*
X628511Y341528D01*
X628428Y341236D01*
Y340903D01*
X628553Y340528D01*
X628761Y340236D01*
X629011Y340028D01*
X629428Y339861D01*
X629803Y339819D01*
X630178Y339903D01*
X630428Y340028D01*
X630678Y340278D01*
X630845Y340569D01*
X630928Y340861D01*
Y341153D01*
X630845Y341444D01*
X630720Y341694D01*
X630553Y341903D01*
G01X630928Y344461D02*
X628428D01*
X630220Y342919D01*
Y345003D01*
G01X630928Y347894D02*
Y346228D01*
X628428D01*
Y347894D01*
G01X629636Y347228D02*
Y346228D01*
G01X630928Y350161D02*
X628428D01*
X628928Y349661D01*
G01X630928D02*
Y350661D01*
G01Y353761D02*
X628428D01*
X630220Y352219D01*
Y354303D01*
G01X622061Y327824D02*
Y326158D01*
X619561D01*
Y327824D01*
G01X620769Y327158D02*
Y326158D01*
G01X619561Y329174D02*
X621353D01*
X621728Y329341D01*
X621978Y329674D01*
X622061Y330091D01*
X621978Y330508D01*
X621728Y330841D01*
X621353Y331008D01*
X619561D01*
G01X622061Y333691D02*
X619561D01*
X621353Y332149D01*
Y334233D01*
G01X622061Y335374D02*
X619561D01*
Y336208D01*
X619686Y336541D01*
X619853Y336791D01*
X620103Y336999D01*
X620394Y337166D01*
X620811Y337208D01*
X621228Y337166D01*
X621519Y336999D01*
X621769Y336791D01*
X621936Y336541D01*
X622061Y336208D01*
Y335374D01*
G01X619978Y338599D02*
X619728Y338849D01*
X619603Y339141D01*
X619561Y339474D01*
X619644Y339891D01*
X619853Y340183D01*
X620103Y340266D01*
X620353Y340224D01*
X620561Y340058D01*
X620978Y339224D01*
X621269Y338849D01*
X621686Y338599D01*
X622061Y338516D01*
Y340266D01*
G01X647319Y299048D02*
Y338448D01*
X686719D01*
Y299048D01*
X647319D01*
G01X629857Y396296D02*
X630524Y395596D01*
X631324Y395129D01*
X632257Y394896D01*
X633324Y395129D01*
X634124Y395596D01*
X634924Y396296D01*
X635191Y397229D01*
Y401896D01*
G01X610080Y395860D02*
Y404500D01*
X656650D01*
G01X609580Y373670D02*
Y375700D01*
G01Y379880D02*
Y381720D01*
G01X659300Y365800D02*
Y385350D01*
G01X633590Y357505D02*
X631090D01*
Y358546D01*
X631215Y358880D01*
X631382Y359088D01*
X631715Y359171D01*
X632048Y359088D01*
X632257Y358838D01*
X632382Y358546D01*
Y357505D01*
G01Y358546D02*
X633590Y359171D01*
G01Y361938D02*
X631090D01*
X632882Y360396D01*
Y362480D01*
G01X633590Y365371D02*
Y363705D01*
X631090D01*
Y365371D01*
G01X632298Y364705D02*
Y363705D01*
G01X631507Y366846D02*
X631257Y367096D01*
X631132Y367388D01*
X631090Y367721D01*
X631173Y368138D01*
X631382Y368430D01*
X631632Y368513D01*
X631882Y368471D01*
X632090Y368305D01*
X632507Y367471D01*
X632798Y367096D01*
X633215Y366846D01*
X633590Y366763D01*
Y368513D01*
G01X631090Y370738D02*
X631173Y370405D01*
X631382Y370155D01*
X631632Y369988D01*
X631965Y369863D01*
X632340Y369821D01*
X632715Y369863D01*
X633048Y369988D01*
X633298Y370155D01*
X633507Y370405D01*
X633590Y370738D01*
X633507Y371071D01*
X633298Y371321D01*
X633048Y371488D01*
X632715Y371613D01*
X632340Y371655D01*
X631965Y371613D01*
X631632Y371488D01*
X631382Y371321D01*
X631173Y371071D01*
X631090Y370738D01*
G01X637080Y374097D02*
X634580D01*
Y375138D01*
X634705Y375472D01*
X634872Y375680D01*
X635205Y375763D01*
X635538Y375680D01*
X635747Y375430D01*
X635872Y375138D01*
Y374097D01*
G01Y375138D02*
X637080Y375763D01*
G01Y378530D02*
X634580D01*
X636372Y376988D01*
Y379072D01*
G01X637080Y380213D02*
X634580D01*
Y381047D01*
X634705Y381380D01*
X634872Y381630D01*
X635122Y381838D01*
X635413Y382005D01*
X635830Y382047D01*
X636247Y382005D01*
X636538Y381838D01*
X636788Y381630D01*
X636955Y381380D01*
X637080Y381047D01*
Y380213D01*
G01X636038Y383438D02*
X635747Y383730D01*
X635580Y383980D01*
X635497Y384313D01*
X635580Y384605D01*
X635747Y384813D01*
X635997Y384980D01*
X636288Y385022D01*
X636538Y384980D01*
X636788Y384813D01*
X636997Y384563D01*
X637080Y384272D01*
X636997Y383938D01*
X636747Y383647D01*
X636372Y383480D01*
X635955Y383438D01*
X635413Y383522D01*
X635122Y383647D01*
X634830Y383855D01*
X634622Y384147D01*
X634580Y384438D01*
X634663Y384730D01*
X634872Y384938D01*
G01X637080Y387247D02*
X636538Y387330D01*
X636080Y387455D01*
X635663Y387622D01*
X635205Y387830D01*
X634580Y388163D01*
Y386497D01*
G01X644351Y373573D02*
X641851D01*
Y374614D01*
X641976Y374948D01*
X642143Y375156D01*
X642476Y375239D01*
X642809Y375156D01*
X643018Y374906D01*
X643143Y374614D01*
Y373573D01*
G01Y374614D02*
X644351Y375239D01*
G01Y376714D02*
X641851D01*
Y378298D01*
G01X643059Y377714D02*
Y376714D01*
G01X644351Y380606D02*
X641851D01*
X642351Y380106D01*
G01X644351D02*
Y381106D01*
G01X646117Y364867D02*
Y367367D01*
X647158D01*
X647492Y367242D01*
X647700Y367075D01*
X647783Y366742D01*
X647700Y366409D01*
X647450Y366200D01*
X647158Y366075D01*
X646117D01*
G01X647158D02*
X647783Y364867D01*
G01X650550D02*
Y367367D01*
X649008Y365575D01*
X651092D01*
G01X653983Y364867D02*
X652317D01*
Y367367D01*
X653983D01*
G01X653317Y366159D02*
X652317D01*
G01X656250Y364867D02*
X656542Y364909D01*
X656875Y365034D01*
X657083Y365242D01*
X657167Y365534D01*
X657083Y365825D01*
X656833Y366075D01*
X656458Y366200D01*
X656042D01*
X655792Y366284D01*
X655583Y366492D01*
X655500Y366784D01*
X655625Y367075D01*
X655917Y367284D01*
X656250Y367367D01*
X656583Y367284D01*
X656875Y367075D01*
X657000Y366784D01*
X656917Y366492D01*
X656708Y366284D01*
X656458Y366200D01*
X656042D01*
X655667Y366075D01*
X655417Y365825D01*
X655333Y365534D01*
X655417Y365242D01*
X655625Y365034D01*
X655958Y364909D01*
X656250Y364867D01*
G01X645200Y395682D02*
X642700D01*
Y396723D01*
X642825Y397057D01*
X642992Y397265D01*
X643325Y397348D01*
X643658Y397265D01*
X643867Y397015D01*
X643992Y396723D01*
Y395682D01*
G01Y396723D02*
X645200Y397348D01*
G01Y398823D02*
X642700D01*
Y400407D01*
G01X643908Y399823D02*
Y398823D01*
G01X644825Y401798D02*
X645033Y402048D01*
X645158Y402340D01*
X645200Y402715D01*
X645117Y403090D01*
X644950Y403382D01*
X644658Y403590D01*
X644325Y403632D01*
X643992Y403548D01*
X643783Y403340D01*
X643617Y403048D01*
X643575Y402757D01*
X643617Y402465D01*
X643783Y402090D01*
X642700Y402215D01*
Y403340D01*
G01X653364Y390581D02*
X650864D01*
Y391622D01*
X650989Y391956D01*
X651156Y392164D01*
X651489Y392247D01*
X651822Y392164D01*
X652031Y391914D01*
X652156Y391622D01*
Y390581D01*
G01Y391622D02*
X653364Y392247D01*
G01Y393722D02*
X650864D01*
Y395306D01*
G01X652072Y394722D02*
Y393722D01*
G01X653364Y398114D02*
X650864D01*
X652656Y396572D01*
Y398656D01*
G01X652700Y378067D02*
X650200D01*
Y379108D01*
X650325Y379442D01*
X650492Y379650D01*
X650825Y379733D01*
X651158Y379650D01*
X651367Y379400D01*
X651492Y379108D01*
Y378067D01*
G01Y379108D02*
X652700Y379733D01*
G01Y381208D02*
X650200D01*
Y382792D01*
G01X651408Y382208D02*
Y381208D01*
G01X650617Y384308D02*
X650367Y384558D01*
X650242Y384850D01*
X650200Y385183D01*
X650283Y385600D01*
X650492Y385892D01*
X650742Y385975D01*
X650992Y385933D01*
X651200Y385767D01*
X651617Y384933D01*
X651908Y384558D01*
X652325Y384308D01*
X652700Y384225D01*
Y385975D01*
G01X644634Y383767D02*
X642134D01*
Y384808D01*
X642259Y385142D01*
X642426Y385350D01*
X642759Y385433D01*
X643092Y385350D01*
X643301Y385100D01*
X643426Y384808D01*
Y383767D01*
G01Y384808D02*
X644634Y385433D01*
G01Y386908D02*
X642134D01*
Y388492D01*
G01X643342Y387908D02*
Y386908D01*
G01X644134Y389883D02*
X644426Y390133D01*
X644592Y390467D01*
X644634Y390842D01*
X644592Y391175D01*
X644384Y391508D01*
X644134Y391717D01*
X643884Y391758D01*
X643592Y391675D01*
X643384Y391383D01*
X643301Y391092D01*
Y390717D01*
G01Y391092D02*
X643176Y391342D01*
X642967Y391550D01*
X642717Y391633D01*
X642467Y391550D01*
X642259Y391342D01*
X642134Y390967D01*
X642176Y390592D01*
X642342Y390217D01*
G01X630090Y357505D02*
X627590D01*
Y358546D01*
X627715Y358880D01*
X627882Y359088D01*
X628215Y359171D01*
X628548Y359088D01*
X628757Y358838D01*
X628882Y358546D01*
Y357505D01*
G01Y358546D02*
X630090Y359171D01*
G01Y361938D02*
X627590D01*
X629382Y360396D01*
Y362480D01*
G01X630090Y365371D02*
Y363705D01*
X627590D01*
Y365371D01*
G01X628798Y364705D02*
Y363705D01*
G01X630090Y367638D02*
X627590D01*
X628090Y367138D01*
G01X630090D02*
Y368138D01*
G01X627590Y370738D02*
X627673Y370405D01*
X627882Y370155D01*
X628132Y369988D01*
X628465Y369863D01*
X628840Y369821D01*
X629215Y369863D01*
X629548Y369988D01*
X629798Y370155D01*
X630007Y370405D01*
X630090Y370738D01*
X630007Y371071D01*
X629798Y371321D01*
X629548Y371488D01*
X629215Y371613D01*
X628840Y371655D01*
X628465Y371613D01*
X628132Y371488D01*
X627882Y371321D01*
X627673Y371071D01*
X627590Y370738D01*
G01X626590Y359505D02*
X624090D01*
Y360546D01*
X624215Y360880D01*
X624382Y361088D01*
X624715Y361171D01*
X625048Y361088D01*
X625257Y360838D01*
X625382Y360546D01*
Y359505D01*
G01Y360546D02*
X626590Y361171D01*
G01Y363938D02*
X624090D01*
X625882Y362396D01*
Y364480D01*
G01X626590Y367371D02*
Y365705D01*
X624090D01*
Y367371D01*
G01X625298Y366705D02*
Y365705D01*
G01X626298Y368930D02*
X626507Y369221D01*
X626590Y369555D01*
X626507Y369888D01*
X626257Y370180D01*
X625882Y370388D01*
X625507Y370471D01*
X625048D01*
X624673Y370388D01*
X624340Y370180D01*
X624173Y369930D01*
X624090Y369638D01*
X624173Y369305D01*
X624340Y369055D01*
X624590Y368888D01*
X624923Y368805D01*
X625215Y368888D01*
X625507Y369096D01*
X625673Y369346D01*
X625715Y369638D01*
X625632Y369971D01*
X625423Y370221D01*
X625048Y370471D01*
G01X633480Y374197D02*
X630980D01*
Y375238D01*
X631105Y375572D01*
X631272Y375780D01*
X631605Y375863D01*
X631938Y375780D01*
X632147Y375530D01*
X632272Y375238D01*
Y374197D01*
G01Y375238D02*
X633480Y375863D01*
G01Y378630D02*
X630980D01*
X632772Y377088D01*
Y379172D01*
G01X633480Y380313D02*
X630980D01*
Y381147D01*
X631105Y381480D01*
X631272Y381730D01*
X631522Y381938D01*
X631813Y382105D01*
X632230Y382147D01*
X632647Y382105D01*
X632938Y381938D01*
X633188Y381730D01*
X633355Y381480D01*
X633480Y381147D01*
Y380313D01*
G01X632438Y383538D02*
X632147Y383830D01*
X631980Y384080D01*
X631897Y384413D01*
X631980Y384705D01*
X632147Y384913D01*
X632397Y385080D01*
X632688Y385122D01*
X632938Y385080D01*
X633188Y384913D01*
X633397Y384663D01*
X633480Y384372D01*
X633397Y384038D01*
X633147Y383747D01*
X632772Y383580D01*
X632355Y383538D01*
X631813Y383622D01*
X631522Y383747D01*
X631230Y383955D01*
X631022Y384247D01*
X630980Y384538D01*
X631063Y384830D01*
X631272Y385038D01*
G01X632438Y386638D02*
X632147Y386930D01*
X631980Y387180D01*
X631897Y387513D01*
X631980Y387805D01*
X632147Y388013D01*
X632397Y388180D01*
X632688Y388222D01*
X632938Y388180D01*
X633188Y388013D01*
X633397Y387763D01*
X633480Y387472D01*
X633397Y387138D01*
X633147Y386847D01*
X632772Y386680D01*
X632355Y386638D01*
X631813Y386722D01*
X631522Y386847D01*
X631230Y387055D01*
X631022Y387347D01*
X630980Y387638D01*
X631063Y387930D01*
X631272Y388138D01*
G01X622125Y374113D02*
X619625D01*
Y375154D01*
X619750Y375488D01*
X619917Y375696D01*
X620250Y375779D01*
X620583Y375696D01*
X620792Y375446D01*
X620917Y375154D01*
Y374113D01*
G01Y375154D02*
X622125Y375779D01*
G01Y378546D02*
X619625D01*
X621417Y377004D01*
Y379088D01*
G01X622125Y381979D02*
Y380313D01*
X619625D01*
Y381979D01*
G01X620833Y381313D02*
Y380313D01*
G01X621750Y383329D02*
X621958Y383579D01*
X622083Y383871D01*
X622125Y384246D01*
X622042Y384621D01*
X621875Y384913D01*
X621583Y385121D01*
X621250Y385163D01*
X620917Y385079D01*
X620708Y384871D01*
X620542Y384579D01*
X620500Y384288D01*
X620542Y383996D01*
X620708Y383621D01*
X619625Y383746D01*
Y384871D01*
G01X618425Y374113D02*
X615925D01*
Y375154D01*
X616050Y375488D01*
X616217Y375696D01*
X616550Y375779D01*
X616883Y375696D01*
X617092Y375446D01*
X617217Y375154D01*
Y374113D01*
G01Y375154D02*
X618425Y375779D01*
G01Y378546D02*
X615925D01*
X617717Y377004D01*
Y379088D01*
G01X618425Y381979D02*
Y380313D01*
X615925D01*
Y381979D01*
G01X617133Y381313D02*
Y380313D01*
G01X618425Y384746D02*
X615925D01*
X617717Y383204D01*
Y385288D01*
G01X625934Y374167D02*
X623434D01*
Y375208D01*
X623559Y375542D01*
X623726Y375750D01*
X624059Y375833D01*
X624392Y375750D01*
X624601Y375500D01*
X624726Y375208D01*
Y374167D01*
G01Y375208D02*
X625934Y375833D01*
G01Y378600D02*
X623434D01*
X625226Y377058D01*
Y379142D01*
G01X625934Y380283D02*
X623434D01*
Y381117D01*
X623559Y381450D01*
X623726Y381700D01*
X623976Y381908D01*
X624267Y382075D01*
X624684Y382117D01*
X625101Y382075D01*
X625392Y381908D01*
X625642Y381700D01*
X625809Y381450D01*
X625934Y381117D01*
Y380283D01*
G01X624892Y383508D02*
X624601Y383800D01*
X624434Y384050D01*
X624351Y384383D01*
X624434Y384675D01*
X624601Y384883D01*
X624851Y385050D01*
X625142Y385092D01*
X625392Y385050D01*
X625642Y384883D01*
X625851Y384633D01*
X625934Y384342D01*
X625851Y384008D01*
X625601Y383717D01*
X625226Y383550D01*
X624809Y383508D01*
X624267Y383592D01*
X623976Y383717D01*
X623684Y383925D01*
X623476Y384217D01*
X623434Y384508D01*
X623517Y384800D01*
X623726Y385008D01*
G01X625559Y386483D02*
X625767Y386733D01*
X625892Y387025D01*
X625934Y387400D01*
X625851Y387775D01*
X625684Y388067D01*
X625392Y388275D01*
X625059Y388317D01*
X624726Y388233D01*
X624517Y388025D01*
X624351Y387733D01*
X624309Y387442D01*
X624351Y387150D01*
X624517Y386775D01*
X623434Y386900D01*
Y388025D01*
G01X629734Y374117D02*
X627234D01*
Y375158D01*
X627359Y375492D01*
X627526Y375700D01*
X627859Y375783D01*
X628192Y375700D01*
X628401Y375450D01*
X628526Y375158D01*
Y374117D01*
G01Y375158D02*
X629734Y375783D01*
G01Y378550D02*
X627234D01*
X629026Y377008D01*
Y379092D01*
G01X629734Y381983D02*
Y380317D01*
X627234D01*
Y381983D01*
G01X628442Y381317D02*
Y380317D01*
G01X628692Y383458D02*
X628401Y383750D01*
X628234Y384000D01*
X628151Y384333D01*
X628234Y384625D01*
X628401Y384833D01*
X628651Y385000D01*
X628942Y385042D01*
X629192Y385000D01*
X629442Y384833D01*
X629651Y384583D01*
X629734Y384292D01*
X629651Y383958D01*
X629401Y383667D01*
X629026Y383500D01*
X628609Y383458D01*
X628067Y383542D01*
X627776Y383667D01*
X627484Y383875D01*
X627276Y384167D01*
X627234Y384458D01*
X627317Y384750D01*
X627526Y384958D01*
G01X614725Y374113D02*
X612225D01*
Y375154D01*
X612350Y375488D01*
X612517Y375696D01*
X612850Y375779D01*
X613183Y375696D01*
X613392Y375446D01*
X613517Y375154D01*
Y374113D01*
G01Y375154D02*
X614725Y375779D01*
G01Y378546D02*
X612225D01*
X614017Y377004D01*
Y379088D01*
G01X614725Y381979D02*
Y380313D01*
X612225D01*
Y381979D01*
G01X613433Y381313D02*
Y380313D01*
G01X614225Y383329D02*
X614517Y383579D01*
X614683Y383913D01*
X614725Y384288D01*
X614683Y384621D01*
X614475Y384954D01*
X614225Y385163D01*
X613975Y385204D01*
X613683Y385121D01*
X613475Y384829D01*
X613392Y384538D01*
Y384163D01*
G01Y384538D02*
X613267Y384788D01*
X613058Y384996D01*
X612808Y385079D01*
X612558Y384996D01*
X612350Y384788D01*
X612225Y384413D01*
X612267Y384038D01*
X612433Y383663D01*
G01X612462Y391106D02*
Y393606D01*
X613503D01*
X613837Y393481D01*
X614045Y393314D01*
X614128Y392981D01*
X614045Y392648D01*
X613795Y392439D01*
X613503Y392314D01*
X612462D01*
G01X613503D02*
X614128Y391106D01*
G01X616895D02*
Y393606D01*
X615353Y391814D01*
X617437D01*
G01X618578Y391106D02*
Y393606D01*
X619412D01*
X619745Y393481D01*
X619995Y393314D01*
X620203Y393064D01*
X620370Y392773D01*
X620412Y392356D01*
X620370Y391939D01*
X620203Y391648D01*
X619995Y391398D01*
X619745Y391231D01*
X619412Y391106D01*
X618578D01*
G01X621803Y392148D02*
X622095Y392439D01*
X622345Y392606D01*
X622678Y392689D01*
X622970Y392606D01*
X623178Y392439D01*
X623345Y392189D01*
X623387Y391898D01*
X623345Y391648D01*
X623178Y391398D01*
X622928Y391189D01*
X622637Y391106D01*
X622303Y391189D01*
X622012Y391439D01*
X621845Y391814D01*
X621803Y392231D01*
X621887Y392773D01*
X622012Y393064D01*
X622220Y393356D01*
X622512Y393564D01*
X622803Y393606D01*
X623095Y393523D01*
X623303Y393314D01*
G01X624778Y391606D02*
X625028Y391314D01*
X625362Y391148D01*
X625737Y391106D01*
X626070Y391148D01*
X626403Y391356D01*
X626612Y391606D01*
X626653Y391856D01*
X626570Y392148D01*
X626278Y392356D01*
X625987Y392439D01*
X625612D01*
G01X625987D02*
X626237Y392564D01*
X626445Y392773D01*
X626528Y393023D01*
X626445Y393273D01*
X626237Y393481D01*
X625862Y393606D01*
X625487Y393564D01*
X625112Y393398D01*
G01X612462Y394506D02*
Y397006D01*
X613503D01*
X613837Y396881D01*
X614045Y396714D01*
X614128Y396381D01*
X614045Y396048D01*
X613795Y395839D01*
X613503Y395714D01*
X612462D01*
G01X613503D02*
X614128Y394506D01*
G01X616895D02*
Y397006D01*
X615353Y395214D01*
X617437D01*
G01X618578Y394506D02*
Y397006D01*
X619412D01*
X619745Y396881D01*
X619995Y396714D01*
X620203Y396464D01*
X620370Y396173D01*
X620412Y395756D01*
X620370Y395339D01*
X620203Y395048D01*
X619995Y394798D01*
X619745Y394631D01*
X619412Y394506D01*
X618578D01*
G01X621678Y394881D02*
X621928Y394673D01*
X622220Y394548D01*
X622595Y394506D01*
X622970Y394589D01*
X623262Y394756D01*
X623470Y395048D01*
X623512Y395381D01*
X623428Y395714D01*
X623220Y395923D01*
X622928Y396089D01*
X622637Y396131D01*
X622345Y396089D01*
X621970Y395923D01*
X622095Y397006D01*
X623220D01*
G01X625695Y394506D02*
X625987Y394548D01*
X626320Y394673D01*
X626528Y394881D01*
X626612Y395173D01*
X626528Y395464D01*
X626278Y395714D01*
X625903Y395839D01*
X625487D01*
X625237Y395923D01*
X625028Y396131D01*
X624945Y396423D01*
X625070Y396714D01*
X625362Y396923D01*
X625695Y397006D01*
X626028Y396923D01*
X626320Y396714D01*
X626445Y396423D01*
X626362Y396131D01*
X626153Y395923D01*
X625903Y395839D01*
X625487D01*
X625112Y395714D01*
X624862Y395464D01*
X624778Y395173D01*
X624862Y394881D01*
X625070Y394673D01*
X625403Y394548D01*
X625695Y394506D01*
G01X663033Y348647D02*
X660533D01*
Y349688D01*
X660658Y350022D01*
X660825Y350230D01*
X661158Y350313D01*
X661491Y350230D01*
X661700Y349980D01*
X661825Y349688D01*
Y348647D01*
G01Y349688D02*
X663033Y350313D01*
G01Y353080D02*
X660533D01*
X662325Y351538D01*
Y353622D01*
G01X663033Y354763D02*
X660533D01*
Y355597D01*
X660658Y355930D01*
X660825Y356180D01*
X661075Y356388D01*
X661366Y356555D01*
X661783Y356597D01*
X662200Y356555D01*
X662491Y356388D01*
X662741Y356180D01*
X662908Y355930D01*
X663033Y355597D01*
Y354763D01*
G01Y359280D02*
X660533D01*
X662325Y357738D01*
Y359822D01*
G01X647533Y348847D02*
X645033D01*
Y349888D01*
X645158Y350222D01*
X645325Y350430D01*
X645658Y350513D01*
X645991Y350430D01*
X646200Y350180D01*
X646325Y349888D01*
Y348847D01*
G01Y349888D02*
X647533Y350513D01*
G01Y353280D02*
X645033D01*
X646825Y351738D01*
Y353822D01*
G01X647533Y354963D02*
X645033D01*
Y355797D01*
X645158Y356130D01*
X645325Y356380D01*
X645575Y356588D01*
X645866Y356755D01*
X646283Y356797D01*
X646700Y356755D01*
X646991Y356588D01*
X647241Y356380D01*
X647408Y356130D01*
X647533Y355797D01*
Y354963D01*
G01Y358980D02*
X645033D01*
X645533Y358480D01*
G01X647533D02*
Y359480D01*
G01X652833Y348847D02*
X650333D01*
Y349888D01*
X650458Y350222D01*
X650625Y350430D01*
X650958Y350513D01*
X651291Y350430D01*
X651500Y350180D01*
X651625Y349888D01*
Y348847D01*
G01Y349888D02*
X652833Y350513D01*
G01Y353280D02*
X650333D01*
X652125Y351738D01*
Y353822D01*
G01X652833Y354963D02*
X650333D01*
Y355797D01*
X650458Y356130D01*
X650625Y356380D01*
X650875Y356588D01*
X651166Y356755D01*
X651583Y356797D01*
X652000Y356755D01*
X652291Y356588D01*
X652541Y356380D01*
X652708Y356130D01*
X652833Y355797D01*
Y354963D01*
G01X650750Y358188D02*
X650500Y358438D01*
X650375Y358730D01*
X650333Y359063D01*
X650416Y359480D01*
X650625Y359772D01*
X650875Y359855D01*
X651125Y359813D01*
X651333Y359647D01*
X651750Y358813D01*
X652041Y358438D01*
X652458Y358188D01*
X652833Y358105D01*
Y359855D01*
G01X658033Y348847D02*
X655533D01*
Y349888D01*
X655658Y350222D01*
X655825Y350430D01*
X656158Y350513D01*
X656491Y350430D01*
X656700Y350180D01*
X656825Y349888D01*
Y348847D01*
G01Y349888D02*
X658033Y350513D01*
G01Y353280D02*
X655533D01*
X657325Y351738D01*
Y353822D01*
G01X658033Y354963D02*
X655533D01*
Y355797D01*
X655658Y356130D01*
X655825Y356380D01*
X656075Y356588D01*
X656366Y356755D01*
X656783Y356797D01*
X657200Y356755D01*
X657491Y356588D01*
X657741Y356380D01*
X657908Y356130D01*
X658033Y355797D01*
Y354963D01*
G01X657533Y358063D02*
X657825Y358313D01*
X657991Y358647D01*
X658033Y359022D01*
X657991Y359355D01*
X657783Y359688D01*
X657533Y359897D01*
X657283Y359938D01*
X656991Y359855D01*
X656783Y359563D01*
X656700Y359272D01*
Y358897D01*
G01Y359272D02*
X656575Y359522D01*
X656366Y359730D01*
X656116Y359813D01*
X655866Y359730D01*
X655658Y359522D01*
X655533Y359147D01*
X655575Y358772D01*
X655741Y358397D01*
G01X603321Y348577D02*
Y351077D01*
X604362D01*
X604696Y350952D01*
X604904Y350785D01*
X604987Y350452D01*
X604904Y350119D01*
X604654Y349910D01*
X604362Y349785D01*
X603321D01*
G01X604362D02*
X604987Y348577D01*
G01X607754D02*
Y351077D01*
X606212Y349285D01*
X608296D01*
G01X609437Y348577D02*
Y351077D01*
X610271D01*
X610604Y350952D01*
X610854Y350785D01*
X611062Y350535D01*
X611229Y350244D01*
X611271Y349827D01*
X611229Y349410D01*
X611062Y349119D01*
X610854Y348869D01*
X610604Y348702D01*
X610271Y348577D01*
X609437D01*
G01X612746Y348869D02*
X613037Y348660D01*
X613371Y348577D01*
X613704Y348660D01*
X613996Y348910D01*
X614204Y349285D01*
X614287Y349660D01*
Y350119D01*
X614204Y350494D01*
X613996Y350827D01*
X613746Y350994D01*
X613454Y351077D01*
X613121Y350994D01*
X612871Y350827D01*
X612704Y350577D01*
X612621Y350244D01*
X612704Y349952D01*
X612912Y349660D01*
X613162Y349494D01*
X613454Y349452D01*
X613787Y349535D01*
X614037Y349744D01*
X614287Y350119D01*
G01X603321Y345077D02*
Y347577D01*
X604362D01*
X604696Y347452D01*
X604904Y347285D01*
X604987Y346952D01*
X604904Y346619D01*
X604654Y346410D01*
X604362Y346285D01*
X603321D01*
G01X604362D02*
X604987Y345077D01*
G01X607754D02*
Y347577D01*
X606212Y345785D01*
X608296D01*
G01X609437Y345077D02*
Y347577D01*
X610271D01*
X610604Y347452D01*
X610854Y347285D01*
X611062Y347035D01*
X611229Y346744D01*
X611271Y346327D01*
X611229Y345910D01*
X611062Y345619D01*
X610854Y345369D01*
X610604Y345202D01*
X610271Y345077D01*
X609437D01*
G01X613454D02*
Y347577D01*
X612954Y347077D01*
G01Y345077D02*
X613954D01*
G01X616554D02*
Y347577D01*
X616054Y347077D01*
G01Y345077D02*
X617054D01*
G01X641378Y371508D02*
X641128Y371633D01*
X640836Y371716D01*
X640503D01*
X640128Y371591D01*
X639836Y371383D01*
X639628Y371133D01*
X639461Y370716D01*
X639419Y370341D01*
X639503Y369966D01*
X639628Y369716D01*
X639878Y369466D01*
X640169Y369299D01*
X640461Y369216D01*
X640753D01*
X641044Y369299D01*
X641294Y369424D01*
X641503Y369591D01*
G01X644061Y369216D02*
Y371716D01*
X642519Y369924D01*
X644603D01*
G01X645744Y369216D02*
Y371716D01*
X646578D01*
X646911Y371591D01*
X647161Y371424D01*
X647369Y371174D01*
X647536Y370883D01*
X647578Y370466D01*
X647536Y370049D01*
X647369Y369758D01*
X647161Y369508D01*
X646911Y369341D01*
X646578Y369216D01*
X645744D01*
G01X650261D02*
Y371716D01*
X648719Y369924D01*
X650803D01*
G01X651944Y369591D02*
X652194Y369383D01*
X652486Y369258D01*
X652861Y369216D01*
X653236Y369299D01*
X653528Y369466D01*
X653736Y369758D01*
X653778Y370091D01*
X653694Y370424D01*
X653486Y370633D01*
X653194Y370799D01*
X652903Y370841D01*
X652611Y370799D01*
X652236Y370633D01*
X652361Y371716D01*
X653486D01*
G01X614212Y400198D02*
X613962Y400323D01*
X613670Y400406D01*
X613337D01*
X612962Y400281D01*
X612670Y400073D01*
X612462Y399823D01*
X612295Y399406D01*
X612253Y399031D01*
X612337Y398656D01*
X612462Y398406D01*
X612712Y398156D01*
X613003Y397989D01*
X613295Y397906D01*
X613587D01*
X613878Y397989D01*
X614128Y398114D01*
X614337Y398281D01*
G01X616895Y397906D02*
Y400406D01*
X615353Y398614D01*
X617437D01*
G01X618578Y397906D02*
Y400406D01*
X619412D01*
X619745Y400281D01*
X619995Y400114D01*
X620203Y399864D01*
X620370Y399573D01*
X620412Y399156D01*
X620370Y398739D01*
X620203Y398448D01*
X619995Y398198D01*
X619745Y398031D01*
X619412Y397906D01*
X618578D01*
G01X623095D02*
Y400406D01*
X621553Y398614D01*
X623637D01*
G01X624903Y399989D02*
X625153Y400239D01*
X625445Y400364D01*
X625778Y400406D01*
X626195Y400323D01*
X626487Y400114D01*
X626570Y399864D01*
X626528Y399614D01*
X626362Y399406D01*
X625528Y398989D01*
X625153Y398698D01*
X624903Y398281D01*
X624820Y397906D01*
X626570D01*
G01X657327Y386100D02*
Y408672D01*
G01Y386100D02*
X660022D01*
G01X645818Y375518D02*
X645693Y375268D01*
X645610Y374976D01*
Y374643D01*
X645735Y374268D01*
X645943Y373976D01*
X646193Y373768D01*
X646610Y373601D01*
X646985Y373559D01*
X647360Y373643D01*
X647610Y373768D01*
X647860Y374018D01*
X648027Y374309D01*
X648110Y374601D01*
Y374893D01*
X648027Y375184D01*
X647902Y375434D01*
X647735Y375643D01*
G01X648110Y376909D02*
X645610D01*
Y378493D01*
G01X646818Y377909D02*
Y376909D01*
G01X648110Y380801D02*
X645610D01*
X646110Y380301D01*
G01X648110D02*
Y381301D01*
G01X653942Y379817D02*
X653817Y379567D01*
X653734Y379275D01*
Y378942D01*
X653859Y378567D01*
X654067Y378275D01*
X654317Y378067D01*
X654734Y377900D01*
X655109Y377858D01*
X655484Y377942D01*
X655734Y378067D01*
X655984Y378317D01*
X656151Y378608D01*
X656234Y378900D01*
Y379192D01*
X656151Y379483D01*
X656026Y379733D01*
X655859Y379942D01*
G01X656234Y381208D02*
X653734D01*
Y382792D01*
G01X654942Y382208D02*
Y381208D01*
G01X654151Y384308D02*
X653901Y384558D01*
X653776Y384850D01*
X653734Y385183D01*
X653817Y385600D01*
X654026Y385892D01*
X654276Y385975D01*
X654526Y385933D01*
X654734Y385767D01*
X655151Y384933D01*
X655442Y384558D01*
X655859Y384308D01*
X656234Y384225D01*
Y385975D01*
G01X646308Y397432D02*
X646183Y397182D01*
X646100Y396890D01*
Y396557D01*
X646225Y396182D01*
X646433Y395890D01*
X646683Y395682D01*
X647100Y395515D01*
X647475Y395473D01*
X647850Y395557D01*
X648100Y395682D01*
X648350Y395932D01*
X648517Y396223D01*
X648600Y396515D01*
Y396807D01*
X648517Y397098D01*
X648392Y397348D01*
X648225Y397557D01*
G01X648600Y398823D02*
X646100D01*
Y400407D01*
G01X647308Y399823D02*
Y398823D01*
G01X648225Y401798D02*
X648433Y402048D01*
X648558Y402340D01*
X648600Y402715D01*
X648517Y403090D01*
X648350Y403382D01*
X648058Y403590D01*
X647725Y403632D01*
X647392Y403548D01*
X647183Y403340D01*
X647017Y403048D01*
X646975Y402757D01*
X647017Y402465D01*
X647183Y402090D01*
X646100Y402215D01*
Y403340D01*
G01X654208Y392517D02*
X654083Y392267D01*
X654000Y391975D01*
Y391642D01*
X654125Y391267D01*
X654333Y390975D01*
X654583Y390767D01*
X655000Y390600D01*
X655375Y390558D01*
X655750Y390642D01*
X656000Y390767D01*
X656250Y391017D01*
X656417Y391308D01*
X656500Y391600D01*
Y391892D01*
X656417Y392183D01*
X656292Y392433D01*
X656125Y392642D01*
G01X656500Y393908D02*
X654000D01*
Y395492D01*
G01X655208Y394908D02*
Y393908D01*
G01X656500Y398300D02*
X654000D01*
X655792Y396758D01*
Y398842D01*
G01X645908Y385217D02*
X645783Y384967D01*
X645700Y384675D01*
Y384342D01*
X645825Y383967D01*
X646033Y383675D01*
X646283Y383467D01*
X646700Y383300D01*
X647075Y383258D01*
X647450Y383342D01*
X647700Y383467D01*
X647950Y383717D01*
X648117Y384008D01*
X648200Y384300D01*
Y384592D01*
X648117Y384883D01*
X647992Y385133D01*
X647825Y385342D01*
G01X648200Y386608D02*
X645700D01*
Y388192D01*
G01X646908Y387608D02*
Y386608D01*
G01X647700Y389583D02*
X647992Y389833D01*
X648158Y390167D01*
X648200Y390542D01*
X648158Y390875D01*
X647950Y391208D01*
X647700Y391417D01*
X647450Y391458D01*
X647158Y391375D01*
X646950Y391083D01*
X646867Y390792D01*
Y390417D01*
G01Y390792D02*
X646742Y391042D01*
X646533Y391250D01*
X646283Y391333D01*
X646033Y391250D01*
X645825Y391042D01*
X645700Y390667D01*
X645742Y390292D01*
X645908Y389917D01*
G01X620577Y357039D02*
X620452Y356789D01*
X620369Y356497D01*
Y356164D01*
X620494Y355789D01*
X620702Y355497D01*
X620952Y355289D01*
X621369Y355122D01*
X621744Y355080D01*
X622119Y355164D01*
X622369Y355289D01*
X622619Y355539D01*
X622786Y355830D01*
X622869Y356122D01*
Y356414D01*
X622786Y356705D01*
X622661Y356955D01*
X622494Y357164D01*
G01X620786Y358430D02*
X620536Y358680D01*
X620411Y358972D01*
X620369Y359305D01*
X620452Y359722D01*
X620661Y360014D01*
X620911Y360097D01*
X621161Y360055D01*
X621369Y359889D01*
X621786Y359055D01*
X622077Y358680D01*
X622494Y358430D01*
X622869Y358347D01*
Y360097D01*
G01X620786Y361530D02*
X620536Y361780D01*
X620411Y362072D01*
X620369Y362405D01*
X620452Y362822D01*
X620661Y363114D01*
X620911Y363197D01*
X621161Y363155D01*
X621369Y362989D01*
X621786Y362155D01*
X622077Y361780D01*
X622494Y361530D01*
X622869Y361447D01*
Y363197D01*
G01X620369Y364172D02*
X622869Y364755D01*
X620369Y365422D01*
X622869Y366089D01*
X620369Y366672D01*
G01X622869Y368522D02*
X620369D01*
X620869Y368022D01*
G01X622869D02*
Y369022D01*
G01X621827Y370830D02*
X621536Y371122D01*
X621369Y371372D01*
X621286Y371705D01*
X621369Y371997D01*
X621536Y372205D01*
X621786Y372372D01*
X622077Y372414D01*
X622327Y372372D01*
X622577Y372205D01*
X622786Y371955D01*
X622869Y371664D01*
X622786Y371330D01*
X622536Y371039D01*
X622161Y370872D01*
X621744Y370830D01*
X621202Y370914D01*
X620911Y371039D01*
X620619Y371247D01*
X620411Y371539D01*
X620369Y371830D01*
X620452Y372122D01*
X620661Y372330D01*
G01X635342Y361567D02*
X635217Y361317D01*
X635134Y361025D01*
Y360692D01*
X635259Y360317D01*
X635467Y360025D01*
X635717Y359817D01*
X636134Y359650D01*
X636509Y359608D01*
X636884Y359692D01*
X637134Y359817D01*
X637384Y360067D01*
X637551Y360358D01*
X637634Y360650D01*
Y360942D01*
X637551Y361233D01*
X637426Y361483D01*
X637259Y361692D01*
G01X637634Y364250D02*
X635134D01*
X636926Y362708D01*
Y364792D01*
G01X637634Y367683D02*
Y366017D01*
X635134D01*
Y367683D01*
G01X636342Y367017D02*
Y366017D01*
G01X637342Y369242D02*
X637551Y369533D01*
X637634Y369867D01*
X637551Y370200D01*
X637301Y370492D01*
X636926Y370700D01*
X636551Y370783D01*
X636092D01*
X635717Y370700D01*
X635384Y370492D01*
X635217Y370242D01*
X635134Y369950D01*
X635217Y369617D01*
X635384Y369367D01*
X635634Y369200D01*
X635967Y369117D01*
X636259Y369200D01*
X636551Y369408D01*
X636717Y369658D01*
X636759Y369950D01*
X636676Y370283D01*
X636467Y370533D01*
X636092Y370783D01*
G01X640052Y391157D02*
Y389491D01*
X637552D01*
Y391157D01*
G01X638760Y390491D02*
Y389491D01*
G01X637552Y392507D02*
X639344D01*
X639719Y392674D01*
X639969Y393007D01*
X640052Y393424D01*
X639969Y393841D01*
X639719Y394174D01*
X639344Y394341D01*
X637552D01*
G01X640052Y397024D02*
X637552D01*
X639344Y395482D01*
Y397566D01*
G01X640052Y398707D02*
X637552D01*
Y399541D01*
X637677Y399874D01*
X637844Y400124D01*
X638094Y400332D01*
X638385Y400499D01*
X638802Y400541D01*
X639219Y400499D01*
X639510Y400332D01*
X639760Y400124D01*
X639927Y399874D01*
X640052Y399541D01*
Y398707D01*
G01Y403224D02*
X637552D01*
X639344Y401682D01*
Y403766D01*
G01X618465Y455438D02*
Y457938D01*
X619506D01*
X619840Y457813D01*
X620048Y457646D01*
X620131Y457313D01*
X620048Y456980D01*
X619798Y456771D01*
X619506Y456646D01*
X618465D01*
G01X619506D02*
X620131Y455438D01*
G01X621481Y455938D02*
X621731Y455646D01*
X622065Y455480D01*
X622440Y455438D01*
X622773Y455480D01*
X623106Y455688D01*
X623315Y455938D01*
X623356Y456188D01*
X623273Y456480D01*
X622981Y456688D01*
X622690Y456771D01*
X622315D01*
G01X622690D02*
X622940Y456896D01*
X623148Y457105D01*
X623231Y457355D01*
X623148Y457605D01*
X622940Y457813D01*
X622565Y457938D01*
X622190Y457896D01*
X621815Y457730D01*
G01X625831Y456771D02*
X625998Y456896D01*
X626123Y457105D01*
X626206Y457396D01*
X626123Y457646D01*
X625956Y457813D01*
X625665Y457938D01*
X624540D01*
Y455438D01*
X625915D01*
X626206Y455605D01*
X626373Y455855D01*
X626456Y456146D01*
X626373Y456438D01*
X626123Y456688D01*
X625831Y456771D01*
X624540D01*
G01X629098Y455438D02*
Y457938D01*
X627556Y456146D01*
X629640D01*
G01X603964Y451867D02*
Y454367D01*
X605005D01*
X605339Y454242D01*
X605547Y454075D01*
X605630Y453742D01*
X605547Y453409D01*
X605297Y453200D01*
X605005Y453075D01*
X603964D01*
G01X605005D02*
X605630Y451867D01*
G01X606980Y452367D02*
X607230Y452075D01*
X607564Y451909D01*
X607939Y451867D01*
X608272Y451909D01*
X608605Y452117D01*
X608814Y452367D01*
X608855Y452617D01*
X608772Y452909D01*
X608480Y453117D01*
X608189Y453200D01*
X607814D01*
G01X608189D02*
X608439Y453325D01*
X608647Y453534D01*
X608730Y453784D01*
X608647Y454034D01*
X608439Y454242D01*
X608064Y454367D01*
X607689Y454325D01*
X607314Y454159D01*
G01X611330Y453200D02*
X611497Y453325D01*
X611622Y453534D01*
X611705Y453825D01*
X611622Y454075D01*
X611455Y454242D01*
X611164Y454367D01*
X610039D01*
Y451867D01*
X611414D01*
X611705Y452034D01*
X611872Y452284D01*
X611955Y452575D01*
X611872Y452867D01*
X611622Y453117D01*
X611330Y453200D01*
X610039D01*
G01X613180Y452242D02*
X613430Y452034D01*
X613722Y451909D01*
X614097Y451867D01*
X614472Y451950D01*
X614764Y452117D01*
X614972Y452409D01*
X615014Y452742D01*
X614930Y453075D01*
X614722Y453284D01*
X614430Y453450D01*
X614139Y453492D01*
X613847Y453450D01*
X613472Y453284D01*
X613597Y454367D01*
X614722D01*
G01X603964Y455367D02*
Y457867D01*
X605005D01*
X605339Y457742D01*
X605547Y457575D01*
X605630Y457242D01*
X605547Y456909D01*
X605297Y456700D01*
X605005Y456575D01*
X603964D01*
G01X605005D02*
X605630Y455367D01*
G01X606980Y455867D02*
X607230Y455575D01*
X607564Y455409D01*
X607939Y455367D01*
X608272Y455409D01*
X608605Y455617D01*
X608814Y455867D01*
X608855Y456117D01*
X608772Y456409D01*
X608480Y456617D01*
X608189Y456700D01*
X607814D01*
G01X608189D02*
X608439Y456825D01*
X608647Y457034D01*
X608730Y457284D01*
X608647Y457534D01*
X608439Y457742D01*
X608064Y457867D01*
X607689Y457825D01*
X607314Y457659D01*
G01X611330Y456700D02*
X611497Y456825D01*
X611622Y457034D01*
X611705Y457325D01*
X611622Y457575D01*
X611455Y457742D01*
X611164Y457867D01*
X610039D01*
Y455367D01*
X611414D01*
X611705Y455534D01*
X611872Y455784D01*
X611955Y456075D01*
X611872Y456367D01*
X611622Y456617D01*
X611330Y456700D01*
X610039D01*
G01X613180Y455867D02*
X613430Y455575D01*
X613764Y455409D01*
X614139Y455367D01*
X614472Y455409D01*
X614805Y455617D01*
X615014Y455867D01*
X615055Y456117D01*
X614972Y456409D01*
X614680Y456617D01*
X614389Y456700D01*
X614014D01*
G01X614389D02*
X614639Y456825D01*
X614847Y457034D01*
X614930Y457284D01*
X614847Y457534D01*
X614639Y457742D01*
X614264Y457867D01*
X613889Y457825D01*
X613514Y457659D01*
G01X603964Y458867D02*
Y461367D01*
X605005D01*
X605339Y461242D01*
X605547Y461075D01*
X605630Y460742D01*
X605547Y460409D01*
X605297Y460200D01*
X605005Y460075D01*
X603964D01*
G01X605005D02*
X605630Y458867D01*
G01X606980Y459367D02*
X607230Y459075D01*
X607564Y458909D01*
X607939Y458867D01*
X608272Y458909D01*
X608605Y459117D01*
X608814Y459367D01*
X608855Y459617D01*
X608772Y459909D01*
X608480Y460117D01*
X608189Y460200D01*
X607814D01*
G01X608189D02*
X608439Y460325D01*
X608647Y460534D01*
X608730Y460784D01*
X608647Y461034D01*
X608439Y461242D01*
X608064Y461367D01*
X607689Y461325D01*
X607314Y461159D01*
G01X611330Y460200D02*
X611497Y460325D01*
X611622Y460534D01*
X611705Y460825D01*
X611622Y461075D01*
X611455Y461242D01*
X611164Y461367D01*
X610039D01*
Y458867D01*
X611414D01*
X611705Y459034D01*
X611872Y459284D01*
X611955Y459575D01*
X611872Y459867D01*
X611622Y460117D01*
X611330Y460200D01*
X610039D01*
G01X614097Y458867D02*
Y461367D01*
X613597Y460867D01*
G01Y458867D02*
X614597D01*
G01X618465Y458938D02*
Y461438D01*
X619506D01*
X619840Y461313D01*
X620048Y461146D01*
X620131Y460813D01*
X620048Y460480D01*
X619798Y460271D01*
X619506Y460146D01*
X618465D01*
G01X619506D02*
X620131Y458938D01*
G01X621481Y459438D02*
X621731Y459146D01*
X622065Y458980D01*
X622440Y458938D01*
X622773Y458980D01*
X623106Y459188D01*
X623315Y459438D01*
X623356Y459688D01*
X623273Y459980D01*
X622981Y460188D01*
X622690Y460271D01*
X622315D01*
G01X622690D02*
X622940Y460396D01*
X623148Y460605D01*
X623231Y460855D01*
X623148Y461105D01*
X622940Y461313D01*
X622565Y461438D01*
X622190Y461396D01*
X621815Y461230D01*
G01X625831Y460271D02*
X625998Y460396D01*
X626123Y460605D01*
X626206Y460896D01*
X626123Y461146D01*
X625956Y461313D01*
X625665Y461438D01*
X624540D01*
Y458938D01*
X625915D01*
X626206Y459105D01*
X626373Y459355D01*
X626456Y459646D01*
X626373Y459938D01*
X626123Y460188D01*
X625831Y460271D01*
X624540D01*
G01X627806Y461021D02*
X628056Y461271D01*
X628348Y461396D01*
X628681Y461438D01*
X629098Y461355D01*
X629390Y461146D01*
X629473Y460896D01*
X629431Y460646D01*
X629265Y460438D01*
X628431Y460021D01*
X628056Y459730D01*
X627806Y459313D01*
X627723Y458938D01*
X629473D01*
G01X639563Y415209D02*
X639438Y414959D01*
X639355Y414667D01*
Y414334D01*
X639480Y413959D01*
X639688Y413667D01*
X639938Y413459D01*
X640355Y413292D01*
X640730Y413250D01*
X641105Y413334D01*
X641355Y413459D01*
X641605Y413709D01*
X641772Y414000D01*
X641855Y414292D01*
Y414584D01*
X641772Y414875D01*
X641647Y415125D01*
X641480Y415334D01*
G01X641355Y416475D02*
X641647Y416725D01*
X641813Y417059D01*
X641855Y417434D01*
X641813Y417767D01*
X641605Y418100D01*
X641355Y418309D01*
X641105Y418350D01*
X640813Y418267D01*
X640605Y417975D01*
X640522Y417684D01*
Y417309D01*
G01Y417684D02*
X640397Y417934D01*
X640188Y418142D01*
X639938Y418225D01*
X639688Y418142D01*
X639480Y417934D01*
X639355Y417559D01*
X639397Y417184D01*
X639563Y416809D01*
G01Y421409D02*
X639438Y421159D01*
X639355Y420867D01*
Y420534D01*
X639480Y420159D01*
X639688Y419867D01*
X639938Y419659D01*
X640355Y419492D01*
X640730Y419450D01*
X641105Y419534D01*
X641355Y419659D01*
X641605Y419909D01*
X641772Y420200D01*
X641855Y420492D01*
Y420784D01*
X641772Y421075D01*
X641647Y421325D01*
X641480Y421534D01*
G01X639772Y422800D02*
X639522Y423050D01*
X639397Y423342D01*
X639355Y423675D01*
X639438Y424092D01*
X639647Y424384D01*
X639897Y424467D01*
X640147Y424425D01*
X640355Y424259D01*
X640772Y423425D01*
X641063Y423050D01*
X641480Y422800D01*
X641855Y422717D01*
Y424467D01*
G01X635263Y415609D02*
X635138Y415359D01*
X635055Y415067D01*
Y414734D01*
X635180Y414359D01*
X635388Y414067D01*
X635638Y413859D01*
X636055Y413692D01*
X636430Y413650D01*
X636805Y413734D01*
X637055Y413859D01*
X637305Y414109D01*
X637472Y414400D01*
X637555Y414692D01*
Y414984D01*
X637472Y415275D01*
X637347Y415525D01*
X637180Y415734D01*
G01X637055Y416875D02*
X637347Y417125D01*
X637513Y417459D01*
X637555Y417834D01*
X637513Y418167D01*
X637305Y418500D01*
X637055Y418709D01*
X636805Y418750D01*
X636513Y418667D01*
X636305Y418375D01*
X636222Y418084D01*
Y417709D01*
G01Y418084D02*
X636097Y418334D01*
X635888Y418542D01*
X635638Y418625D01*
X635388Y418542D01*
X635180Y418334D01*
X635055Y417959D01*
X635097Y417584D01*
X635263Y417209D01*
G01Y421809D02*
X635138Y421559D01*
X635055Y421267D01*
Y420934D01*
X635180Y420559D01*
X635388Y420267D01*
X635638Y420059D01*
X636055Y419892D01*
X636430Y419850D01*
X636805Y419934D01*
X637055Y420059D01*
X637305Y420309D01*
X637472Y420600D01*
X637555Y420892D01*
Y421184D01*
X637472Y421475D01*
X637347Y421725D01*
X637180Y421934D01*
G01X637555Y423992D02*
X635055D01*
X635555Y423492D01*
G01X637555D02*
Y424492D01*
G01X651708Y411898D02*
X651583Y411648D01*
X651500Y411356D01*
Y411023D01*
X651625Y410648D01*
X651833Y410356D01*
X652083Y410148D01*
X652500Y409981D01*
X652875Y409939D01*
X653250Y410023D01*
X653500Y410148D01*
X653750Y410398D01*
X653917Y410689D01*
X654000Y410981D01*
Y411273D01*
X653917Y411564D01*
X653792Y411814D01*
X653625Y412023D01*
G01X654000Y414581D02*
X651500D01*
X653292Y413039D01*
Y415123D01*
G01X651708Y418098D02*
X651583Y417848D01*
X651500Y417556D01*
Y417223D01*
X651625Y416848D01*
X651833Y416556D01*
X652083Y416348D01*
X652500Y416181D01*
X652875Y416139D01*
X653250Y416223D01*
X653500Y416348D01*
X653750Y416598D01*
X653917Y416889D01*
X654000Y417181D01*
Y417473D01*
X653917Y417764D01*
X653792Y418014D01*
X653625Y418223D01*
G01X654000Y420281D02*
X651500D01*
X652000Y419781D01*
G01X654000D02*
Y420781D01*
G01X660027Y421464D02*
X656236D01*
Y408668D01*
X660027D01*
G01X652636Y466400D02*
Y462609D01*
X665432D01*
Y466400D01*
G01X634873Y460509D02*
Y463609D01*
X636329D01*
G01X635793Y462111D02*
X634873D01*
G01X637973Y463092D02*
X638203Y463402D01*
X638471Y463557D01*
X638778Y463609D01*
X639161Y463506D01*
X639429Y463247D01*
X639506Y462937D01*
X639468Y462627D01*
X639314Y462369D01*
X638548Y461852D01*
X638203Y461491D01*
X637973Y460974D01*
X637896Y460509D01*
X639506D01*
G01X641801Y463609D02*
X641494Y463506D01*
X641264Y463247D01*
X641111Y462937D01*
X640996Y462524D01*
X640958Y462059D01*
X640996Y461594D01*
X641111Y461181D01*
X641264Y460871D01*
X641494Y460612D01*
X641801Y460509D01*
X642108Y460612D01*
X642338Y460871D01*
X642491Y461181D01*
X642606Y461594D01*
X642644Y462059D01*
X642606Y462524D01*
X642491Y462937D01*
X642338Y463247D01*
X642108Y463506D01*
X641801Y463609D01*
G01X626636Y447463D02*
Y450563D01*
X628092D01*
G01X627556Y449065D02*
X626636D01*
G01X630464Y447463D02*
Y450563D01*
X630004Y449943D01*
G01Y447463D02*
X630924D01*
G01X633091Y453425D02*
Y431425D01*
X636091D01*
Y426275D01*
X759091D01*
Y458575D01*
X641383D01*
G01X637543Y498401D02*
X637418Y498151D01*
X637335Y497859D01*
Y497526D01*
X637460Y497151D01*
X637668Y496859D01*
X637918Y496651D01*
X638335Y496484D01*
X638710Y496442D01*
X639085Y496526D01*
X639335Y496651D01*
X639585Y496901D01*
X639752Y497192D01*
X639835Y497484D01*
Y497776D01*
X639752Y498067D01*
X639627Y498317D01*
X639460Y498526D01*
G01X639835Y501084D02*
X637335D01*
X639127Y499542D01*
Y501626D01*
G01X638502Y504017D02*
X638377Y504184D01*
X638168Y504309D01*
X637877Y504392D01*
X637627Y504309D01*
X637460Y504142D01*
X637335Y503851D01*
Y502726D01*
X639835D01*
Y504101D01*
X639668Y504392D01*
X639418Y504559D01*
X639127Y504642D01*
X638835Y504559D01*
X638585Y504309D01*
X638502Y504017D01*
Y502726D01*
G01X639335Y505867D02*
X639627Y506117D01*
X639793Y506451D01*
X639835Y506826D01*
X639793Y507159D01*
X639585Y507492D01*
X639335Y507701D01*
X639085Y507742D01*
X638793Y507659D01*
X638585Y507367D01*
X638502Y507076D01*
Y506701D01*
G01Y507076D02*
X638377Y507326D01*
X638168Y507534D01*
X637918Y507617D01*
X637668Y507534D01*
X637460Y507326D01*
X637335Y506951D01*
X637377Y506576D01*
X637543Y506201D01*
G01X633962Y498167D02*
X633837Y497917D01*
X633754Y497625D01*
Y497292D01*
X633879Y496917D01*
X634087Y496625D01*
X634337Y496417D01*
X634754Y496250D01*
X635129Y496208D01*
X635504Y496292D01*
X635754Y496417D01*
X636004Y496667D01*
X636171Y496958D01*
X636254Y497250D01*
Y497542D01*
X636171Y497833D01*
X636046Y498083D01*
X635879Y498292D01*
G01X636254Y500850D02*
X633754D01*
X635546Y499308D01*
Y501392D01*
G01X634921Y503783D02*
X634796Y503950D01*
X634587Y504075D01*
X634296Y504158D01*
X634046Y504075D01*
X633879Y503908D01*
X633754Y503617D01*
Y502492D01*
X636254D01*
Y503867D01*
X636087Y504158D01*
X635837Y504325D01*
X635546Y504408D01*
X635254Y504325D01*
X635004Y504075D01*
X634921Y503783D01*
Y502492D01*
G01X634171Y505758D02*
X633921Y506008D01*
X633796Y506300D01*
X633754Y506633D01*
X633837Y507050D01*
X634046Y507342D01*
X634296Y507425D01*
X634546Y507383D01*
X634754Y507217D01*
X635171Y506383D01*
X635462Y506008D01*
X635879Y505758D01*
X636254Y505675D01*
Y507425D01*
G01X649790Y500951D02*
X647290D01*
Y501992D01*
X647415Y502326D01*
X647582Y502534D01*
X647915Y502617D01*
X648248Y502534D01*
X648457Y502284D01*
X648582Y501992D01*
Y500951D01*
G01Y501992D02*
X649790Y502617D01*
G01Y505384D02*
X647290D01*
X649082Y503842D01*
Y505926D01*
G01X648457Y508317D02*
X648332Y508484D01*
X648123Y508609D01*
X647832Y508692D01*
X647582Y508609D01*
X647415Y508442D01*
X647290Y508151D01*
Y507026D01*
X649790D01*
Y508401D01*
X649623Y508692D01*
X649373Y508859D01*
X649082Y508942D01*
X648790Y508859D01*
X648540Y508609D01*
X648457Y508317D01*
Y507026D01*
G01X649290Y510167D02*
X649582Y510417D01*
X649748Y510751D01*
X649790Y511126D01*
X649748Y511459D01*
X649540Y511792D01*
X649290Y512001D01*
X649040Y512042D01*
X648748Y511959D01*
X648540Y511667D01*
X648457Y511376D01*
Y511001D01*
G01Y511376D02*
X648332Y511626D01*
X648123Y511834D01*
X647873Y511917D01*
X647623Y511834D01*
X647415Y511626D01*
X647290Y511251D01*
X647332Y510876D01*
X647498Y510501D01*
G01X653784Y509421D02*
Y511921D01*
X654825D01*
X655159Y511796D01*
X655367Y511629D01*
X655450Y511296D01*
X655367Y510963D01*
X655117Y510754D01*
X654825Y510629D01*
X653784D01*
G01X654825D02*
X655450Y509421D01*
G01X658217D02*
Y511921D01*
X656675Y510129D01*
X658759D01*
G01X661150Y510754D02*
X661317Y510879D01*
X661442Y511088D01*
X661525Y511379D01*
X661442Y511629D01*
X661275Y511796D01*
X660984Y511921D01*
X659859D01*
Y509421D01*
X661234D01*
X661525Y509588D01*
X661692Y509838D01*
X661775Y510129D01*
X661692Y510421D01*
X661442Y510671D01*
X661150Y510754D01*
X659859D01*
G01X663917Y509421D02*
Y511921D01*
X663417Y511421D01*
G01Y509421D02*
X664417D01*
G01X655239Y490539D02*
Y493039D01*
X656280D01*
X656614Y492914D01*
X656822Y492747D01*
X656905Y492414D01*
X656822Y492081D01*
X656572Y491872D01*
X656280Y491747D01*
X655239D01*
G01X656280D02*
X656905Y490539D01*
G01X659672D02*
Y493039D01*
X658130Y491247D01*
X660214D01*
G01X662605Y491872D02*
X662772Y491997D01*
X662897Y492206D01*
X662980Y492497D01*
X662897Y492747D01*
X662730Y492914D01*
X662439Y493039D01*
X661314D01*
Y490539D01*
X662689D01*
X662980Y490706D01*
X663147Y490956D01*
X663230Y491247D01*
X663147Y491539D01*
X662897Y491789D01*
X662605Y491872D01*
X661314D01*
G01X664664Y490831D02*
X664955Y490622D01*
X665289Y490539D01*
X665622Y490622D01*
X665914Y490872D01*
X666122Y491247D01*
X666205Y491622D01*
Y492081D01*
X666122Y492456D01*
X665914Y492789D01*
X665664Y492956D01*
X665372Y493039D01*
X665039Y492956D01*
X664789Y492789D01*
X664622Y492539D01*
X664539Y492206D01*
X664622Y491914D01*
X664830Y491622D01*
X665080Y491456D01*
X665372Y491414D01*
X665705Y491497D01*
X665955Y491706D01*
X666205Y492081D01*
G01X654090Y495951D02*
X651590D01*
Y496992D01*
X651715Y497326D01*
X651882Y497534D01*
X652215Y497617D01*
X652548Y497534D01*
X652757Y497284D01*
X652882Y496992D01*
Y495951D01*
G01Y496992D02*
X654090Y497617D01*
G01Y500384D02*
X651590D01*
X653382Y498842D01*
Y500926D01*
G01X652757Y503317D02*
X652632Y503484D01*
X652423Y503609D01*
X652132Y503692D01*
X651882Y503609D01*
X651715Y503442D01*
X651590Y503151D01*
Y502026D01*
X654090D01*
Y503401D01*
X653923Y503692D01*
X653673Y503859D01*
X653382Y503942D01*
X653090Y503859D01*
X652840Y503609D01*
X652757Y503317D01*
Y502026D01*
G01X653715Y505167D02*
X653923Y505417D01*
X654048Y505709D01*
X654090Y506084D01*
X654007Y506459D01*
X653840Y506751D01*
X653548Y506959D01*
X653215Y507001D01*
X652882Y506917D01*
X652673Y506709D01*
X652507Y506417D01*
X652465Y506126D01*
X652507Y505834D01*
X652673Y505459D01*
X651590Y505584D01*
Y506709D01*
G01X646335Y501051D02*
X643835D01*
Y502092D01*
X643960Y502426D01*
X644127Y502634D01*
X644460Y502717D01*
X644793Y502634D01*
X645002Y502384D01*
X645127Y502092D01*
Y501051D01*
G01Y502092D02*
X646335Y502717D01*
G01Y505484D02*
X643835D01*
X645627Y503942D01*
Y506026D01*
G01X645002Y508417D02*
X644877Y508584D01*
X644668Y508709D01*
X644377Y508792D01*
X644127Y508709D01*
X643960Y508542D01*
X643835Y508251D01*
Y507126D01*
X646335D01*
Y508501D01*
X646168Y508792D01*
X645918Y508959D01*
X645627Y509042D01*
X645335Y508959D01*
X645085Y508709D01*
X645002Y508417D01*
Y507126D01*
G01X644252Y510392D02*
X644002Y510642D01*
X643877Y510934D01*
X643835Y511267D01*
X643918Y511684D01*
X644127Y511976D01*
X644377Y512059D01*
X644627Y512017D01*
X644835Y511851D01*
X645252Y511017D01*
X645543Y510642D01*
X645960Y510392D01*
X646335Y510309D01*
Y512059D01*
G01X622428Y508608D02*
X622178Y508733D01*
X621886Y508816D01*
X621553D01*
X621178Y508691D01*
X620886Y508483D01*
X620678Y508233D01*
X620511Y507816D01*
X620469Y507441D01*
X620553Y507066D01*
X620678Y506816D01*
X620928Y506566D01*
X621219Y506399D01*
X621511Y506316D01*
X621803D01*
X622094Y506399D01*
X622344Y506524D01*
X622553Y506691D01*
G01X623694Y506816D02*
X623944Y506524D01*
X624278Y506358D01*
X624653Y506316D01*
X624986Y506358D01*
X625319Y506566D01*
X625528Y506816D01*
X625569Y507066D01*
X625486Y507358D01*
X625194Y507566D01*
X624903Y507649D01*
X624528D01*
G01X624903D02*
X625153Y507774D01*
X625361Y507983D01*
X625444Y508233D01*
X625361Y508483D01*
X625153Y508691D01*
X624778Y508816D01*
X624403Y508774D01*
X624028Y508608D01*
G01X628044Y507649D02*
X628211Y507774D01*
X628336Y507983D01*
X628419Y508274D01*
X628336Y508524D01*
X628169Y508691D01*
X627878Y508816D01*
X626753D01*
Y506316D01*
X628128D01*
X628419Y506483D01*
X628586Y506733D01*
X628669Y507024D01*
X628586Y507316D01*
X628336Y507566D01*
X628044Y507649D01*
X626753D01*
G01X630019Y508399D02*
X630269Y508649D01*
X630561Y508774D01*
X630894Y508816D01*
X631311Y508733D01*
X631603Y508524D01*
X631686Y508274D01*
X631644Y508024D01*
X631478Y507816D01*
X630644Y507399D01*
X630269Y507108D01*
X630019Y506691D01*
X629936Y506316D01*
X631686D01*
G01X620992Y512151D02*
X620742Y512276D01*
X620450Y512359D01*
X620117D01*
X619742Y512234D01*
X619450Y512026D01*
X619242Y511776D01*
X619075Y511359D01*
X619033Y510984D01*
X619117Y510609D01*
X619242Y510359D01*
X619492Y510109D01*
X619783Y509942D01*
X620075Y509859D01*
X620367D01*
X620658Y509942D01*
X620908Y510067D01*
X621117Y510234D01*
G01X622258Y510359D02*
X622508Y510067D01*
X622842Y509901D01*
X623217Y509859D01*
X623550Y509901D01*
X623883Y510109D01*
X624092Y510359D01*
X624133Y510609D01*
X624050Y510901D01*
X623758Y511109D01*
X623467Y511192D01*
X623092D01*
G01X623467D02*
X623717Y511317D01*
X623925Y511526D01*
X624008Y511776D01*
X623925Y512026D01*
X623717Y512234D01*
X623342Y512359D01*
X622967Y512317D01*
X622592Y512151D01*
G01X626608Y511192D02*
X626775Y511317D01*
X626900Y511526D01*
X626983Y511817D01*
X626900Y512067D01*
X626733Y512234D01*
X626442Y512359D01*
X625317D01*
Y509859D01*
X626692D01*
X626983Y510026D01*
X627150Y510276D01*
X627233Y510567D01*
X627150Y510859D01*
X626900Y511109D01*
X626608Y511192D01*
X625317D01*
G01X629375Y509859D02*
Y512359D01*
X628875Y511859D01*
G01Y509859D02*
X629875D01*
G01X641027Y479830D02*
X640694Y479872D01*
X640402Y480038D01*
X640152Y480288D01*
X639985Y480580D01*
X639902Y480913D01*
Y481247D01*
X639985Y481580D01*
X640152Y481872D01*
X640402Y482122D01*
X640694Y482288D01*
X641027Y482330D01*
X641360Y482288D01*
X641652Y482122D01*
X641902Y481872D01*
X642069Y481580D01*
X642152Y481247D01*
Y480913D01*
X642069Y480580D01*
X641902Y480288D01*
X641652Y480038D01*
X641360Y479872D01*
X641027Y479830D01*
G01X641360Y480497D02*
X641860Y479830D01*
G01X644627D02*
Y482330D01*
X643085Y480538D01*
X645169D01*
G01X647560Y481163D02*
X647727Y481288D01*
X647852Y481497D01*
X647935Y481788D01*
X647852Y482038D01*
X647685Y482205D01*
X647394Y482330D01*
X646269D01*
Y479830D01*
X647644D01*
X647935Y479997D01*
X648102Y480247D01*
X648185Y480538D01*
X648102Y480830D01*
X647852Y481080D01*
X647560Y481163D01*
X646269D01*
G01X649535Y481913D02*
X649785Y482163D01*
X650077Y482288D01*
X650410Y482330D01*
X650827Y482247D01*
X651119Y482038D01*
X651202Y481788D01*
X651160Y481538D01*
X650994Y481330D01*
X650160Y480913D01*
X649785Y480622D01*
X649535Y480205D01*
X649452Y479830D01*
X651202D01*
G01X655398Y497701D02*
X655273Y497451D01*
X655190Y497159D01*
Y496826D01*
X655315Y496451D01*
X655523Y496159D01*
X655773Y495951D01*
X656190Y495784D01*
X656565Y495742D01*
X656940Y495826D01*
X657190Y495951D01*
X657440Y496201D01*
X657607Y496492D01*
X657690Y496784D01*
Y497076D01*
X657607Y497367D01*
X657482Y497617D01*
X657315Y497826D01*
G01X657690Y500384D02*
X655190D01*
X656982Y498842D01*
Y500926D01*
G01X656357Y503317D02*
X656232Y503484D01*
X656023Y503609D01*
X655732Y503692D01*
X655482Y503609D01*
X655315Y503442D01*
X655190Y503151D01*
Y502026D01*
X657690D01*
Y503401D01*
X657523Y503692D01*
X657273Y503859D01*
X656982Y503942D01*
X656690Y503859D01*
X656440Y503609D01*
X656357Y503317D01*
Y502026D01*
G01X657690Y506001D02*
X657148Y506084D01*
X656690Y506209D01*
X656273Y506376D01*
X655815Y506584D01*
X655190Y506917D01*
Y505251D01*
G01X659098Y497701D02*
X658973Y497451D01*
X658890Y497159D01*
Y496826D01*
X659015Y496451D01*
X659223Y496159D01*
X659473Y495951D01*
X659890Y495784D01*
X660265Y495742D01*
X660640Y495826D01*
X660890Y495951D01*
X661140Y496201D01*
X661307Y496492D01*
X661390Y496784D01*
Y497076D01*
X661307Y497367D01*
X661182Y497617D01*
X661015Y497826D01*
G01X661390Y500384D02*
X658890D01*
X660682Y498842D01*
Y500926D01*
G01X660057Y503317D02*
X659932Y503484D01*
X659723Y503609D01*
X659432Y503692D01*
X659182Y503609D01*
X659015Y503442D01*
X658890Y503151D01*
Y502026D01*
X661390D01*
Y503401D01*
X661223Y503692D01*
X660973Y503859D01*
X660682Y503942D01*
X660390Y503859D01*
X660140Y503609D01*
X660057Y503317D01*
Y502026D01*
G01X661015Y505167D02*
X661223Y505417D01*
X661348Y505709D01*
X661390Y506084D01*
X661307Y506459D01*
X661140Y506751D01*
X660848Y506959D01*
X660515Y507001D01*
X660182Y506917D01*
X659973Y506709D01*
X659807Y506417D01*
X659765Y506126D01*
X659807Y505834D01*
X659973Y505459D01*
X658890Y505584D01*
Y506709D01*
G01X662898Y497201D02*
X662773Y496951D01*
X662690Y496659D01*
Y496326D01*
X662815Y495951D01*
X663023Y495659D01*
X663273Y495451D01*
X663690Y495284D01*
X664065Y495242D01*
X664440Y495326D01*
X664690Y495451D01*
X664940Y495701D01*
X665107Y495992D01*
X665190Y496284D01*
Y496576D01*
X665107Y496867D01*
X664982Y497117D01*
X664815Y497326D01*
G01X665190Y499884D02*
X662690D01*
X664482Y498342D01*
Y500426D01*
G01X663857Y502817D02*
X663732Y502984D01*
X663523Y503109D01*
X663232Y503192D01*
X662982Y503109D01*
X662815Y502942D01*
X662690Y502651D01*
Y501526D01*
X665190D01*
Y502901D01*
X665023Y503192D01*
X664773Y503359D01*
X664482Y503442D01*
X664190Y503359D01*
X663940Y503109D01*
X663857Y502817D01*
Y501526D01*
G01X664148Y504792D02*
X663857Y505084D01*
X663690Y505334D01*
X663607Y505667D01*
X663690Y505959D01*
X663857Y506167D01*
X664107Y506334D01*
X664398Y506376D01*
X664648Y506334D01*
X664898Y506167D01*
X665107Y505917D01*
X665190Y505626D01*
X665107Y505292D01*
X664857Y505001D01*
X664482Y504834D01*
X664065Y504792D01*
X663523Y504876D01*
X663232Y505001D01*
X662940Y505209D01*
X662732Y505501D01*
X662690Y505792D01*
X662773Y506084D01*
X662982Y506292D01*
G01X618930Y501152D02*
X618680Y501277D01*
X618388Y501360D01*
X618055D01*
X617680Y501235D01*
X617388Y501027D01*
X617180Y500777D01*
X617013Y500360D01*
X616971Y499985D01*
X617055Y499610D01*
X617180Y499360D01*
X617430Y499110D01*
X617721Y498943D01*
X618013Y498860D01*
X618305D01*
X618596Y498943D01*
X618846Y499068D01*
X619055Y499235D01*
G01X620196Y499360D02*
X620446Y499068D01*
X620780Y498902D01*
X621155Y498860D01*
X621488Y498902D01*
X621821Y499110D01*
X622030Y499360D01*
X622071Y499610D01*
X621988Y499902D01*
X621696Y500110D01*
X621405Y500193D01*
X621030D01*
G01X621405D02*
X621655Y500318D01*
X621863Y500527D01*
X621946Y500777D01*
X621863Y501027D01*
X621655Y501235D01*
X621280Y501360D01*
X620905Y501318D01*
X620530Y501152D01*
G01X624546Y500193D02*
X624713Y500318D01*
X624838Y500527D01*
X624921Y500818D01*
X624838Y501068D01*
X624671Y501235D01*
X624380Y501360D01*
X623255D01*
Y498860D01*
X624630D01*
X624921Y499027D01*
X625088Y499277D01*
X625171Y499568D01*
X625088Y499860D01*
X624838Y500110D01*
X624546Y500193D01*
X623255D01*
G01X626396Y499235D02*
X626646Y499027D01*
X626938Y498902D01*
X627313Y498860D01*
X627688Y498943D01*
X627980Y499110D01*
X628188Y499402D01*
X628230Y499735D01*
X628146Y500068D01*
X627938Y500277D01*
X627646Y500443D01*
X627355Y500485D01*
X627063Y500443D01*
X626688Y500277D01*
X626813Y501360D01*
X627938D01*
G01X614930Y504852D02*
X614680Y504977D01*
X614388Y505060D01*
X614055D01*
X613680Y504935D01*
X613388Y504727D01*
X613180Y504477D01*
X613013Y504060D01*
X612971Y503685D01*
X613055Y503310D01*
X613180Y503060D01*
X613430Y502810D01*
X613721Y502643D01*
X614013Y502560D01*
X614305D01*
X614596Y502643D01*
X614846Y502768D01*
X615055Y502935D01*
G01X616196Y503060D02*
X616446Y502768D01*
X616780Y502602D01*
X617155Y502560D01*
X617488Y502602D01*
X617821Y502810D01*
X618030Y503060D01*
X618071Y503310D01*
X617988Y503602D01*
X617696Y503810D01*
X617405Y503893D01*
X617030D01*
G01X617405D02*
X617655Y504018D01*
X617863Y504227D01*
X617946Y504477D01*
X617863Y504727D01*
X617655Y504935D01*
X617280Y505060D01*
X616905Y505018D01*
X616530Y504852D01*
G01X620546Y503893D02*
X620713Y504018D01*
X620838Y504227D01*
X620921Y504518D01*
X620838Y504768D01*
X620671Y504935D01*
X620380Y505060D01*
X619255D01*
Y502560D01*
X620630D01*
X620921Y502727D01*
X621088Y502977D01*
X621171Y503268D01*
X621088Y503560D01*
X620838Y503810D01*
X620546Y503893D01*
X619255D01*
G01X623813Y502560D02*
Y505060D01*
X622271Y503268D01*
X624355D01*
G01X652636Y479000D02*
Y482562D01*
X665432D01*
Y479000D01*
G01X614616Y497485D02*
Y495693D01*
X614783Y495318D01*
X615116Y495068D01*
X615533Y494985D01*
X615950Y495068D01*
X616283Y495318D01*
X616450Y495693D01*
Y497485D01*
G01X617716Y495485D02*
X617966Y495193D01*
X618300Y495027D01*
X618675Y494985D01*
X619008Y495027D01*
X619341Y495235D01*
X619550Y495485D01*
X619591Y495735D01*
X619508Y496027D01*
X619216Y496235D01*
X618925Y496318D01*
X618550D01*
G01X618925D02*
X619175Y496443D01*
X619383Y496652D01*
X619466Y496902D01*
X619383Y497152D01*
X619175Y497360D01*
X618800Y497485D01*
X618425Y497443D01*
X618050Y497277D01*
G01X622066Y496318D02*
X622233Y496443D01*
X622358Y496652D01*
X622441Y496943D01*
X622358Y497193D01*
X622191Y497360D01*
X621900Y497485D01*
X620775D01*
Y494985D01*
X622150D01*
X622441Y495152D01*
X622608Y495402D01*
X622691Y495693D01*
X622608Y495985D01*
X622358Y496235D01*
X622066Y496318D01*
X620775D01*
G01X624833Y494985D02*
Y497485D01*
X624333Y496985D01*
G01Y494985D02*
X625333D01*
G01X629628Y489310D02*
X622256D01*
G01X629627Y477110D02*
X622239D01*
G01X642124Y467654D02*
X643082Y470754D01*
X644040Y467654D01*
G01X643695Y468739D02*
X642469D01*
G01X645454Y470237D02*
X645684Y470547D01*
X645952Y470702D01*
X646259Y470754D01*
X646642Y470651D01*
X646910Y470392D01*
X646987Y470082D01*
X646949Y469772D01*
X646795Y469514D01*
X646029Y468997D01*
X645684Y468636D01*
X645454Y468119D01*
X645377Y467654D01*
X646987D01*
G01X649282Y470754D02*
X648975Y470651D01*
X648745Y470392D01*
X648592Y470082D01*
X648477Y469669D01*
X648439Y469204D01*
X648477Y468739D01*
X648592Y468326D01*
X648745Y468016D01*
X648975Y467757D01*
X649282Y467654D01*
X649589Y467757D01*
X649819Y468016D01*
X649972Y468326D01*
X650087Y468739D01*
X650125Y469204D01*
X650087Y469669D01*
X649972Y470082D01*
X649819Y470392D01*
X649589Y470651D01*
X649282Y470754D01*
G01X620650Y515777D02*
Y518877D01*
X620190Y518257D01*
G01Y515777D02*
X621110D01*
G01X624210D02*
Y518877D01*
X622792Y516655D01*
X624708D01*
G01X627310Y515777D02*
Y518877D01*
X625892Y516655D01*
X627808D01*
G01X621376Y545750D02*
X645766D01*
Y520160D01*
X621376D01*
G01X659732Y565791D02*
Y563291D01*
X661398D01*
G01X664165D02*
Y565791D01*
X662623Y563999D01*
X664707D01*
G01X665723Y563291D02*
X666765Y565791D01*
X667807Y563291D01*
G01X667432Y564166D02*
X666098D01*
G01X669865Y563291D02*
Y565791D01*
X669365Y565291D01*
G01Y563291D02*
X670365D01*
G01X679750Y533650D02*
Y530350D01*
X652950D01*
Y533650D01*
G01Y553850D02*
Y557150D01*
X679750D01*
Y553850D01*
G01X651417Y560859D02*
X651167Y560984D01*
X650875Y561067D01*
X650542D01*
X650167Y560942D01*
X649875Y560734D01*
X649667Y560484D01*
X649500Y560067D01*
X649458Y559692D01*
X649542Y559317D01*
X649667Y559067D01*
X649917Y558817D01*
X650208Y558650D01*
X650500Y558567D01*
X650792D01*
X651083Y558650D01*
X651333Y558775D01*
X651542Y558942D01*
G01X654100Y558567D02*
Y561067D01*
X652558Y559275D01*
X654642D01*
G01X657033Y559900D02*
X657200Y560025D01*
X657325Y560234D01*
X657408Y560525D01*
X657325Y560775D01*
X657158Y560942D01*
X656867Y561067D01*
X655742D01*
Y558567D01*
X657117D01*
X657408Y558734D01*
X657575Y558984D01*
X657658Y559275D01*
X657575Y559567D01*
X657325Y559817D01*
X657033Y559900D01*
X655742D01*
G01X659800Y558567D02*
Y561067D01*
X659300Y560567D01*
G01Y558567D02*
X660300D01*
G01X661983Y558942D02*
X662233Y558734D01*
X662525Y558609D01*
X662900Y558567D01*
X663275Y558650D01*
X663567Y558817D01*
X663775Y559109D01*
X663817Y559442D01*
X663733Y559775D01*
X663525Y559984D01*
X663233Y560150D01*
X662942Y560192D01*
X662650Y560150D01*
X662275Y559984D01*
X662400Y561067D01*
X663525D01*
G01X649004Y572900D02*
X648754Y573025D01*
X648462Y573108D01*
X648129D01*
X647754Y572983D01*
X647462Y572775D01*
X647254Y572525D01*
X647087Y572108D01*
X647045Y571733D01*
X647129Y571358D01*
X647254Y571108D01*
X647504Y570858D01*
X647795Y570691D01*
X648087Y570608D01*
X648379D01*
X648670Y570691D01*
X648920Y570816D01*
X649129Y570983D01*
G01X651687Y570608D02*
Y573108D01*
X650145Y571316D01*
X652229D01*
G01X653245Y570608D02*
X654287Y573108D01*
X655329Y570608D01*
G01X654954Y571483D02*
X653620D01*
G01X657387Y570608D02*
Y573108D01*
X656887Y572608D01*
G01Y570608D02*
X657887D01*
G01X659570Y570983D02*
X659820Y570775D01*
X660112Y570650D01*
X660487Y570608D01*
X660862Y570691D01*
X661154Y570858D01*
X661362Y571150D01*
X661404Y571483D01*
X661320Y571816D01*
X661112Y572025D01*
X660820Y572191D01*
X660529Y572233D01*
X660237Y572191D01*
X659862Y572025D01*
X659987Y573108D01*
X661112D01*
G01X622422Y550460D02*
X622652Y550770D01*
X622920Y550925D01*
X623227Y550977D01*
X623610Y550874D01*
X623878Y550615D01*
X623955Y550305D01*
X623917Y549995D01*
X623763Y549737D01*
X622997Y549220D01*
X622652Y548859D01*
X622422Y548342D01*
X622345Y547877D01*
X623955D01*
G01X626250D02*
X626518Y547929D01*
X626825Y548084D01*
X627017Y548342D01*
X627093Y548704D01*
X627017Y549065D01*
X626787Y549375D01*
X626442Y549530D01*
X626058D01*
X625828Y549634D01*
X625637Y549892D01*
X625560Y550254D01*
X625675Y550615D01*
X625943Y550874D01*
X626250Y550977D01*
X626557Y550874D01*
X626825Y550615D01*
X626940Y550254D01*
X626863Y549892D01*
X626672Y549634D01*
X626442Y549530D01*
X626058D01*
X625713Y549375D01*
X625483Y549065D01*
X625407Y548704D01*
X625483Y548342D01*
X625675Y548084D01*
X625982Y547929D01*
X626250Y547877D01*
G01X629350D02*
X629618Y547929D01*
X629925Y548084D01*
X630117Y548342D01*
X630193Y548704D01*
X630117Y549065D01*
X629887Y549375D01*
X629542Y549530D01*
X629158D01*
X628928Y549634D01*
X628737Y549892D01*
X628660Y550254D01*
X628775Y550615D01*
X629043Y550874D01*
X629350Y550977D01*
X629657Y550874D01*
X629925Y550615D01*
X630040Y550254D01*
X629963Y549892D01*
X629772Y549634D01*
X629542Y549530D01*
X629158D01*
X628813Y549375D01*
X628583Y549065D01*
X628507Y548704D01*
X628583Y548342D01*
X628775Y548084D01*
X629082Y547929D01*
X629350Y547877D01*
G01X622250Y553677D02*
Y556777D01*
X621790Y556157D01*
G01Y553677D02*
X622710D01*
G01X625810D02*
Y556777D01*
X624392Y554555D01*
X626308D01*
G01X628910Y553677D02*
Y556777D01*
X627492Y554555D01*
X629408D01*
G01X621122Y587560D02*
X621352Y587870D01*
X621620Y588025D01*
X621927Y588077D01*
X622310Y587974D01*
X622578Y587715D01*
X622655Y587405D01*
X622617Y587095D01*
X622463Y586837D01*
X621697Y586320D01*
X621352Y585959D01*
X621122Y585442D01*
X621045Y584977D01*
X622655D01*
G01X624950D02*
X625218Y585029D01*
X625525Y585184D01*
X625717Y585442D01*
X625793Y585804D01*
X625717Y586165D01*
X625487Y586475D01*
X625142Y586630D01*
X624758D01*
X624528Y586734D01*
X624337Y586992D01*
X624260Y587354D01*
X624375Y587715D01*
X624643Y587974D01*
X624950Y588077D01*
X625257Y587974D01*
X625525Y587715D01*
X625640Y587354D01*
X625563Y586992D01*
X625372Y586734D01*
X625142Y586630D01*
X624758D01*
X624413Y586475D01*
X624183Y586165D01*
X624107Y585804D01*
X624183Y585442D01*
X624375Y585184D01*
X624682Y585029D01*
X624950Y584977D01*
G01X628050D02*
X628318Y585029D01*
X628625Y585184D01*
X628817Y585442D01*
X628893Y585804D01*
X628817Y586165D01*
X628587Y586475D01*
X628242Y586630D01*
X627858D01*
X627628Y586734D01*
X627437Y586992D01*
X627360Y587354D01*
X627475Y587715D01*
X627743Y587974D01*
X628050Y588077D01*
X628357Y587974D01*
X628625Y587715D01*
X628740Y587354D01*
X628663Y586992D01*
X628472Y586734D01*
X628242Y586630D01*
X627858D01*
X627513Y586475D01*
X627283Y586165D01*
X627207Y585804D01*
X627283Y585442D01*
X627475Y585184D01*
X627782Y585029D01*
X628050Y584977D01*
G01X621376Y583550D02*
X645766D01*
Y557960D01*
X621376D01*
G01X648932Y596141D02*
X648682Y596266D01*
X648390Y596349D01*
X648057D01*
X647682Y596224D01*
X647390Y596016D01*
X647182Y595766D01*
X647015Y595349D01*
X646973Y594974D01*
X647057Y594599D01*
X647182Y594349D01*
X647432Y594099D01*
X647723Y593932D01*
X648015Y593849D01*
X648307D01*
X648598Y593932D01*
X648848Y594057D01*
X649057Y594224D01*
G01X651615Y593849D02*
Y596349D01*
X650073Y594557D01*
X652157D01*
G01X653173Y593849D02*
X654215Y596349D01*
X655257Y593849D01*
G01X654882Y594724D02*
X653548D01*
G01X657315Y593849D02*
Y596349D01*
X656815Y595849D01*
G01Y593849D02*
X657815D01*
G01X659498Y594349D02*
X659748Y594057D01*
X660082Y593891D01*
X660457Y593849D01*
X660790Y593891D01*
X661123Y594099D01*
X661332Y594349D01*
X661373Y594599D01*
X661290Y594891D01*
X660998Y595099D01*
X660707Y595182D01*
X660332D01*
G01X660707D02*
X660957Y595307D01*
X661165Y595516D01*
X661248Y595766D01*
X661165Y596016D01*
X660957Y596224D01*
X660582Y596349D01*
X660207Y596307D01*
X659832Y596141D01*
G01X647182Y600849D02*
Y603349D01*
X648223D01*
X648557Y603224D01*
X648765Y603057D01*
X648848Y602724D01*
X648765Y602391D01*
X648515Y602182D01*
X648223Y602057D01*
X647182D01*
G01X648223D02*
X648848Y600849D01*
G01X651615D02*
Y603349D01*
X650073Y601557D01*
X652157D01*
G01X653173Y600849D02*
X654215Y603349D01*
X655257Y600849D01*
G01X654882Y601724D02*
X653548D01*
G01X656398Y601349D02*
X656648Y601057D01*
X656982Y600891D01*
X657357Y600849D01*
X657690Y600891D01*
X658023Y601099D01*
X658232Y601349D01*
X658273Y601599D01*
X658190Y601891D01*
X657898Y602099D01*
X657607Y602182D01*
X657232D01*
G01X657607D02*
X657857Y602307D01*
X658065Y602516D01*
X658148Y602766D01*
X658065Y603016D01*
X657857Y603224D01*
X657482Y603349D01*
X657107Y603307D01*
X656732Y603141D01*
G01X648932Y599641D02*
X648682Y599766D01*
X648390Y599849D01*
X648057D01*
X647682Y599724D01*
X647390Y599516D01*
X647182Y599266D01*
X647015Y598849D01*
X646973Y598474D01*
X647057Y598099D01*
X647182Y597849D01*
X647432Y597599D01*
X647723Y597432D01*
X648015Y597349D01*
X648307D01*
X648598Y597432D01*
X648848Y597557D01*
X649057Y597724D01*
G01X651615Y597349D02*
Y599849D01*
X650073Y598057D01*
X652157D01*
G01X653173Y597349D02*
X654215Y599849D01*
X655257Y597349D01*
G01X654882Y598224D02*
X653548D01*
G01X656523Y598391D02*
X656815Y598682D01*
X657065Y598849D01*
X657398Y598932D01*
X657690Y598849D01*
X657898Y598682D01*
X658065Y598432D01*
X658107Y598141D01*
X658065Y597891D01*
X657898Y597641D01*
X657648Y597432D01*
X657357Y597349D01*
X657023Y597432D01*
X656732Y597682D01*
X656565Y598057D01*
X656523Y598474D01*
X656607Y599016D01*
X656732Y599307D01*
X656940Y599599D01*
X657232Y599807D01*
X657523Y599849D01*
X657815Y599766D01*
X658023Y599557D01*
G01X650360Y618745D02*
Y616245D01*
G01X649402Y618745D02*
X651318D01*
G01X652585Y616245D02*
Y618745D01*
G01X654335D02*
Y616245D01*
G01Y617495D02*
X652585D01*
G01X657060Y616245D02*
Y618745D01*
X655518Y616953D01*
X657602D01*
G01X658618Y616245D02*
X659660Y618745D01*
X660702Y616245D01*
G01X660327Y617120D02*
X658993D01*
G01X662760Y616245D02*
Y618745D01*
X662260Y618245D01*
G01Y616245D02*
X663260D01*
G01X623150Y590277D02*
Y593377D01*
X622690Y592757D01*
G01Y590277D02*
X623610D01*
G01X626710D02*
Y593377D01*
X625292Y591155D01*
X627208D01*
G01X629810Y590277D02*
Y593377D01*
X628392Y591155D01*
X630308D01*
G01X616962Y624990D02*
X617192Y625300D01*
X617460Y625455D01*
X617767Y625507D01*
X618150Y625404D01*
X618418Y625145D01*
X618495Y624835D01*
X618457Y624525D01*
X618303Y624267D01*
X617537Y623750D01*
X617192Y623389D01*
X616962Y622872D01*
X616885Y622407D01*
X618495D01*
G01X620790D02*
X621058Y622459D01*
X621365Y622614D01*
X621557Y622872D01*
X621633Y623234D01*
X621557Y623595D01*
X621327Y623905D01*
X620982Y624060D01*
X620598D01*
X620368Y624164D01*
X620177Y624422D01*
X620100Y624784D01*
X620215Y625145D01*
X620483Y625404D01*
X620790Y625507D01*
X621097Y625404D01*
X621365Y625145D01*
X621480Y624784D01*
X621403Y624422D01*
X621212Y624164D01*
X620982Y624060D01*
X620598D01*
X620253Y623905D01*
X620023Y623595D01*
X619947Y623234D01*
X620023Y622872D01*
X620215Y622614D01*
X620522Y622459D01*
X620790Y622407D01*
G01X623890D02*
X624158Y622459D01*
X624465Y622614D01*
X624657Y622872D01*
X624733Y623234D01*
X624657Y623595D01*
X624427Y623905D01*
X624082Y624060D01*
X623698D01*
X623468Y624164D01*
X623277Y624422D01*
X623200Y624784D01*
X623315Y625145D01*
X623583Y625404D01*
X623890Y625507D01*
X624197Y625404D01*
X624465Y625145D01*
X624580Y624784D01*
X624503Y624422D01*
X624312Y624164D01*
X624082Y624060D01*
X623698D01*
X623353Y623905D01*
X623123Y623595D01*
X623047Y623234D01*
X623123Y622872D01*
X623315Y622614D01*
X623622Y622459D01*
X623890Y622407D01*
G01X621376Y621350D02*
X645766D01*
Y595760D01*
X621376D01*
G01X602598Y658631D02*
X635298D01*
Y639931D01*
X602598D01*
Y658631D01*
G01X713600Y24600D02*
Y31600D01*
G01X719200D02*
Y24600D01*
G01Y28100D02*
X713600D01*
G01X680700Y21900D02*
Y19800D01*
X688641D01*
G01X689400Y22200D02*
X699900D01*
G01X723850Y12600D02*
X715600D01*
Y15700D01*
X709100D01*
G01X704000Y22200D02*
X706000D01*
Y18600D01*
G01X719000Y-4893D02*
X718750Y-4768D01*
X718458Y-4685D01*
X718125D01*
X717750Y-4810D01*
X717458Y-5018D01*
X717250Y-5268D01*
X717083Y-5685D01*
X717041Y-6060D01*
X717125Y-6435D01*
X717250Y-6685D01*
X717500Y-6935D01*
X717791Y-7102D01*
X718083Y-7185D01*
X718375D01*
X718666Y-7102D01*
X718916Y-6977D01*
X719125Y-6810D01*
G01X721683Y-7185D02*
Y-4685D01*
X720141Y-6477D01*
X722225D01*
G01X724533Y-5935D02*
X725366D01*
Y-6685D01*
X725116Y-6935D01*
X724825Y-7102D01*
X724408Y-7185D01*
X723991Y-7102D01*
X723700Y-6935D01*
X723450Y-6685D01*
X723283Y-6393D01*
X723200Y-6060D01*
Y-5768D01*
X723283Y-5518D01*
X723450Y-5227D01*
X723700Y-4977D01*
X723950Y-4810D01*
X724283Y-4685D01*
X724575D01*
X724908Y-4768D01*
X725158Y-4935D01*
G01X726591Y-5102D02*
X726841Y-4852D01*
X727133Y-4727D01*
X727466Y-4685D01*
X727883Y-4768D01*
X728175Y-4977D01*
X728258Y-5227D01*
X728216Y-5477D01*
X728050Y-5685D01*
X727216Y-6102D01*
X726841Y-6393D01*
X726591Y-6810D01*
X726508Y-7185D01*
X728258D01*
G01X730983D02*
Y-4685D01*
X729441Y-6477D01*
X731525D01*
G01X709099Y-16204D02*
Y-13704D01*
X710140D01*
X710474Y-13829D01*
X710682Y-13996D01*
X710765Y-14329D01*
X710682Y-14662D01*
X710432Y-14871D01*
X710140Y-14996D01*
X709099D01*
G01X710140D02*
X710765Y-16204D01*
G01X713532D02*
Y-13704D01*
X711990Y-15496D01*
X714074D01*
G01X716382Y-14954D02*
X717215D01*
Y-15704D01*
X716965Y-15954D01*
X716674Y-16121D01*
X716257Y-16204D01*
X715840Y-16121D01*
X715549Y-15954D01*
X715299Y-15704D01*
X715132Y-15412D01*
X715049Y-15079D01*
Y-14787D01*
X715132Y-14537D01*
X715299Y-14246D01*
X715549Y-13996D01*
X715799Y-13829D01*
X716132Y-13704D01*
X716424D01*
X716757Y-13787D01*
X717007Y-13954D01*
G01X718440Y-14121D02*
X718690Y-13871D01*
X718982Y-13746D01*
X719315Y-13704D01*
X719732Y-13787D01*
X720024Y-13996D01*
X720107Y-14246D01*
X720065Y-14496D01*
X719899Y-14704D01*
X719065Y-15121D01*
X718690Y-15412D01*
X718440Y-15829D01*
X718357Y-16204D01*
X720107D01*
G01X721415Y-15704D02*
X721665Y-15996D01*
X721999Y-16162D01*
X722374Y-16204D01*
X722707Y-16162D01*
X723040Y-15954D01*
X723249Y-15704D01*
X723290Y-15454D01*
X723207Y-15162D01*
X722915Y-14954D01*
X722624Y-14871D01*
X722249D01*
G01X722624D02*
X722874Y-14746D01*
X723082Y-14537D01*
X723165Y-14287D01*
X723082Y-14037D01*
X722874Y-13829D01*
X722499Y-13704D01*
X722124Y-13746D01*
X721749Y-13912D01*
G01X695717Y12292D02*
X695467Y12417D01*
X695175Y12500D01*
X694842D01*
X694467Y12375D01*
X694175Y12167D01*
X693967Y11917D01*
X693800Y11500D01*
X693758Y11125D01*
X693842Y10750D01*
X693967Y10500D01*
X694217Y10250D01*
X694508Y10083D01*
X694800Y10000D01*
X695092D01*
X695383Y10083D01*
X695633Y10208D01*
X695842Y10375D01*
G01X698400Y10000D02*
Y12500D01*
X696858Y10708D01*
X698942D01*
G01X701250Y11250D02*
X702083D01*
Y10500D01*
X701833Y10250D01*
X701542Y10083D01*
X701125Y10000D01*
X700708Y10083D01*
X700417Y10250D01*
X700167Y10500D01*
X700000Y10792D01*
X699917Y11125D01*
Y11417D01*
X700000Y11667D01*
X700167Y11958D01*
X700417Y12208D01*
X700667Y12375D01*
X701000Y12500D01*
X701292D01*
X701625Y12417D01*
X701875Y12250D01*
G01X704100Y10000D02*
Y12500D01*
X703600Y12000D01*
G01Y10000D02*
X704600D01*
G01X707200D02*
X707492Y10042D01*
X707825Y10167D01*
X708033Y10375D01*
X708117Y10667D01*
X708033Y10958D01*
X707783Y11208D01*
X707408Y11333D01*
X706992D01*
X706742Y11417D01*
X706533Y11625D01*
X706450Y11917D01*
X706575Y12208D01*
X706867Y12417D01*
X707200Y12500D01*
X707533Y12417D01*
X707825Y12208D01*
X707950Y11917D01*
X707867Y11625D01*
X707658Y11417D01*
X707408Y11333D01*
X706992D01*
X706617Y11208D01*
X706367Y10958D01*
X706283Y10667D01*
X706367Y10375D01*
X706575Y10167D01*
X706908Y10042D01*
X707200Y10000D01*
G01X701717Y8792D02*
X701467Y8917D01*
X701175Y9000D01*
X700842D01*
X700467Y8875D01*
X700175Y8667D01*
X699967Y8417D01*
X699800Y8000D01*
X699758Y7625D01*
X699842Y7250D01*
X699967Y7000D01*
X700217Y6750D01*
X700508Y6583D01*
X700800Y6500D01*
X701092D01*
X701383Y6583D01*
X701633Y6708D01*
X701842Y6875D01*
G01X704400Y6500D02*
Y9000D01*
X702858Y7208D01*
X704942D01*
G01X707250Y7750D02*
X708083D01*
Y7000D01*
X707833Y6750D01*
X707542Y6583D01*
X707125Y6500D01*
X706708Y6583D01*
X706417Y6750D01*
X706167Y7000D01*
X706000Y7292D01*
X705917Y7625D01*
Y7917D01*
X706000Y8167D01*
X706167Y8458D01*
X706417Y8708D01*
X706667Y8875D01*
X707000Y9000D01*
X707292D01*
X707625Y8917D01*
X707875Y8750D01*
G01X709308Y8583D02*
X709558Y8833D01*
X709850Y8958D01*
X710183Y9000D01*
X710600Y8917D01*
X710892Y8708D01*
X710975Y8458D01*
X710933Y8208D01*
X710767Y8000D01*
X709933Y7583D01*
X709558Y7292D01*
X709308Y6875D01*
X709225Y6500D01*
X710975D01*
G01X713200D02*
Y9000D01*
X712700Y8500D01*
G01Y6500D02*
X713700D01*
G01X713416Y-18350D02*
X713166Y-18225D01*
X712874Y-18142D01*
X712541D01*
X712166Y-18267D01*
X711874Y-18475D01*
X711666Y-18725D01*
X711499Y-19142D01*
X711457Y-19517D01*
X711541Y-19892D01*
X711666Y-20142D01*
X711916Y-20392D01*
X712207Y-20559D01*
X712499Y-20642D01*
X712791D01*
X713082Y-20559D01*
X713332Y-20434D01*
X713541Y-20267D01*
G01X716099Y-20642D02*
Y-18142D01*
X714557Y-19934D01*
X716641D01*
G01X718949Y-19392D02*
X719782D01*
Y-20142D01*
X719532Y-20392D01*
X719241Y-20559D01*
X718824Y-20642D01*
X718407Y-20559D01*
X718116Y-20392D01*
X717866Y-20142D01*
X717699Y-19850D01*
X717616Y-19517D01*
Y-19225D01*
X717699Y-18975D01*
X717866Y-18684D01*
X718116Y-18434D01*
X718366Y-18267D01*
X718699Y-18142D01*
X718991D01*
X719324Y-18225D01*
X719574Y-18392D01*
G01X721007Y-18559D02*
X721257Y-18309D01*
X721549Y-18184D01*
X721882Y-18142D01*
X722299Y-18225D01*
X722591Y-18434D01*
X722674Y-18684D01*
X722632Y-18934D01*
X722466Y-19142D01*
X721632Y-19559D01*
X721257Y-19850D01*
X721007Y-20267D01*
X720924Y-20642D01*
X722674D01*
G01X723982Y-20142D02*
X724232Y-20434D01*
X724566Y-20600D01*
X724941Y-20642D01*
X725274Y-20600D01*
X725607Y-20392D01*
X725816Y-20142D01*
X725857Y-19892D01*
X725774Y-19600D01*
X725482Y-19392D01*
X725191Y-19309D01*
X724816D01*
G01X725191D02*
X725441Y-19184D01*
X725649Y-18975D01*
X725732Y-18725D01*
X725649Y-18475D01*
X725441Y-18267D01*
X725066Y-18142D01*
X724691Y-18184D01*
X724316Y-18350D01*
G01X695717Y15792D02*
X695467Y15917D01*
X695175Y16000D01*
X694842D01*
X694467Y15875D01*
X694175Y15667D01*
X693967Y15417D01*
X693800Y15000D01*
X693758Y14625D01*
X693842Y14250D01*
X693967Y14000D01*
X694217Y13750D01*
X694508Y13583D01*
X694800Y13500D01*
X695092D01*
X695383Y13583D01*
X695633Y13708D01*
X695842Y13875D01*
G01X698400Y13500D02*
Y16000D01*
X696858Y14208D01*
X698942D01*
G01X701250Y14750D02*
X702083D01*
Y14000D01*
X701833Y13750D01*
X701542Y13583D01*
X701125Y13500D01*
X700708Y13583D01*
X700417Y13750D01*
X700167Y14000D01*
X700000Y14292D01*
X699917Y14625D01*
Y14917D01*
X700000Y15167D01*
X700167Y15458D01*
X700417Y15708D01*
X700667Y15875D01*
X701000Y16000D01*
X701292D01*
X701625Y15917D01*
X701875Y15750D01*
G01X704100Y13500D02*
Y16000D01*
X703600Y15500D01*
G01Y13500D02*
X704600D01*
G01X706283Y14000D02*
X706533Y13708D01*
X706867Y13542D01*
X707242Y13500D01*
X707575Y13542D01*
X707908Y13750D01*
X708117Y14000D01*
X708158Y14250D01*
X708075Y14542D01*
X707783Y14750D01*
X707492Y14833D01*
X707117D01*
G01X707492D02*
X707742Y14958D01*
X707950Y15167D01*
X708033Y15417D01*
X707950Y15667D01*
X707742Y15875D01*
X707367Y16000D01*
X706992Y15958D01*
X706617Y15792D01*
G01X666433Y5067D02*
X664767D01*
Y7567D01*
X666433D01*
G01X665767Y6359D02*
X664767D01*
G01X667783Y7567D02*
Y5775D01*
X667950Y5400D01*
X668283Y5150D01*
X668700Y5067D01*
X669117Y5150D01*
X669450Y5400D01*
X669617Y5775D01*
Y7567D01*
G01X672300Y5067D02*
Y7567D01*
X670758Y5775D01*
X672842D01*
G01X675150Y6317D02*
X675983D01*
Y5567D01*
X675733Y5317D01*
X675442Y5150D01*
X675025Y5067D01*
X674608Y5150D01*
X674317Y5317D01*
X674067Y5567D01*
X673900Y5859D01*
X673817Y6192D01*
Y6484D01*
X673900Y6734D01*
X674067Y7025D01*
X674317Y7275D01*
X674567Y7442D01*
X674900Y7567D01*
X675192D01*
X675525Y7484D01*
X675775Y7317D01*
G01X677208Y7150D02*
X677458Y7400D01*
X677750Y7525D01*
X678083Y7567D01*
X678500Y7484D01*
X678792Y7275D01*
X678875Y7025D01*
X678833Y6775D01*
X678667Y6567D01*
X677833Y6150D01*
X677458Y5859D01*
X677208Y5442D01*
X677125Y5067D01*
X678875D01*
G01X665000Y42999D02*
X665001Y43000D01*
X683000D01*
G01X685000Y38000D02*
Y36700D01*
G01X689600D02*
X697400D01*
G01X706900D02*
X717500D01*
Y47000D01*
G01X719568Y65812D02*
X719443Y65562D01*
X719360Y65270D01*
Y64937D01*
X719485Y64562D01*
X719693Y64270D01*
X719943Y64062D01*
X720360Y63895D01*
X720735Y63853D01*
X721110Y63937D01*
X721360Y64062D01*
X721610Y64312D01*
X721777Y64603D01*
X721860Y64895D01*
Y65187D01*
X721777Y65478D01*
X721652Y65728D01*
X721485Y65937D01*
G01X721860Y68495D02*
X719360D01*
X721152Y66953D01*
Y69037D01*
G01X720610Y71345D02*
Y72178D01*
X721360D01*
X721610Y71928D01*
X721777Y71637D01*
X721860Y71220D01*
X721777Y70803D01*
X721610Y70512D01*
X721360Y70262D01*
X721068Y70095D01*
X720735Y70012D01*
X720443D01*
X720193Y70095D01*
X719902Y70262D01*
X719652Y70512D01*
X719485Y70762D01*
X719360Y71095D01*
Y71387D01*
X719443Y71720D01*
X719610Y71970D01*
G01X719777Y73403D02*
X719527Y73653D01*
X719402Y73945D01*
X719360Y74278D01*
X719443Y74695D01*
X719652Y74987D01*
X719902Y75070D01*
X720152Y75028D01*
X720360Y74862D01*
X720777Y74028D01*
X721068Y73653D01*
X721485Y73403D01*
X721860Y73320D01*
Y75070D01*
G01X705755Y71161D02*
X703255D01*
Y72202D01*
X703380Y72536D01*
X703547Y72744D01*
X703880Y72827D01*
X704213Y72744D01*
X704422Y72494D01*
X704547Y72202D01*
Y71161D01*
G01Y72202D02*
X705755Y72827D01*
G01Y75594D02*
X703255D01*
X705047Y74052D01*
Y76136D01*
G01X705755Y77402D02*
X703255D01*
Y78986D01*
G01X704463Y78402D02*
Y77402D01*
G01X704713Y80502D02*
X704422Y80794D01*
X704255Y81044D01*
X704172Y81377D01*
X704255Y81669D01*
X704422Y81877D01*
X704672Y82044D01*
X704963Y82086D01*
X705213Y82044D01*
X705463Y81877D01*
X705672Y81627D01*
X705755Y81336D01*
X705672Y81002D01*
X705422Y80711D01*
X705047Y80544D01*
X704630Y80502D01*
X704088Y80586D01*
X703797Y80711D01*
X703505Y80919D01*
X703297Y81211D01*
X703255Y81502D01*
X703338Y81794D01*
X703547Y82002D01*
G01X715925Y63415D02*
X715800Y63165D01*
X715717Y62873D01*
Y62540D01*
X715842Y62165D01*
X716050Y61873D01*
X716300Y61665D01*
X716717Y61498D01*
X717092Y61456D01*
X717467Y61540D01*
X717717Y61665D01*
X717967Y61915D01*
X718134Y62206D01*
X718217Y62498D01*
Y62790D01*
X718134Y63081D01*
X718009Y63331D01*
X717842Y63540D01*
G01X718217Y66098D02*
X715717D01*
X717509Y64556D01*
Y66640D01*
G01X716967Y68948D02*
Y69781D01*
X717717D01*
X717967Y69531D01*
X718134Y69240D01*
X718217Y68823D01*
X718134Y68406D01*
X717967Y68115D01*
X717717Y67865D01*
X717425Y67698D01*
X717092Y67615D01*
X716800D01*
X716550Y67698D01*
X716259Y67865D01*
X716009Y68115D01*
X715842Y68365D01*
X715717Y68698D01*
Y68990D01*
X715800Y69323D01*
X715967Y69573D01*
G01X718217Y72298D02*
X715717D01*
X717509Y70756D01*
Y72840D01*
G01X689150Y75833D02*
X688900Y75958D01*
X688608Y76041D01*
X688275D01*
X687900Y75916D01*
X687608Y75708D01*
X687400Y75458D01*
X687233Y75041D01*
X687191Y74666D01*
X687275Y74291D01*
X687400Y74041D01*
X687650Y73791D01*
X687941Y73624D01*
X688233Y73541D01*
X688525D01*
X688816Y73624D01*
X689066Y73749D01*
X689275Y73916D01*
G01X691833Y73541D02*
Y76041D01*
X690291Y74249D01*
X692375D01*
G01X693641Y73541D02*
Y76041D01*
X695225D01*
G01X694641Y74833D02*
X693641D01*
G01X697533Y73541D02*
Y76041D01*
X697033Y75541D01*
G01Y73541D02*
X698033D01*
G01X699841Y75624D02*
X700091Y75874D01*
X700383Y75999D01*
X700716Y76041D01*
X701133Y75958D01*
X701425Y75749D01*
X701508Y75499D01*
X701466Y75249D01*
X701300Y75041D01*
X700466Y74624D01*
X700091Y74333D01*
X699841Y73916D01*
X699758Y73541D01*
X701508D01*
G01X692188Y82924D02*
X692063Y82674D01*
X691980Y82382D01*
Y82049D01*
X692105Y81674D01*
X692313Y81382D01*
X692563Y81174D01*
X692980Y81007D01*
X693355Y80965D01*
X693730Y81049D01*
X693980Y81174D01*
X694230Y81424D01*
X694397Y81715D01*
X694480Y82007D01*
Y82299D01*
X694397Y82590D01*
X694272Y82840D01*
X694105Y83049D01*
G01X694480Y85607D02*
X691980D01*
X693772Y84065D01*
Y86149D01*
G01X694480Y87415D02*
X691980D01*
Y88999D01*
G01X693188Y88415D02*
Y87415D01*
G01X694480Y91307D02*
X691980D01*
X692480Y90807D01*
G01X694480D02*
Y91807D01*
G01Y94407D02*
X691980D01*
X692480Y93907D01*
G01X694480D02*
Y94907D01*
G01X714674Y88788D02*
Y100530D01*
X715316D01*
Y88788D01*
X714674D01*
X714995Y90188D01*
X715316Y88788D01*
G01X710132Y69585D02*
Y67919D01*
X707632D01*
Y69585D01*
G01X708840Y68919D02*
Y67919D01*
G01X707632Y70935D02*
X709424D01*
X709799Y71102D01*
X710049Y71435D01*
X710132Y71852D01*
X710049Y72269D01*
X709799Y72602D01*
X709424Y72769D01*
X707632D01*
G01X710132Y75452D02*
X707632D01*
X709424Y73910D01*
Y75994D01*
G01X708882Y78302D02*
Y79135D01*
X709632D01*
X709882Y78885D01*
X710049Y78594D01*
X710132Y78177D01*
X710049Y77760D01*
X709882Y77469D01*
X709632Y77219D01*
X709340Y77052D01*
X709007Y76969D01*
X708715D01*
X708465Y77052D01*
X708174Y77219D01*
X707924Y77469D01*
X707757Y77719D01*
X707632Y78052D01*
Y78344D01*
X707715Y78677D01*
X707882Y78927D01*
G01X710132Y81152D02*
X707632D01*
X708132Y80652D01*
G01X710132D02*
Y81652D01*
G01X685850Y38850D02*
Y66150D01*
X713150D01*
Y38850D01*
X685850D01*
G01X711705Y41091D02*
Y40295D01*
X710907D01*
G01Y64705D02*
X711705D01*
Y63909D01*
G01X687295D02*
Y64705D01*
X688079D01*
G01Y40295D02*
X687295D01*
Y41091D01*
G01X714049Y106671D02*
Y109171D01*
X715090D01*
X715424Y109046D01*
X715632Y108879D01*
X715715Y108546D01*
X715632Y108213D01*
X715382Y108004D01*
X715090Y107879D01*
X714049D01*
G01X715090D02*
X715715Y106671D01*
G01X717982D02*
Y109171D01*
X717482Y108671D01*
G01Y106671D02*
X718482D01*
G01X720290Y108754D02*
X720540Y109004D01*
X720832Y109129D01*
X721165Y109171D01*
X721582Y109088D01*
X721874Y108879D01*
X721957Y108629D01*
X721915Y108379D01*
X721749Y108171D01*
X720915Y107754D01*
X720540Y107463D01*
X720290Y107046D01*
X720207Y106671D01*
X721957D01*
G01X722932Y109171D02*
X723515Y106671D01*
X724182Y109171D01*
X724849Y106671D01*
X725432Y109171D01*
G01X727782Y106671D02*
Y109171D01*
X726240Y107379D01*
X728324D01*
G01X745500Y138500D02*
X722925D01*
G01X745500Y120500D02*
X722928D01*
G01X710136Y135800D02*
Y139362D01*
X722932D01*
Y135800D01*
G01X710136Y123200D02*
Y119409D01*
X722932D01*
Y123200D01*
G01X681440Y141971D02*
X681190Y142096D01*
X680898Y142179D01*
X680565D01*
X680190Y142054D01*
X679898Y141846D01*
X679690Y141596D01*
X679523Y141179D01*
X679481Y140804D01*
X679565Y140429D01*
X679690Y140179D01*
X679940Y139929D01*
X680231Y139762D01*
X680523Y139679D01*
X680815D01*
X681106Y139762D01*
X681356Y139887D01*
X681565Y140054D01*
G01X684123Y139679D02*
Y142179D01*
X682581Y140387D01*
X684665D01*
G01X685931Y139679D02*
Y142179D01*
X687515D01*
G01X686931Y140971D02*
X685931D01*
G01X688906Y140054D02*
X689156Y139846D01*
X689448Y139721D01*
X689823Y139679D01*
X690198Y139762D01*
X690490Y139929D01*
X690698Y140221D01*
X690740Y140554D01*
X690656Y140887D01*
X690448Y141096D01*
X690156Y141262D01*
X689865Y141304D01*
X689573Y141262D01*
X689198Y141096D01*
X689323Y142179D01*
X690448D01*
G01X671500Y120000D02*
X694075D01*
G01X671500Y138000D02*
X694072D01*
G01X671500D02*
Y135305D01*
G01Y120000D02*
Y122698D01*
G01X706864Y122700D02*
X706865Y119138D01*
X694067D01*
X694068Y122700D01*
G01X706864Y135300D02*
Y139090D01*
X694067Y139091D01*
X694068Y135300D01*
G01X723950Y96316D02*
Y100758D01*
G01X666927Y115149D02*
X666677Y115274D01*
X666385Y115357D01*
X666052D01*
X665677Y115232D01*
X665385Y115024D01*
X665177Y114774D01*
X665010Y114357D01*
X664968Y113982D01*
X665052Y113607D01*
X665177Y113357D01*
X665427Y113107D01*
X665718Y112940D01*
X666010Y112857D01*
X666302D01*
X666593Y112940D01*
X666843Y113065D01*
X667052Y113232D01*
G01X669610Y112857D02*
Y115357D01*
X668068Y113565D01*
X670152D01*
G01X671418Y112857D02*
Y115357D01*
X673002D01*
G01X672418Y114149D02*
X671418D01*
G01X675227Y112857D02*
X675310Y113399D01*
X675435Y113857D01*
X675602Y114274D01*
X675810Y114732D01*
X676143Y115357D01*
X674477D01*
G01X690917Y108037D02*
Y110537D01*
X691958D01*
X692292Y110412D01*
X692500Y110245D01*
X692583Y109912D01*
X692500Y109579D01*
X692250Y109370D01*
X691958Y109245D01*
X690917D01*
G01X691958D02*
X692583Y108037D01*
G01X694850D02*
Y110537D01*
X694350Y110037D01*
G01Y108037D02*
X695350D01*
G01X697158Y110120D02*
X697408Y110370D01*
X697700Y110495D01*
X698033Y110537D01*
X698450Y110454D01*
X698742Y110245D01*
X698825Y109995D01*
X698783Y109745D01*
X698617Y109537D01*
X697783Y109120D01*
X697408Y108829D01*
X697158Y108412D01*
X697075Y108037D01*
X698825D01*
G01X699800Y110537D02*
X700383Y108037D01*
X701050Y110537D01*
X701717Y108037D01*
X702300Y110537D01*
G01X703233Y108537D02*
X703483Y108245D01*
X703817Y108079D01*
X704192Y108037D01*
X704525Y108079D01*
X704858Y108287D01*
X705067Y108537D01*
X705108Y108787D01*
X705025Y109079D01*
X704733Y109287D01*
X704442Y109370D01*
X704067D01*
G01X704442D02*
X704692Y109495D01*
X704900Y109704D01*
X704983Y109954D01*
X704900Y110204D01*
X704692Y110412D01*
X704317Y110537D01*
X703942Y110495D01*
X703567Y110329D01*
G01X698515Y100272D02*
Y96272D01*
X705915D01*
G01X708264Y110419D02*
X707931Y110461D01*
X707639Y110627D01*
X707389Y110877D01*
X707222Y111169D01*
X707139Y111502D01*
Y111836D01*
X707222Y112169D01*
X707389Y112461D01*
X707639Y112711D01*
X707931Y112877D01*
X708264Y112919D01*
X708597Y112877D01*
X708889Y112711D01*
X709139Y112461D01*
X709306Y112169D01*
X709389Y111836D01*
Y111502D01*
X709306Y111169D01*
X709139Y110877D01*
X708889Y110627D01*
X708597Y110461D01*
X708264Y110419D01*
G01X708597Y111086D02*
X709097Y110419D01*
G01X711364D02*
Y112919D01*
X710864Y112419D01*
G01Y110419D02*
X711864D01*
G01X713672Y112502D02*
X713922Y112752D01*
X714214Y112877D01*
X714547Y112919D01*
X714964Y112836D01*
X715256Y112627D01*
X715339Y112377D01*
X715297Y112127D01*
X715131Y111919D01*
X714297Y111502D01*
X713922Y111211D01*
X713672Y110794D01*
X713589Y110419D01*
X715339D01*
G01X716314Y112919D02*
X716897Y110419D01*
X717564Y112919D01*
X718231Y110419D01*
X718814Y112919D01*
G01X720664Y110419D02*
Y112919D01*
X720164Y112419D01*
G01Y110419D02*
X721164D01*
G01X725199Y194950D02*
Y197450D01*
X726240D01*
X726574Y197325D01*
X726782Y197158D01*
X726865Y196825D01*
X726782Y196492D01*
X726532Y196283D01*
X726240Y196158D01*
X725199D01*
G01X726240D02*
X726865Y194950D01*
G01X729132Y197450D02*
Y194950D01*
G01X728174Y197450D02*
X730090D01*
G01X732732Y194950D02*
Y197450D01*
X731190Y195658D01*
X733274D01*
G01X735332Y194950D02*
Y197450D01*
X734832Y196950D01*
G01Y194950D02*
X735832D01*
G01X722714Y203324D02*
X722464Y203449D01*
X722172Y203532D01*
X721839D01*
X721464Y203407D01*
X721172Y203199D01*
X720964Y202949D01*
X720797Y202532D01*
X720755Y202157D01*
X720839Y201782D01*
X720964Y201532D01*
X721214Y201282D01*
X721505Y201115D01*
X721797Y201032D01*
X722089D01*
X722380Y201115D01*
X722630Y201240D01*
X722839Y201407D01*
G01X724897Y203532D02*
Y201032D01*
G01X723939Y203532D02*
X725855D01*
G01X727205Y202074D02*
X727497Y202365D01*
X727747Y202532D01*
X728080Y202615D01*
X728372Y202532D01*
X728580Y202365D01*
X728747Y202115D01*
X728789Y201824D01*
X728747Y201574D01*
X728580Y201324D01*
X728330Y201115D01*
X728039Y201032D01*
X727705Y201115D01*
X727414Y201365D01*
X727247Y201740D01*
X727205Y202157D01*
X727289Y202699D01*
X727414Y202990D01*
X727622Y203282D01*
X727914Y203490D01*
X728205Y203532D01*
X728497Y203449D01*
X728705Y203240D01*
G01X731097Y201032D02*
Y203532D01*
X730597Y203032D01*
G01Y201032D02*
X731597D01*
G01X683031Y200887D02*
X682781Y201012D01*
X682489Y201095D01*
X682156D01*
X681781Y200970D01*
X681489Y200762D01*
X681281Y200512D01*
X681114Y200095D01*
X681072Y199720D01*
X681156Y199345D01*
X681281Y199095D01*
X681531Y198845D01*
X681822Y198678D01*
X682114Y198595D01*
X682406D01*
X682697Y198678D01*
X682947Y198803D01*
X683156Y198970D01*
G01X685714Y198595D02*
Y201095D01*
X684172Y199303D01*
X686256D01*
G01X689147Y198595D02*
X687481D01*
Y201095D01*
X689147D01*
G01X688481Y199887D02*
X687481D01*
G01X691414Y198595D02*
Y201095D01*
X690914Y200595D01*
G01Y198595D02*
X691914D01*
G01X693597Y199095D02*
X693847Y198803D01*
X694181Y198637D01*
X694556Y198595D01*
X694889Y198637D01*
X695222Y198845D01*
X695431Y199095D01*
X695472Y199345D01*
X695389Y199637D01*
X695097Y199845D01*
X694806Y199928D01*
X694431D01*
G01X694806D02*
X695056Y200053D01*
X695264Y200262D01*
X695347Y200512D01*
X695264Y200762D01*
X695056Y200970D01*
X694681Y201095D01*
X694306Y201053D01*
X693931Y200887D01*
G01X679334Y183225D02*
X679209Y182975D01*
X679126Y182683D01*
Y182350D01*
X679251Y181975D01*
X679459Y181683D01*
X679709Y181475D01*
X680126Y181308D01*
X680501Y181266D01*
X680876Y181350D01*
X681126Y181475D01*
X681376Y181725D01*
X681543Y182016D01*
X681626Y182308D01*
Y182600D01*
X681543Y182891D01*
X681418Y183141D01*
X681251Y183350D01*
G01X681626Y185908D02*
X679126D01*
X680918Y184366D01*
Y186450D01*
G01X681626Y189341D02*
Y187675D01*
X679126D01*
Y189341D01*
G01X680334Y188675D02*
Y187675D01*
G01X679543Y190816D02*
X679293Y191066D01*
X679168Y191358D01*
X679126Y191691D01*
X679209Y192108D01*
X679418Y192400D01*
X679668Y192483D01*
X679918Y192441D01*
X680126Y192275D01*
X680543Y191441D01*
X680834Y191066D01*
X681251Y190816D01*
X681626Y190733D01*
Y192483D01*
G01Y195208D02*
X679126D01*
X680918Y193666D01*
Y195750D01*
G01X688000Y179300D02*
X710575D01*
G01X688000Y197300D02*
X710572D01*
G01X688000D02*
Y194605D01*
G01Y179300D02*
Y181998D01*
G01X723364Y182000D02*
Y178438D01*
X710568D01*
Y182000D01*
G01X723364Y194600D02*
Y198391D01*
X710568D01*
Y194600D01*
G01X672500Y179500D02*
Y182195D01*
G01Y197500D02*
Y194802D01*
G01X684334Y208233D02*
Y206567D01*
X681834D01*
Y208233D01*
G01X683042Y207567D02*
Y206567D01*
G01X681834Y209583D02*
X683626D01*
X684001Y209750D01*
X684251Y210083D01*
X684334Y210500D01*
X684251Y210917D01*
X684001Y211250D01*
X683626Y211417D01*
X681834D01*
G01X684334Y214100D02*
X681834D01*
X683626Y212558D01*
Y214642D01*
G01X684334Y217533D02*
Y215867D01*
X681834D01*
Y217533D01*
G01X683042Y216867D02*
Y215867D01*
G01X682251Y219008D02*
X682001Y219258D01*
X681876Y219550D01*
X681834Y219883D01*
X681917Y220300D01*
X682126Y220592D01*
X682376Y220675D01*
X682626Y220633D01*
X682834Y220467D01*
X683251Y219633D01*
X683542Y219258D01*
X683959Y219008D01*
X684334Y218925D01*
Y220675D01*
G01X685061Y225817D02*
X712361D01*
Y202267D01*
X685061D01*
Y225817D01*
G01X678634Y206445D02*
Y200397D01*
G01X719900Y225300D02*
X732900D01*
G01X712700Y232100D02*
X719200D01*
Y229100D01*
G01X710700Y240500D02*
Y232800D01*
G01X702487Y250780D02*
X709063D01*
Y246200D01*
G01X701815Y256467D02*
Y274127D01*
X708166D01*
Y285461D01*
G01X692979Y279483D02*
X692729Y279608D01*
X692437Y279691D01*
X692104D01*
X691729Y279566D01*
X691437Y279358D01*
X691229Y279108D01*
X691062Y278691D01*
X691020Y278316D01*
X691104Y277941D01*
X691229Y277691D01*
X691479Y277441D01*
X691770Y277274D01*
X692062Y277191D01*
X692354D01*
X692645Y277274D01*
X692895Y277399D01*
X693104Y277566D01*
G01X695662Y277191D02*
Y279691D01*
X694120Y277899D01*
X696204D01*
G01X697345Y277191D02*
Y279691D01*
X698179D01*
X698512Y279566D01*
X698762Y279399D01*
X698970Y279149D01*
X699137Y278858D01*
X699179Y278441D01*
X699137Y278024D01*
X698970Y277733D01*
X698762Y277483D01*
X698512Y277316D01*
X698179Y277191D01*
X697345D01*
G01X700570Y279274D02*
X700820Y279524D01*
X701112Y279649D01*
X701445Y279691D01*
X701862Y279608D01*
X702154Y279399D01*
X702237Y279149D01*
X702195Y278899D01*
X702029Y278691D01*
X701195Y278274D01*
X700820Y277983D01*
X700570Y277566D01*
X700487Y277191D01*
X702237D01*
G01X703545Y277566D02*
X703795Y277358D01*
X704087Y277233D01*
X704462Y277191D01*
X704837Y277274D01*
X705129Y277441D01*
X705337Y277733D01*
X705379Y278066D01*
X705295Y278399D01*
X705087Y278608D01*
X704795Y278774D01*
X704504Y278816D01*
X704212Y278774D01*
X703837Y278608D01*
X703962Y279691D01*
X705087D01*
G01X706732Y233097D02*
X706607Y232847D01*
X706524Y232555D01*
Y232222D01*
X706649Y231847D01*
X706857Y231555D01*
X707107Y231347D01*
X707524Y231180D01*
X707899Y231138D01*
X708274Y231222D01*
X708524Y231347D01*
X708774Y231597D01*
X708941Y231888D01*
X709024Y232180D01*
Y232472D01*
X708941Y232763D01*
X708816Y233013D01*
X708649Y233222D01*
G01X706524Y235280D02*
X709024D01*
G01X706524Y234322D02*
Y236238D01*
G01X707982Y237588D02*
X707691Y237880D01*
X707524Y238130D01*
X707441Y238463D01*
X707524Y238755D01*
X707691Y238963D01*
X707941Y239130D01*
X708232Y239172D01*
X708482Y239130D01*
X708732Y238963D01*
X708941Y238713D01*
X709024Y238422D01*
X708941Y238088D01*
X708691Y237797D01*
X708316Y237630D01*
X707899Y237588D01*
X707357Y237672D01*
X707066Y237797D01*
X706774Y238005D01*
X706566Y238297D01*
X706524Y238588D01*
X706607Y238880D01*
X706816Y239088D01*
G01X708524Y240563D02*
X708816Y240813D01*
X708982Y241147D01*
X709024Y241522D01*
X708982Y241855D01*
X708774Y242188D01*
X708524Y242397D01*
X708274Y242438D01*
X707982Y242355D01*
X707774Y242063D01*
X707691Y241772D01*
Y241397D01*
G01Y241772D02*
X707566Y242022D01*
X707357Y242230D01*
X707107Y242313D01*
X706857Y242230D01*
X706649Y242022D01*
X706524Y241647D01*
X706566Y241272D01*
X706732Y240897D01*
G01X702888Y233275D02*
X702763Y233025D01*
X702680Y232733D01*
Y232400D01*
X702805Y232025D01*
X703013Y231733D01*
X703263Y231525D01*
X703680Y231358D01*
X704055Y231316D01*
X704430Y231400D01*
X704680Y231525D01*
X704930Y231775D01*
X705097Y232066D01*
X705180Y232358D01*
Y232650D01*
X705097Y232941D01*
X704972Y233191D01*
X704805Y233400D01*
G01X705180Y235958D02*
X702680D01*
X704472Y234416D01*
Y236500D01*
G01X705180Y239391D02*
Y237725D01*
X702680D01*
Y239391D01*
G01X703888Y238725D02*
Y237725D01*
G01X703097Y240866D02*
X702847Y241116D01*
X702722Y241408D01*
X702680Y241741D01*
X702763Y242158D01*
X702972Y242450D01*
X703222Y242533D01*
X703472Y242491D01*
X703680Y242325D01*
X704097Y241491D01*
X704388Y241116D01*
X704805Y240866D01*
X705180Y240783D01*
Y242533D01*
G01X703097Y243966D02*
X702847Y244216D01*
X702722Y244508D01*
X702680Y244841D01*
X702763Y245258D01*
X702972Y245550D01*
X703222Y245633D01*
X703472Y245591D01*
X703680Y245425D01*
X704097Y244591D01*
X704388Y244216D01*
X704805Y243966D01*
X705180Y243883D01*
Y245633D01*
G01X698418Y234080D02*
X698293Y233830D01*
X698210Y233538D01*
Y233205D01*
X698335Y232830D01*
X698543Y232538D01*
X698793Y232330D01*
X699210Y232163D01*
X699585Y232121D01*
X699960Y232205D01*
X700210Y232330D01*
X700460Y232580D01*
X700627Y232871D01*
X700710Y233163D01*
Y233455D01*
X700627Y233746D01*
X700502Y233996D01*
X700335Y234205D01*
G01X700710Y236763D02*
X698210D01*
X700002Y235221D01*
Y237305D01*
G01X700710Y240196D02*
Y238530D01*
X698210D01*
Y240196D01*
G01X699418Y239530D02*
Y238530D01*
G01X698627Y241671D02*
X698377Y241921D01*
X698252Y242213D01*
X698210Y242546D01*
X698293Y242963D01*
X698502Y243255D01*
X698752Y243338D01*
X699002Y243296D01*
X699210Y243130D01*
X699627Y242296D01*
X699918Y241921D01*
X700335Y241671D01*
X700710Y241588D01*
Y243338D01*
G01X700210Y244646D02*
X700502Y244896D01*
X700668Y245230D01*
X700710Y245605D01*
X700668Y245938D01*
X700460Y246271D01*
X700210Y246480D01*
X699960Y246521D01*
X699668Y246438D01*
X699460Y246146D01*
X699377Y245855D01*
Y245480D01*
G01Y245855D02*
X699252Y246105D01*
X699043Y246313D01*
X698793Y246396D01*
X698543Y246313D01*
X698335Y246105D01*
X698210Y245730D01*
X698252Y245355D01*
X698418Y244980D01*
G01X678500Y248900D02*
Y246202D01*
G01Y230900D02*
Y233595D01*
G01X686866Y230744D02*
X684366D01*
Y231785D01*
X684491Y232119D01*
X684658Y232327D01*
X684991Y232410D01*
X685324Y232327D01*
X685533Y232077D01*
X685658Y231785D01*
Y230744D01*
G01Y231785D02*
X686866Y232410D01*
G01X684366Y234677D02*
X686866D01*
G01X684366Y233719D02*
Y235635D01*
G01X686866Y238277D02*
X684366D01*
X686158Y236735D01*
Y238819D01*
G01X684783Y240085D02*
X684533Y240335D01*
X684408Y240627D01*
X684366Y240960D01*
X684449Y241377D01*
X684658Y241669D01*
X684908Y241752D01*
X685158Y241710D01*
X685366Y241544D01*
X685783Y240710D01*
X686074Y240335D01*
X686491Y240085D01*
X686866Y240002D01*
Y241752D01*
G01X689274Y241662D02*
X689149Y241412D01*
X689066Y241120D01*
Y240787D01*
X689191Y240412D01*
X689399Y240120D01*
X689649Y239912D01*
X690066Y239745D01*
X690441Y239703D01*
X690816Y239787D01*
X691066Y239912D01*
X691316Y240162D01*
X691483Y240453D01*
X691566Y240745D01*
Y241037D01*
X691483Y241328D01*
X691358Y241578D01*
X691191Y241787D01*
G01X689483Y243053D02*
X689233Y243303D01*
X689108Y243595D01*
X689066Y243928D01*
X689149Y244345D01*
X689358Y244637D01*
X689608Y244720D01*
X689858Y244678D01*
X690066Y244512D01*
X690483Y243678D01*
X690774Y243303D01*
X691191Y243053D01*
X691566Y242970D01*
Y244720D01*
G01X689483Y246153D02*
X689233Y246403D01*
X689108Y246695D01*
X689066Y247028D01*
X689149Y247445D01*
X689358Y247737D01*
X689608Y247820D01*
X689858Y247778D01*
X690066Y247612D01*
X690483Y246778D01*
X690774Y246403D01*
X691191Y246153D01*
X691566Y246070D01*
Y247820D01*
G01X689066Y248795D02*
X691566Y249378D01*
X689066Y250045D01*
X691566Y250712D01*
X689066Y251295D01*
G01X691566Y253145D02*
X689066D01*
X689566Y252645D01*
G01X691566D02*
Y253645D01*
G01X691274Y255537D02*
X691483Y255828D01*
X691566Y256162D01*
X691483Y256495D01*
X691233Y256787D01*
X690858Y256995D01*
X690483Y257078D01*
X690024D01*
X689649Y256995D01*
X689316Y256787D01*
X689149Y256537D01*
X689066Y256245D01*
X689149Y255912D01*
X689316Y255662D01*
X689566Y255495D01*
X689899Y255412D01*
X690191Y255495D01*
X690483Y255703D01*
X690649Y255953D01*
X690691Y256245D01*
X690608Y256578D01*
X690399Y256828D01*
X690024Y257078D01*
G01X711700Y288800D02*
X739300D01*
Y261200D01*
X711700D01*
Y288800D01*
G01X714673Y263189D02*
X713689D01*
Y264173D01*
G01X675130Y273039D02*
X676139D01*
Y271857D01*
G01Y254159D02*
Y252961D01*
X674991D01*
G01X688500Y311500D02*
Y309900D01*
G01Y306800D02*
Y298201D01*
X688501Y298200D01*
X703099D01*
X703100Y298201D01*
Y320400D01*
X713600D01*
Y323900D01*
X721800D01*
G01X722500Y337900D02*
Y346200D01*
X720601D01*
X720600Y346201D01*
Y381699D01*
X720599Y381700D01*
X708900D01*
Y370300D01*
X696500D01*
Y358988D01*
G01X718246Y289910D02*
X727725D01*
G01X696500Y344732D02*
Y339500D01*
X688501D01*
X688500Y339499D01*
Y313200D01*
G01X707235Y316089D02*
Y318589D01*
X708276D01*
X708610Y318464D01*
X708818Y318297D01*
X708901Y317964D01*
X708818Y317631D01*
X708568Y317422D01*
X708276Y317297D01*
X707235D01*
G01X708276D02*
X708901Y316089D01*
G01X711668D02*
Y318589D01*
X710126Y316797D01*
X712210D01*
G01X713351Y316089D02*
Y318589D01*
X714185D01*
X714518Y318464D01*
X714768Y318297D01*
X714976Y318047D01*
X715143Y317756D01*
X715185Y317339D01*
X715143Y316922D01*
X714976Y316631D01*
X714768Y316381D01*
X714518Y316214D01*
X714185Y316089D01*
X713351D01*
G01X716576Y318172D02*
X716826Y318422D01*
X717118Y318547D01*
X717451Y318589D01*
X717868Y318506D01*
X718160Y318297D01*
X718243Y318047D01*
X718201Y317797D01*
X718035Y317589D01*
X717201Y317172D01*
X716826Y316881D01*
X716576Y316464D01*
X716493Y316089D01*
X718243D01*
G01X720385D02*
X720468Y316631D01*
X720593Y317089D01*
X720760Y317506D01*
X720968Y317964D01*
X721301Y318589D01*
X719635D01*
G01X724900Y308867D02*
X722400D01*
Y309908D01*
X722525Y310242D01*
X722692Y310450D01*
X723025Y310533D01*
X723358Y310450D01*
X723567Y310200D01*
X723692Y309908D01*
Y308867D01*
G01Y309908D02*
X724900Y310533D01*
G01Y313300D02*
X722400D01*
X724192Y311758D01*
Y313842D01*
G01X724900Y314983D02*
X722400D01*
Y315817D01*
X722525Y316150D01*
X722692Y316400D01*
X722942Y316608D01*
X723233Y316775D01*
X723650Y316817D01*
X724067Y316775D01*
X724358Y316608D01*
X724608Y316400D01*
X724775Y316150D01*
X724900Y315817D01*
Y314983D01*
G01X722817Y318208D02*
X722567Y318458D01*
X722442Y318750D01*
X722400Y319083D01*
X722483Y319500D01*
X722692Y319792D01*
X722942Y319875D01*
X723192Y319833D01*
X723400Y319667D01*
X723817Y318833D01*
X724108Y318458D01*
X724525Y318208D01*
X724900Y318125D01*
Y319875D01*
G01X723858Y321308D02*
X723567Y321600D01*
X723400Y321850D01*
X723317Y322183D01*
X723400Y322475D01*
X723567Y322683D01*
X723817Y322850D01*
X724108Y322892D01*
X724358Y322850D01*
X724608Y322683D01*
X724817Y322433D01*
X724900Y322142D01*
X724817Y321808D01*
X724567Y321517D01*
X724192Y321350D01*
X723775Y321308D01*
X723233Y321392D01*
X722942Y321517D01*
X722650Y321725D01*
X722442Y322017D01*
X722400Y322308D01*
X722483Y322600D01*
X722692Y322808D01*
G01X705175Y339902D02*
Y342402D01*
X706216D01*
X706550Y342277D01*
X706758Y342110D01*
X706841Y341777D01*
X706758Y341444D01*
X706508Y341235D01*
X706216Y341110D01*
X705175D01*
G01X706216D02*
X706841Y339902D01*
G01X709608D02*
Y342402D01*
X708066Y340610D01*
X710150D01*
G01X711291Y339902D02*
Y342402D01*
X712125D01*
X712458Y342277D01*
X712708Y342110D01*
X712916Y341860D01*
X713083Y341569D01*
X713125Y341152D01*
X713083Y340735D01*
X712916Y340444D01*
X712708Y340194D01*
X712458Y340027D01*
X712125Y339902D01*
X711291D01*
G01X714516Y341985D02*
X714766Y342235D01*
X715058Y342360D01*
X715391Y342402D01*
X715808Y342319D01*
X716100Y342110D01*
X716183Y341860D01*
X716141Y341610D01*
X715975Y341402D01*
X715141Y340985D01*
X714766Y340694D01*
X714516Y340277D01*
X714433Y339902D01*
X716183D01*
G01X717616Y341985D02*
X717866Y342235D01*
X718158Y342360D01*
X718491Y342402D01*
X718908Y342319D01*
X719200Y342110D01*
X719283Y341860D01*
X719241Y341610D01*
X719075Y341402D01*
X718241Y340985D01*
X717866Y340694D01*
X717616Y340277D01*
X717533Y339902D01*
X719283D01*
G01X710556Y322804D02*
X708056D01*
Y323845D01*
X708181Y324179D01*
X708348Y324387D01*
X708681Y324470D01*
X709014Y324387D01*
X709223Y324137D01*
X709348Y323845D01*
Y322804D01*
G01Y323845D02*
X710556Y324470D01*
G01Y327237D02*
X708056D01*
X709848Y325695D01*
Y327779D01*
G01X710556Y328920D02*
X708056D01*
Y329754D01*
X708181Y330087D01*
X708348Y330337D01*
X708598Y330545D01*
X708889Y330712D01*
X709306Y330754D01*
X709723Y330712D01*
X710014Y330545D01*
X710264Y330337D01*
X710431Y330087D01*
X710556Y329754D01*
Y328920D01*
G01X708473Y332145D02*
X708223Y332395D01*
X708098Y332687D01*
X708056Y333020D01*
X708139Y333437D01*
X708348Y333729D01*
X708598Y333812D01*
X708848Y333770D01*
X709056Y333604D01*
X709473Y332770D01*
X709764Y332395D01*
X710181Y332145D01*
X710556Y332062D01*
Y333812D01*
G01Y336537D02*
X708056D01*
X709848Y334995D01*
Y337079D01*
G01X699540Y295673D02*
X699290Y295798D01*
X698998Y295881D01*
X698665D01*
X698290Y295756D01*
X697998Y295548D01*
X697790Y295298D01*
X697623Y294881D01*
X697581Y294506D01*
X697665Y294131D01*
X697790Y293881D01*
X698040Y293631D01*
X698331Y293464D01*
X698623Y293381D01*
X698915D01*
X699206Y293464D01*
X699456Y293589D01*
X699665Y293756D01*
G01X702223Y293381D02*
Y295881D01*
X700681Y294089D01*
X702765D01*
G01X703906Y293381D02*
Y295881D01*
X704740D01*
X705073Y295756D01*
X705323Y295589D01*
X705531Y295339D01*
X705698Y295048D01*
X705740Y294631D01*
X705698Y294214D01*
X705531Y293923D01*
X705323Y293673D01*
X705073Y293506D01*
X704740Y293381D01*
X703906D01*
G01X707923D02*
Y295881D01*
X707423Y295381D01*
G01Y293381D02*
X708423D01*
G01X710315Y293673D02*
X710606Y293464D01*
X710940Y293381D01*
X711273Y293464D01*
X711565Y293714D01*
X711773Y294089D01*
X711856Y294464D01*
Y294923D01*
X711773Y295298D01*
X711565Y295631D01*
X711315Y295798D01*
X711023Y295881D01*
X710690Y295798D01*
X710440Y295631D01*
X710273Y295381D01*
X710190Y295048D01*
X710273Y294756D01*
X710481Y294464D01*
X710731Y294298D01*
X711023Y294256D01*
X711356Y294339D01*
X711606Y294548D01*
X711856Y294923D01*
G01X693290Y283748D02*
X693040Y283873D01*
X692748Y283956D01*
X692415D01*
X692040Y283831D01*
X691748Y283623D01*
X691540Y283373D01*
X691373Y282956D01*
X691331Y282581D01*
X691415Y282206D01*
X691540Y281956D01*
X691790Y281706D01*
X692081Y281539D01*
X692373Y281456D01*
X692665D01*
X692956Y281539D01*
X693206Y281664D01*
X693415Y281831D01*
G01X695973Y281456D02*
Y283956D01*
X694431Y282164D01*
X696515D01*
G01X697656Y281456D02*
Y283956D01*
X698490D01*
X698823Y283831D01*
X699073Y283664D01*
X699281Y283414D01*
X699448Y283123D01*
X699490Y282706D01*
X699448Y282289D01*
X699281Y281998D01*
X699073Y281748D01*
X698823Y281581D01*
X698490Y281456D01*
X697656D01*
G01X700881Y283539D02*
X701131Y283789D01*
X701423Y283914D01*
X701756Y283956D01*
X702173Y283873D01*
X702465Y283664D01*
X702548Y283414D01*
X702506Y283164D01*
X702340Y282956D01*
X701506Y282539D01*
X701131Y282248D01*
X700881Y281831D01*
X700798Y281456D01*
X702548D01*
G01X703981Y282498D02*
X704273Y282789D01*
X704523Y282956D01*
X704856Y283039D01*
X705148Y282956D01*
X705356Y282789D01*
X705523Y282539D01*
X705565Y282248D01*
X705523Y281998D01*
X705356Y281748D01*
X705106Y281539D01*
X704815Y281456D01*
X704481Y281539D01*
X704190Y281789D01*
X704023Y282164D01*
X703981Y282581D01*
X704065Y283123D01*
X704190Y283414D01*
X704398Y283706D01*
X704690Y283914D01*
X704981Y283956D01*
X705273Y283873D01*
X705481Y283664D01*
G01X713689Y285827D02*
Y286811D01*
X714673D01*
G01X696500Y349503D02*
Y347655D01*
G01X697536Y352094D02*
Y354594D01*
X698577D01*
X698911Y354469D01*
X699119Y354302D01*
X699202Y353969D01*
X699119Y353636D01*
X698869Y353427D01*
X698577Y353302D01*
X697536D01*
G01X698577D02*
X699202Y352094D01*
G01X701969D02*
Y354594D01*
X700427Y352802D01*
X702511D01*
G01X703652Y352094D02*
Y354594D01*
X704486D01*
X704819Y354469D01*
X705069Y354302D01*
X705277Y354052D01*
X705444Y353761D01*
X705486Y353344D01*
X705444Y352927D01*
X705277Y352636D01*
X705069Y352386D01*
X704819Y352219D01*
X704486Y352094D01*
X703652D01*
G01X706877Y354177D02*
X707127Y354427D01*
X707419Y354552D01*
X707752Y354594D01*
X708169Y354511D01*
X708461Y354302D01*
X708544Y354052D01*
X708502Y353802D01*
X708336Y353594D01*
X707502Y353177D01*
X707127Y352886D01*
X706877Y352469D01*
X706794Y352094D01*
X708544D01*
G01X709852Y352469D02*
X710102Y352261D01*
X710394Y352136D01*
X710769Y352094D01*
X711144Y352177D01*
X711436Y352344D01*
X711644Y352636D01*
X711686Y352969D01*
X711602Y353302D01*
X711394Y353511D01*
X711102Y353677D01*
X710811Y353719D01*
X710519Y353677D01*
X710144Y353511D01*
X710269Y354594D01*
X711394D01*
G01X697967Y348500D02*
Y351000D01*
X699008D01*
X699342Y350875D01*
X699550Y350708D01*
X699633Y350375D01*
X699550Y350042D01*
X699300Y349833D01*
X699008Y349708D01*
X697967D01*
G01X699008D02*
X699633Y348500D01*
G01X702400D02*
Y351000D01*
X700858Y349208D01*
X702942D01*
G01X704083Y348500D02*
Y351000D01*
X704917D01*
X705250Y350875D01*
X705500Y350708D01*
X705708Y350458D01*
X705875Y350167D01*
X705917Y349750D01*
X705875Y349333D01*
X705708Y349042D01*
X705500Y348792D01*
X705250Y348625D01*
X704917Y348500D01*
X704083D01*
G01X707308Y350583D02*
X707558Y350833D01*
X707850Y350958D01*
X708183Y351000D01*
X708600Y350917D01*
X708892Y350708D01*
X708975Y350458D01*
X708933Y350208D01*
X708767Y350000D01*
X707933Y349583D01*
X707558Y349292D01*
X707308Y348875D01*
X707225Y348500D01*
X708975D01*
G01X710492Y348792D02*
X710783Y348583D01*
X711117Y348500D01*
X711450Y348583D01*
X711742Y348833D01*
X711950Y349208D01*
X712033Y349583D01*
Y350042D01*
X711950Y350417D01*
X711742Y350750D01*
X711492Y350917D01*
X711200Y351000D01*
X710867Y350917D01*
X710617Y350750D01*
X710450Y350500D01*
X710367Y350167D01*
X710450Y349875D01*
X710658Y349583D01*
X710908Y349417D01*
X711200Y349375D01*
X711533Y349458D01*
X711783Y349667D01*
X712033Y350042D01*
G01X697536Y362594D02*
Y365094D01*
X698577D01*
X698911Y364969D01*
X699119Y364802D01*
X699202Y364469D01*
X699119Y364136D01*
X698869Y363927D01*
X698577Y363802D01*
X697536D01*
G01X698577D02*
X699202Y362594D01*
G01X701969D02*
Y365094D01*
X700427Y363302D01*
X702511D01*
G01X703652Y362594D02*
Y365094D01*
X704486D01*
X704819Y364969D01*
X705069Y364802D01*
X705277Y364552D01*
X705444Y364261D01*
X705486Y363844D01*
X705444Y363427D01*
X705277Y363136D01*
X705069Y362886D01*
X704819Y362719D01*
X704486Y362594D01*
X703652D01*
G01X707669D02*
Y365094D01*
X707169Y364594D01*
G01Y362594D02*
X708169D01*
G01X709977Y364677D02*
X710227Y364927D01*
X710519Y365052D01*
X710852Y365094D01*
X711269Y365011D01*
X711561Y364802D01*
X711644Y364552D01*
X711602Y364302D01*
X711436Y364094D01*
X710602Y363677D01*
X710227Y363386D01*
X709977Y362969D01*
X709894Y362594D01*
X711644D01*
G01X697536Y366094D02*
Y368594D01*
X698577D01*
X698911Y368469D01*
X699119Y368302D01*
X699202Y367969D01*
X699119Y367636D01*
X698869Y367427D01*
X698577Y367302D01*
X697536D01*
G01X698577D02*
X699202Y366094D01*
G01X701969D02*
Y368594D01*
X700427Y366802D01*
X702511D01*
G01X703652Y366094D02*
Y368594D01*
X704486D01*
X704819Y368469D01*
X705069Y368302D01*
X705277Y368052D01*
X705444Y367761D01*
X705486Y367344D01*
X705444Y366927D01*
X705277Y366636D01*
X705069Y366386D01*
X704819Y366219D01*
X704486Y366094D01*
X703652D01*
G01X707669D02*
Y368594D01*
X707169Y368094D01*
G01Y366094D02*
X708169D01*
G01X710769Y368594D02*
X710436Y368511D01*
X710186Y368302D01*
X710019Y368052D01*
X709894Y367719D01*
X709852Y367344D01*
X709894Y366969D01*
X710019Y366636D01*
X710186Y366386D01*
X710436Y366177D01*
X710769Y366094D01*
X711102Y366177D01*
X711352Y366386D01*
X711519Y366636D01*
X711644Y366969D01*
X711686Y367344D01*
X711644Y367719D01*
X711519Y368052D01*
X711352Y368302D01*
X711102Y368511D01*
X710769Y368594D01*
G01X688000Y347617D02*
X685500D01*
Y348658D01*
X685625Y348992D01*
X685792Y349200D01*
X686125Y349283D01*
X686458Y349200D01*
X686667Y348950D01*
X686792Y348658D01*
Y347617D01*
G01Y348658D02*
X688000Y349283D01*
G01Y352050D02*
X685500D01*
X687292Y350508D01*
Y352592D01*
G01X688000Y353733D02*
X685500D01*
Y354567D01*
X685625Y354900D01*
X685792Y355150D01*
X686042Y355358D01*
X686333Y355525D01*
X686750Y355567D01*
X687167Y355525D01*
X687458Y355358D01*
X687708Y355150D01*
X687875Y354900D01*
X688000Y354567D01*
Y353733D01*
G01Y357750D02*
X687958Y358042D01*
X687833Y358375D01*
X687625Y358583D01*
X687333Y358667D01*
X687042Y358583D01*
X686792Y358333D01*
X686667Y357958D01*
Y357542D01*
X686583Y357292D01*
X686375Y357083D01*
X686083Y357000D01*
X685792Y357125D01*
X685583Y357417D01*
X685500Y357750D01*
X685583Y358083D01*
X685792Y358375D01*
X686083Y358500D01*
X686375Y358417D01*
X686583Y358208D01*
X686667Y357958D01*
Y357542D01*
X686792Y357167D01*
X687042Y356917D01*
X687333Y356833D01*
X687625Y356917D01*
X687833Y357125D01*
X687958Y357458D01*
X688000Y357750D01*
G01X697536Y359094D02*
Y361594D01*
X698577D01*
X698911Y361469D01*
X699119Y361302D01*
X699202Y360969D01*
X699119Y360636D01*
X698869Y360427D01*
X698577Y360302D01*
X697536D01*
G01X698577D02*
X699202Y359094D01*
G01X701969D02*
Y361594D01*
X700427Y359802D01*
X702511D01*
G01X703652Y359094D02*
Y361594D01*
X704486D01*
X704819Y361469D01*
X705069Y361302D01*
X705277Y361052D01*
X705444Y360761D01*
X705486Y360344D01*
X705444Y359927D01*
X705277Y359636D01*
X705069Y359386D01*
X704819Y359219D01*
X704486Y359094D01*
X703652D01*
G01X707669D02*
Y361594D01*
X707169Y361094D01*
G01Y359094D02*
X708169D01*
G01X711269D02*
Y361594D01*
X709727Y359802D01*
X711811D01*
G01X680728Y360822D02*
Y363322D01*
X681769D01*
X682103Y363197D01*
X682311Y363030D01*
X682394Y362697D01*
X682311Y362364D01*
X682061Y362155D01*
X681769Y362030D01*
X680728D01*
G01X681769D02*
X682394Y360822D01*
G01X685161D02*
Y363322D01*
X683619Y361530D01*
X685703D01*
G01X688678Y363114D02*
X688428Y363239D01*
X688136Y363322D01*
X687803D01*
X687428Y363197D01*
X687136Y362989D01*
X686928Y362739D01*
X686761Y362322D01*
X686719Y361947D01*
X686803Y361572D01*
X686928Y361322D01*
X687178Y361072D01*
X687469Y360905D01*
X687761Y360822D01*
X688053D01*
X688344Y360905D01*
X688594Y361030D01*
X688803Y361197D01*
G01X690861Y360822D02*
Y363322D01*
X690361Y362822D01*
G01Y360822D02*
X691361D01*
G01X693961Y363322D02*
X693628Y363239D01*
X693378Y363030D01*
X693211Y362780D01*
X693086Y362447D01*
X693044Y362072D01*
X693086Y361697D01*
X693211Y361364D01*
X693378Y361114D01*
X693628Y360905D01*
X693961Y360822D01*
X694294Y360905D01*
X694544Y361114D01*
X694711Y361364D01*
X694836Y361697D01*
X694878Y362072D01*
X694836Y362447D01*
X694711Y362780D01*
X694544Y363030D01*
X694294Y363239D01*
X693961Y363322D01*
G01X672833Y348847D02*
X670333D01*
Y349888D01*
X670458Y350222D01*
X670625Y350430D01*
X670958Y350513D01*
X671291Y350430D01*
X671500Y350180D01*
X671625Y349888D01*
Y348847D01*
G01Y349888D02*
X672833Y350513D01*
G01Y353280D02*
X670333D01*
X672125Y351738D01*
Y353822D01*
G01X672833Y354963D02*
X670333D01*
Y355797D01*
X670458Y356130D01*
X670625Y356380D01*
X670875Y356588D01*
X671166Y356755D01*
X671583Y356797D01*
X672000Y356755D01*
X672291Y356588D01*
X672541Y356380D01*
X672708Y356130D01*
X672833Y355797D01*
Y354963D01*
G01X671791Y358188D02*
X671500Y358480D01*
X671333Y358730D01*
X671250Y359063D01*
X671333Y359355D01*
X671500Y359563D01*
X671750Y359730D01*
X672041Y359772D01*
X672291Y359730D01*
X672541Y359563D01*
X672750Y359313D01*
X672833Y359022D01*
X672750Y358688D01*
X672500Y358397D01*
X672125Y358230D01*
X671708Y358188D01*
X671166Y358272D01*
X670875Y358397D01*
X670583Y358605D01*
X670375Y358897D01*
X670333Y359188D01*
X670416Y359480D01*
X670625Y359688D01*
G01X703100Y371217D02*
X700600D01*
Y372258D01*
X700725Y372592D01*
X700892Y372800D01*
X701225Y372883D01*
X701558Y372800D01*
X701767Y372550D01*
X701892Y372258D01*
Y371217D01*
G01Y372258D02*
X703100Y372883D01*
G01Y375650D02*
X700600D01*
X702392Y374108D01*
Y376192D01*
G01X700808Y379167D02*
X700683Y378917D01*
X700600Y378625D01*
Y378292D01*
X700725Y377917D01*
X700933Y377625D01*
X701183Y377417D01*
X701600Y377250D01*
X701975Y377208D01*
X702350Y377292D01*
X702600Y377417D01*
X702850Y377667D01*
X703017Y377958D01*
X703100Y378250D01*
Y378542D01*
X703017Y378833D01*
X702892Y379083D01*
X702725Y379292D01*
G01X703100Y381350D02*
X703058Y381642D01*
X702933Y381975D01*
X702725Y382183D01*
X702433Y382267D01*
X702142Y382183D01*
X701892Y381933D01*
X701767Y381558D01*
Y381142D01*
X701683Y380892D01*
X701475Y380683D01*
X701183Y380600D01*
X700892Y380725D01*
X700683Y381017D01*
X700600Y381350D01*
X700683Y381683D01*
X700892Y381975D01*
X701183Y382100D01*
X701475Y382017D01*
X701683Y381808D01*
X701767Y381558D01*
Y381142D01*
X701892Y380767D01*
X702142Y380517D01*
X702433Y380433D01*
X702725Y380517D01*
X702933Y380725D01*
X703058Y381058D01*
X703100Y381350D01*
G01X706949Y371222D02*
X704449D01*
Y372263D01*
X704574Y372597D01*
X704741Y372805D01*
X705074Y372888D01*
X705407Y372805D01*
X705616Y372555D01*
X705741Y372263D01*
Y371222D01*
G01Y372263D02*
X706949Y372888D01*
G01Y375655D02*
X704449D01*
X706241Y374113D01*
Y376197D01*
G01X704657Y379172D02*
X704532Y378922D01*
X704449Y378630D01*
Y378297D01*
X704574Y377922D01*
X704782Y377630D01*
X705032Y377422D01*
X705449Y377255D01*
X705824Y377213D01*
X706199Y377297D01*
X706449Y377422D01*
X706699Y377672D01*
X706866Y377963D01*
X706949Y378255D01*
Y378547D01*
X706866Y378838D01*
X706741Y379088D01*
X706574Y379297D01*
G01X706657Y380647D02*
X706866Y380938D01*
X706949Y381272D01*
X706866Y381605D01*
X706616Y381897D01*
X706241Y382105D01*
X705866Y382188D01*
X705407D01*
X705032Y382105D01*
X704699Y381897D01*
X704532Y381647D01*
X704449Y381355D01*
X704532Y381022D01*
X704699Y380772D01*
X704949Y380605D01*
X705282Y380522D01*
X705574Y380605D01*
X705866Y380813D01*
X706032Y381063D01*
X706074Y381355D01*
X705991Y381688D01*
X705782Y381938D01*
X705407Y382188D01*
G01X715060Y366211D02*
X712560D01*
Y367252D01*
X712685Y367586D01*
X712852Y367794D01*
X713185Y367877D01*
X713518Y367794D01*
X713727Y367544D01*
X713852Y367252D01*
Y366211D01*
G01Y367252D02*
X715060Y367877D01*
G01Y370644D02*
X712560D01*
X714352Y369102D01*
Y371186D01*
G01X715060Y372327D02*
X712560D01*
Y373161D01*
X712685Y373494D01*
X712852Y373744D01*
X713102Y373952D01*
X713393Y374119D01*
X713810Y374161D01*
X714227Y374119D01*
X714518Y373952D01*
X714768Y373744D01*
X714935Y373494D01*
X715060Y373161D01*
Y372327D01*
G01X714018Y375552D02*
X713727Y375844D01*
X713560Y376094D01*
X713477Y376427D01*
X713560Y376719D01*
X713727Y376927D01*
X713977Y377094D01*
X714268Y377136D01*
X714518Y377094D01*
X714768Y376927D01*
X714977Y376677D01*
X715060Y376386D01*
X714977Y376052D01*
X714727Y375761D01*
X714352Y375594D01*
X713935Y375552D01*
X713393Y375636D01*
X713102Y375761D01*
X712810Y375969D01*
X712602Y376261D01*
X712560Y376552D01*
X712643Y376844D01*
X712852Y377052D01*
G01X714768Y378736D02*
X714977Y379027D01*
X715060Y379361D01*
X714977Y379694D01*
X714727Y379986D01*
X714352Y380194D01*
X713977Y380277D01*
X713518D01*
X713143Y380194D01*
X712810Y379986D01*
X712643Y379736D01*
X712560Y379444D01*
X712643Y379111D01*
X712810Y378861D01*
X713060Y378694D01*
X713393Y378611D01*
X713685Y378694D01*
X713977Y378902D01*
X714143Y379152D01*
X714185Y379444D01*
X714102Y379777D01*
X713893Y380027D01*
X713518Y380277D01*
G01X718560Y366211D02*
X716060D01*
Y367252D01*
X716185Y367586D01*
X716352Y367794D01*
X716685Y367877D01*
X717018Y367794D01*
X717227Y367544D01*
X717352Y367252D01*
Y366211D01*
G01Y367252D02*
X718560Y367877D01*
G01Y370644D02*
X716060D01*
X717852Y369102D01*
Y371186D01*
G01X718560Y372327D02*
X716060D01*
Y373161D01*
X716185Y373494D01*
X716352Y373744D01*
X716602Y373952D01*
X716893Y374119D01*
X717310Y374161D01*
X717727Y374119D01*
X718018Y373952D01*
X718268Y373744D01*
X718435Y373494D01*
X718560Y373161D01*
Y372327D01*
G01Y376261D02*
X718018Y376344D01*
X717560Y376469D01*
X717143Y376636D01*
X716685Y376844D01*
X716060Y377177D01*
Y375511D01*
G01Y379444D02*
X716143Y379111D01*
X716352Y378861D01*
X716602Y378694D01*
X716935Y378569D01*
X717310Y378527D01*
X717685Y378569D01*
X718018Y378694D01*
X718268Y378861D01*
X718477Y379111D01*
X718560Y379444D01*
X718477Y379777D01*
X718268Y380027D01*
X718018Y380194D01*
X717685Y380319D01*
X717310Y380361D01*
X716935Y380319D01*
X716602Y380194D01*
X716352Y380027D01*
X716143Y379777D01*
X716060Y379444D01*
G01X677893Y347614D02*
X675393D01*
Y348655D01*
X675518Y348989D01*
X675685Y349197D01*
X676018Y349280D01*
X676351Y349197D01*
X676560Y348947D01*
X676685Y348655D01*
Y347614D01*
G01Y348655D02*
X677893Y349280D01*
G01Y352047D02*
X675393D01*
X677185Y350505D01*
Y352589D01*
G01X677893Y353730D02*
X675393D01*
Y354564D01*
X675518Y354897D01*
X675685Y355147D01*
X675935Y355355D01*
X676226Y355522D01*
X676643Y355564D01*
X677060Y355522D01*
X677351Y355355D01*
X677601Y355147D01*
X677768Y354897D01*
X677893Y354564D01*
Y353730D01*
G01Y357664D02*
X677351Y357747D01*
X676893Y357872D01*
X676476Y358039D01*
X676018Y358247D01*
X675393Y358580D01*
Y356914D01*
G01X667733Y348847D02*
X665233D01*
Y349888D01*
X665358Y350222D01*
X665525Y350430D01*
X665858Y350513D01*
X666191Y350430D01*
X666400Y350180D01*
X666525Y349888D01*
Y348847D01*
G01Y349888D02*
X667733Y350513D01*
G01Y353280D02*
X665233D01*
X667025Y351738D01*
Y353822D01*
G01X667733Y354963D02*
X665233D01*
Y355797D01*
X665358Y356130D01*
X665525Y356380D01*
X665775Y356588D01*
X666066Y356755D01*
X666483Y356797D01*
X666900Y356755D01*
X667191Y356588D01*
X667441Y356380D01*
X667608Y356130D01*
X667733Y355797D01*
Y354963D01*
G01X667358Y358063D02*
X667566Y358313D01*
X667691Y358605D01*
X667733Y358980D01*
X667650Y359355D01*
X667483Y359647D01*
X667191Y359855D01*
X666858Y359897D01*
X666525Y359813D01*
X666316Y359605D01*
X666150Y359313D01*
X666108Y359022D01*
X666150Y358730D01*
X666316Y358355D01*
X665233Y358480D01*
Y359605D01*
G01X697536Y355594D02*
Y358094D01*
X698577D01*
X698911Y357969D01*
X699119Y357802D01*
X699202Y357469D01*
X699119Y357136D01*
X698869Y356927D01*
X698577Y356802D01*
X697536D01*
G01X698577D02*
X699202Y355594D01*
G01X701969D02*
Y358094D01*
X700427Y356302D01*
X702511D01*
G01X703652Y355594D02*
Y358094D01*
X704486D01*
X704819Y357969D01*
X705069Y357802D01*
X705277Y357552D01*
X705444Y357261D01*
X705486Y356844D01*
X705444Y356427D01*
X705277Y356136D01*
X705069Y355886D01*
X704819Y355719D01*
X704486Y355594D01*
X703652D01*
G01X707669D02*
Y358094D01*
X707169Y357594D01*
G01Y355594D02*
X708169D01*
G01X710686D02*
X710769Y356136D01*
X710894Y356594D01*
X711061Y357011D01*
X711269Y357469D01*
X711602Y358094D01*
X709936D01*
G01X705262Y343629D02*
Y346129D01*
X706303D01*
X706637Y346004D01*
X706845Y345837D01*
X706928Y345504D01*
X706845Y345171D01*
X706595Y344962D01*
X706303Y344837D01*
X705262D01*
G01X706303D02*
X706928Y343629D01*
G01X709695D02*
Y346129D01*
X708153Y344337D01*
X710237D01*
G01X711378Y343629D02*
Y346129D01*
X712212D01*
X712545Y346004D01*
X712795Y345837D01*
X713003Y345587D01*
X713170Y345296D01*
X713212Y344879D01*
X713170Y344462D01*
X713003Y344171D01*
X712795Y343921D01*
X712545Y343754D01*
X712212Y343629D01*
X711378D01*
G01X714603Y345712D02*
X714853Y345962D01*
X715145Y346087D01*
X715478Y346129D01*
X715895Y346046D01*
X716187Y345837D01*
X716270Y345587D01*
X716228Y345337D01*
X716062Y345129D01*
X715228Y344712D01*
X714853Y344421D01*
X714603Y344004D01*
X714520Y343629D01*
X716270D01*
G01X718495Y346129D02*
X718162Y346046D01*
X717912Y345837D01*
X717745Y345587D01*
X717620Y345254D01*
X717578Y344879D01*
X717620Y344504D01*
X717745Y344171D01*
X717912Y343921D01*
X718162Y343712D01*
X718495Y343629D01*
X718828Y343712D01*
X719078Y343921D01*
X719245Y344171D01*
X719370Y344504D01*
X719412Y344879D01*
X719370Y345254D01*
X719245Y345587D01*
X719078Y345837D01*
X718828Y346046D01*
X718495Y346129D01*
G01X718836Y347098D02*
X716336D01*
Y348139D01*
X716461Y348473D01*
X716628Y348681D01*
X716961Y348764D01*
X717294Y348681D01*
X717503Y348431D01*
X717628Y348139D01*
Y347098D01*
G01Y348139D02*
X718836Y348764D01*
G01Y351531D02*
X716336D01*
X718128Y349989D01*
Y352073D01*
G01X718836Y353214D02*
X716336D01*
Y354048D01*
X716461Y354381D01*
X716628Y354631D01*
X716878Y354839D01*
X717169Y355006D01*
X717586Y355048D01*
X718003Y355006D01*
X718294Y354839D01*
X718544Y354631D01*
X718711Y354381D01*
X718836Y354048D01*
Y353214D01*
G01Y357231D02*
X716336D01*
X716836Y356731D01*
G01X718836D02*
Y357731D01*
G01Y360331D02*
X718794Y360623D01*
X718669Y360956D01*
X718461Y361164D01*
X718169Y361248D01*
X717878Y361164D01*
X717628Y360914D01*
X717503Y360539D01*
Y360123D01*
X717419Y359873D01*
X717211Y359664D01*
X716919Y359581D01*
X716628Y359706D01*
X716419Y359998D01*
X716336Y360331D01*
X716419Y360664D01*
X716628Y360956D01*
X716919Y361081D01*
X717211Y360998D01*
X717419Y360789D01*
X717503Y360539D01*
Y360123D01*
X717628Y359748D01*
X717878Y359498D01*
X718169Y359414D01*
X718461Y359498D01*
X718669Y359706D01*
X718794Y360039D01*
X718836Y360331D01*
G01X723408Y346667D02*
X723283Y346417D01*
X723200Y346125D01*
Y345792D01*
X723325Y345417D01*
X723533Y345125D01*
X723783Y344917D01*
X724200Y344750D01*
X724575Y344708D01*
X724950Y344792D01*
X725200Y344917D01*
X725450Y345167D01*
X725617Y345458D01*
X725700Y345750D01*
Y346042D01*
X725617Y346333D01*
X725492Y346583D01*
X725325Y346792D01*
G01X725700Y349350D02*
X723200D01*
X724992Y347808D01*
Y349892D01*
G01X725700Y351033D02*
X723200D01*
Y351867D01*
X723325Y352200D01*
X723492Y352450D01*
X723742Y352658D01*
X724033Y352825D01*
X724450Y352867D01*
X724867Y352825D01*
X725158Y352658D01*
X725408Y352450D01*
X725575Y352200D01*
X725700Y351867D01*
Y351033D01*
G01X723617Y354258D02*
X723367Y354508D01*
X723242Y354800D01*
X723200Y355133D01*
X723283Y355550D01*
X723492Y355842D01*
X723742Y355925D01*
X723992Y355883D01*
X724200Y355717D01*
X724617Y354883D01*
X724908Y354508D01*
X725325Y354258D01*
X725700Y354175D01*
Y355925D01*
G01X675327Y386100D02*
Y408675D01*
G01Y386100D02*
X672629D01*
G01X697622Y404449D02*
Y402657D01*
X697789Y402282D01*
X698122Y402032D01*
X698539Y401949D01*
X698956Y402032D01*
X699289Y402282D01*
X699456Y402657D01*
Y404449D01*
G01X702139Y401949D02*
Y404449D01*
X700597Y402657D01*
X702681D01*
G01X705656Y404241D02*
X705406Y404366D01*
X705114Y404449D01*
X704781D01*
X704406Y404324D01*
X704114Y404116D01*
X703906Y403866D01*
X703739Y403449D01*
X703697Y403074D01*
X703781Y402699D01*
X703906Y402449D01*
X704156Y402199D01*
X704447Y402032D01*
X704739Y401949D01*
X705031D01*
X705322Y402032D01*
X705572Y402157D01*
X705781Y402324D01*
G01X707047Y404032D02*
X707297Y404282D01*
X707589Y404407D01*
X707922Y404449D01*
X708339Y404366D01*
X708631Y404157D01*
X708714Y403907D01*
X708672Y403657D01*
X708506Y403449D01*
X707672Y403032D01*
X707297Y402741D01*
X707047Y402324D01*
X706964Y401949D01*
X708714D01*
G01X677327Y385226D02*
Y396626D01*
X697667D01*
Y385226D01*
X677327D01*
G01Y389676D02*
X681777D01*
Y392176D01*
X677327D01*
G01X713833Y391017D02*
X716333D01*
Y392683D01*
G01Y395450D02*
X713833D01*
X715625Y393908D01*
Y395992D01*
G01X714041Y398967D02*
X713916Y398717D01*
X713833Y398425D01*
Y398092D01*
X713958Y397717D01*
X714166Y397425D01*
X714416Y397217D01*
X714833Y397050D01*
X715208Y397008D01*
X715583Y397092D01*
X715833Y397217D01*
X716083Y397467D01*
X716250Y397758D01*
X716333Y398050D01*
Y398342D01*
X716250Y398633D01*
X716125Y398883D01*
X715958Y399092D01*
G01X716333Y401150D02*
X713833D01*
X714333Y400650D01*
G01X716333D02*
Y401650D01*
G01X745600Y385750D02*
X718400D01*
Y408250D01*
X745600D01*
Y385750D01*
G01X689285Y410606D02*
X686785D01*
Y411647D01*
X686910Y411981D01*
X687077Y412189D01*
X687410Y412272D01*
X687743Y412189D01*
X687952Y411939D01*
X688077Y411647D01*
Y410606D01*
G01Y411647D02*
X689285Y412272D01*
G01Y415039D02*
X686785D01*
X688577Y413497D01*
Y415581D01*
G01X686993Y418556D02*
X686868Y418306D01*
X686785Y418014D01*
Y417681D01*
X686910Y417306D01*
X687118Y417014D01*
X687368Y416806D01*
X687785Y416639D01*
X688160Y416597D01*
X688535Y416681D01*
X688785Y416806D01*
X689035Y417056D01*
X689202Y417347D01*
X689285Y417639D01*
Y417931D01*
X689202Y418222D01*
X689077Y418472D01*
X688910Y418681D01*
G01X689285Y420739D02*
X686785D01*
X687285Y420239D01*
G01X689285D02*
Y421239D01*
G01Y423839D02*
X686785D01*
X687285Y423339D01*
G01X689285D02*
Y424339D01*
G01X701185Y411206D02*
X698685D01*
Y412247D01*
X698810Y412581D01*
X698977Y412789D01*
X699310Y412872D01*
X699643Y412789D01*
X699852Y412539D01*
X699977Y412247D01*
Y411206D01*
G01Y412247D02*
X701185Y412872D01*
G01Y415639D02*
X698685D01*
X700477Y414097D01*
Y416181D01*
G01X698893Y419156D02*
X698768Y418906D01*
X698685Y418614D01*
Y418281D01*
X698810Y417906D01*
X699018Y417614D01*
X699268Y417406D01*
X699685Y417239D01*
X700060Y417197D01*
X700435Y417281D01*
X700685Y417406D01*
X700935Y417656D01*
X701102Y417947D01*
X701185Y418239D01*
Y418531D01*
X701102Y418822D01*
X700977Y419072D01*
X700810Y419281D01*
G01X701185Y421339D02*
X698685D01*
X699185Y420839D01*
G01X701185D02*
Y421839D01*
G01X699102Y423647D02*
X698852Y423897D01*
X698727Y424189D01*
X698685Y424522D01*
X698768Y424939D01*
X698977Y425231D01*
X699227Y425314D01*
X699477Y425272D01*
X699685Y425106D01*
X700102Y424272D01*
X700393Y423897D01*
X700810Y423647D01*
X701185Y423564D01*
Y425314D01*
G01X678712Y411422D02*
X678587Y411172D01*
X678504Y410880D01*
Y410547D01*
X678629Y410172D01*
X678837Y409880D01*
X679087Y409672D01*
X679504Y409505D01*
X679879Y409463D01*
X680254Y409547D01*
X680504Y409672D01*
X680754Y409922D01*
X680921Y410213D01*
X681004Y410505D01*
Y410797D01*
X680921Y411088D01*
X680796Y411338D01*
X680629Y411547D01*
G01X681004Y414105D02*
X678504D01*
X680296Y412563D01*
Y414647D01*
G01X678712Y417622D02*
X678587Y417372D01*
X678504Y417080D01*
Y416747D01*
X678629Y416372D01*
X678837Y416080D01*
X679087Y415872D01*
X679504Y415705D01*
X679879Y415663D01*
X680254Y415747D01*
X680504Y415872D01*
X680754Y416122D01*
X680921Y416413D01*
X681004Y416705D01*
Y416997D01*
X680921Y417288D01*
X680796Y417538D01*
X680629Y417747D01*
G01X680504Y418888D02*
X680796Y419138D01*
X680962Y419472D01*
X681004Y419847D01*
X680962Y420180D01*
X680754Y420513D01*
X680504Y420722D01*
X680254Y420763D01*
X679962Y420680D01*
X679754Y420388D01*
X679671Y420097D01*
Y419722D01*
G01Y420097D02*
X679546Y420347D01*
X679337Y420555D01*
X679087Y420638D01*
X678837Y420555D01*
X678629Y420347D01*
X678504Y419972D01*
X678546Y419597D01*
X678712Y419222D01*
G01X672627Y421464D02*
X676189D01*
Y408668D01*
X672627D01*
G01X688000Y463700D02*
Y466395D01*
G01Y463700D02*
X665428D01*
G01X697397Y460542D02*
X697605Y460292D01*
X697855Y460125D01*
X698147Y460042D01*
X698480Y460125D01*
X698730Y460292D01*
X698980Y460542D01*
X699063Y460875D01*
Y462542D01*
G01X701830Y460042D02*
Y462542D01*
X700288Y460750D01*
X702372D01*
G01X704763Y461375D02*
X704930Y461500D01*
X705055Y461709D01*
X705138Y462000D01*
X705055Y462250D01*
X704888Y462417D01*
X704597Y462542D01*
X703472D01*
Y460042D01*
X704847D01*
X705138Y460209D01*
X705305Y460459D01*
X705388Y460750D01*
X705305Y461042D01*
X705055Y461292D01*
X704763Y461375D01*
X703472D01*
G01X706738Y462125D02*
X706988Y462375D01*
X707280Y462500D01*
X707613Y462542D01*
X708030Y462459D01*
X708322Y462250D01*
X708405Y462000D01*
X708363Y461750D01*
X708197Y461542D01*
X707363Y461125D01*
X706988Y460834D01*
X706738Y460417D01*
X706655Y460042D01*
X708405D01*
G01X718333Y512853D02*
X718083Y512978D01*
X717791Y513061D01*
X717458D01*
X717083Y512936D01*
X716791Y512728D01*
X716583Y512478D01*
X716416Y512061D01*
X716374Y511686D01*
X716458Y511311D01*
X716583Y511061D01*
X716833Y510811D01*
X717124Y510644D01*
X717416Y510561D01*
X717708D01*
X717999Y510644D01*
X718249Y510769D01*
X718458Y510936D01*
G01X719724Y511603D02*
X720016Y511894D01*
X720266Y512061D01*
X720599Y512144D01*
X720891Y512061D01*
X721099Y511894D01*
X721266Y511644D01*
X721308Y511353D01*
X721266Y511103D01*
X721099Y510853D01*
X720849Y510644D01*
X720558Y510561D01*
X720224Y510644D01*
X719933Y510894D01*
X719766Y511269D01*
X719724Y511686D01*
X719808Y512228D01*
X719933Y512519D01*
X720141Y512811D01*
X720433Y513019D01*
X720724Y513061D01*
X721016Y512978D01*
X721224Y512769D01*
G01X722533Y510561D02*
Y513061D01*
X723616Y510978D01*
X724699Y513061D01*
Y510561D01*
G01X725799Y510936D02*
X726049Y510728D01*
X726341Y510603D01*
X726716Y510561D01*
X727091Y510644D01*
X727383Y510811D01*
X727591Y511103D01*
X727633Y511436D01*
X727549Y511769D01*
X727341Y511978D01*
X727049Y512144D01*
X726758Y512186D01*
X726466Y512144D01*
X726091Y511978D01*
X726216Y513061D01*
X727341D01*
G01X717161Y496744D02*
X714661D01*
Y497785D01*
X714786Y498119D01*
X714953Y498327D01*
X715286Y498410D01*
X715619Y498327D01*
X715828Y498077D01*
X715953Y497785D01*
Y496744D01*
G01Y497785D02*
X717161Y498410D01*
G01Y501177D02*
X714661D01*
X716453Y499635D01*
Y501719D01*
G01X715828Y504110D02*
X715703Y504277D01*
X715494Y504402D01*
X715203Y504485D01*
X714953Y504402D01*
X714786Y504235D01*
X714661Y503944D01*
Y502819D01*
X717161D01*
Y504194D01*
X716994Y504485D01*
X716744Y504652D01*
X716453Y504735D01*
X716161Y504652D01*
X715911Y504402D01*
X715828Y504110D01*
Y502819D01*
G01X717161Y506794D02*
X716619Y506877D01*
X716161Y507002D01*
X715744Y507169D01*
X715286Y507377D01*
X714661Y507710D01*
Y506044D01*
G01X712677Y494213D02*
X710177D01*
Y495254D01*
X710302Y495588D01*
X710469Y495796D01*
X710802Y495879D01*
X711135Y495796D01*
X711344Y495546D01*
X711469Y495254D01*
Y494213D01*
G01Y495254D02*
X712677Y495879D01*
G01Y498646D02*
X710177D01*
X711969Y497104D01*
Y499188D01*
G01X711344Y501579D02*
X711219Y501746D01*
X711010Y501871D01*
X710719Y501954D01*
X710469Y501871D01*
X710302Y501704D01*
X710177Y501413D01*
Y500288D01*
X712677D01*
Y501663D01*
X712510Y501954D01*
X712260Y502121D01*
X711969Y502204D01*
X711677Y502121D01*
X711427Y501871D01*
X711344Y501579D01*
Y500288D01*
G01X712677Y504346D02*
X710177D01*
X710677Y503846D01*
G01X712677D02*
Y504846D01*
G01X710177Y507446D02*
X710260Y507113D01*
X710469Y506863D01*
X710719Y506696D01*
X711052Y506571D01*
X711427Y506529D01*
X711802Y506571D01*
X712135Y506696D01*
X712385Y506863D01*
X712594Y507113D01*
X712677Y507446D01*
X712594Y507779D01*
X712385Y508029D01*
X712135Y508196D01*
X711802Y508321D01*
X711427Y508363D01*
X711052Y508321D01*
X710719Y508196D01*
X710469Y508029D01*
X710260Y507779D01*
X710177Y507446D01*
G01X702566Y495306D02*
X700066D01*
Y496347D01*
X700191Y496681D01*
X700358Y496889D01*
X700691Y496972D01*
X701024Y496889D01*
X701233Y496639D01*
X701358Y496347D01*
Y495306D01*
G01Y496347D02*
X702566Y496972D01*
G01Y499739D02*
X700066D01*
X701858Y498197D01*
Y500281D01*
G01X701233Y502672D02*
X701108Y502839D01*
X700899Y502964D01*
X700608Y503047D01*
X700358Y502964D01*
X700191Y502797D01*
X700066Y502506D01*
Y501381D01*
X702566D01*
Y502756D01*
X702399Y503047D01*
X702149Y503214D01*
X701858Y503297D01*
X701566Y503214D01*
X701316Y502964D01*
X701233Y502672D01*
Y501381D01*
G01X701524Y504647D02*
X701233Y504939D01*
X701066Y505189D01*
X700983Y505522D01*
X701066Y505814D01*
X701233Y506022D01*
X701483Y506189D01*
X701774Y506231D01*
X702024Y506189D01*
X702274Y506022D01*
X702483Y505772D01*
X702566Y505481D01*
X702483Y505147D01*
X702233Y504856D01*
X701858Y504689D01*
X701441Y504647D01*
X700899Y504731D01*
X700608Y504856D01*
X700316Y505064D01*
X700108Y505356D01*
X700066Y505647D01*
X700149Y505939D01*
X700358Y506147D01*
G01X689490Y489051D02*
X686990D01*
Y490092D01*
X687115Y490426D01*
X687282Y490634D01*
X687615Y490717D01*
X687948Y490634D01*
X688157Y490384D01*
X688282Y490092D01*
Y489051D01*
G01Y490092D02*
X689490Y490717D01*
G01Y493484D02*
X686990D01*
X688782Y491942D01*
Y494026D01*
G01X688157Y496417D02*
X688032Y496584D01*
X687823Y496709D01*
X687532Y496792D01*
X687282Y496709D01*
X687115Y496542D01*
X686990Y496251D01*
Y495126D01*
X689490D01*
Y496501D01*
X689323Y496792D01*
X689073Y496959D01*
X688782Y497042D01*
X688490Y496959D01*
X688240Y496709D01*
X688157Y496417D01*
Y495126D01*
G01X689490Y499684D02*
X686990D01*
X688782Y498142D01*
Y500226D01*
G01X693134Y491217D02*
X690634D01*
Y492258D01*
X690759Y492592D01*
X690926Y492800D01*
X691259Y492883D01*
X691592Y492800D01*
X691801Y492550D01*
X691926Y492258D01*
Y491217D01*
G01Y492258D02*
X693134Y492883D01*
G01Y495650D02*
X690634D01*
X692426Y494108D01*
Y496192D01*
G01X691801Y498583D02*
X691676Y498750D01*
X691467Y498875D01*
X691176Y498958D01*
X690926Y498875D01*
X690759Y498708D01*
X690634Y498417D01*
Y497292D01*
X693134D01*
Y498667D01*
X692967Y498958D01*
X692717Y499125D01*
X692426Y499208D01*
X692134Y499125D01*
X691884Y498875D01*
X691801Y498583D01*
Y497292D01*
G01X693134Y501350D02*
X693092Y501642D01*
X692967Y501975D01*
X692759Y502183D01*
X692467Y502267D01*
X692176Y502183D01*
X691926Y501933D01*
X691801Y501558D01*
Y501142D01*
X691717Y500892D01*
X691509Y500683D01*
X691217Y500600D01*
X690926Y500725D01*
X690717Y501017D01*
X690634Y501350D01*
X690717Y501683D01*
X690926Y501975D01*
X691217Y502100D01*
X691509Y502017D01*
X691717Y501808D01*
X691801Y501558D01*
Y501142D01*
X691926Y500767D01*
X692176Y500517D01*
X692467Y500433D01*
X692759Y500517D01*
X692967Y500725D01*
X693092Y501058D01*
X693134Y501350D01*
G01X677230Y494400D02*
X674730D01*
Y495441D01*
X674855Y495775D01*
X675022Y495983D01*
X675355Y496066D01*
X675688Y495983D01*
X675897Y495733D01*
X676022Y495441D01*
Y494400D01*
G01Y495441D02*
X677230Y496066D01*
G01Y498833D02*
X674730D01*
X676522Y497291D01*
Y499375D01*
G01X675897Y501766D02*
X675772Y501933D01*
X675563Y502058D01*
X675272Y502141D01*
X675022Y502058D01*
X674855Y501891D01*
X674730Y501600D01*
Y500475D01*
X677230D01*
Y501850D01*
X677063Y502141D01*
X676813Y502308D01*
X676522Y502391D01*
X676230Y502308D01*
X675980Y502058D01*
X675897Y501766D01*
Y500475D01*
G01X677230Y504533D02*
X674730D01*
X675230Y504033D01*
G01X677230D02*
Y505033D01*
G01Y508133D02*
X674730D01*
X676522Y506591D01*
Y508675D01*
G01X683161Y484439D02*
X682828Y484481D01*
X682536Y484647D01*
X682286Y484897D01*
X682119Y485189D01*
X682036Y485522D01*
Y485856D01*
X682119Y486189D01*
X682286Y486481D01*
X682536Y486731D01*
X682828Y486897D01*
X683161Y486939D01*
X683494Y486897D01*
X683786Y486731D01*
X684036Y486481D01*
X684203Y486189D01*
X684286Y485856D01*
Y485522D01*
X684203Y485189D01*
X684036Y484897D01*
X683786Y484647D01*
X683494Y484481D01*
X683161Y484439D01*
G01X683494Y485106D02*
X683994Y484439D01*
G01X686761D02*
Y486939D01*
X685219Y485147D01*
X687303D01*
G01X689694Y485772D02*
X689861Y485897D01*
X689986Y486106D01*
X690069Y486397D01*
X689986Y486647D01*
X689819Y486814D01*
X689528Y486939D01*
X688403D01*
Y484439D01*
X689778D01*
X690069Y484606D01*
X690236Y484856D01*
X690319Y485147D01*
X690236Y485439D01*
X689986Y485689D01*
X689694Y485772D01*
X688403D01*
G01X692461Y484439D02*
Y486939D01*
X691961Y486439D01*
G01Y484439D02*
X692961D01*
G01X696642Y495467D02*
X696517Y495217D01*
X696434Y494925D01*
Y494592D01*
X696559Y494217D01*
X696767Y493925D01*
X697017Y493717D01*
X697434Y493550D01*
X697809Y493508D01*
X698184Y493592D01*
X698434Y493717D01*
X698684Y493967D01*
X698851Y494258D01*
X698934Y494550D01*
Y494842D01*
X698851Y495133D01*
X698726Y495383D01*
X698559Y495592D01*
G01X698934Y498150D02*
X696434D01*
X698226Y496608D01*
Y498692D01*
G01X697601Y501083D02*
X697476Y501250D01*
X697267Y501375D01*
X696976Y501458D01*
X696726Y501375D01*
X696559Y501208D01*
X696434Y500917D01*
Y499792D01*
X698934D01*
Y501167D01*
X698767Y501458D01*
X698517Y501625D01*
X698226Y501708D01*
X697934Y501625D01*
X697684Y501375D01*
X697601Y501083D01*
Y499792D01*
G01X698934Y504350D02*
X696434D01*
X698226Y502808D01*
Y504892D01*
G01X696642Y482167D02*
X696517Y481917D01*
X696434Y481625D01*
Y481292D01*
X696559Y480917D01*
X696767Y480625D01*
X697017Y480417D01*
X697434Y480250D01*
X697809Y480208D01*
X698184Y480292D01*
X698434Y480417D01*
X698684Y480667D01*
X698851Y480958D01*
X698934Y481250D01*
Y481542D01*
X698851Y481833D01*
X698726Y482083D01*
X698559Y482292D01*
G01X698934Y484850D02*
X696434D01*
X698226Y483308D01*
Y485392D01*
G01X697601Y487783D02*
X697476Y487950D01*
X697267Y488075D01*
X696976Y488158D01*
X696726Y488075D01*
X696559Y487908D01*
X696434Y487617D01*
Y486492D01*
X698934D01*
Y487867D01*
X698767Y488158D01*
X698517Y488325D01*
X698226Y488408D01*
X697934Y488325D01*
X697684Y488075D01*
X697601Y487783D01*
Y486492D01*
G01X698642Y489842D02*
X698851Y490133D01*
X698934Y490467D01*
X698851Y490800D01*
X698601Y491092D01*
X698226Y491300D01*
X697851Y491383D01*
X697392D01*
X697017Y491300D01*
X696684Y491092D01*
X696517Y490842D01*
X696434Y490550D01*
X696517Y490217D01*
X696684Y489967D01*
X696934Y489800D01*
X697267Y489717D01*
X697559Y489800D01*
X697851Y490008D01*
X698017Y490258D01*
X698059Y490550D01*
X697976Y490883D01*
X697767Y491133D01*
X697392Y491383D01*
G01X704208Y499267D02*
X704083Y499017D01*
X704000Y498725D01*
Y498392D01*
X704125Y498017D01*
X704333Y497725D01*
X704583Y497517D01*
X705000Y497350D01*
X705375Y497308D01*
X705750Y497392D01*
X706000Y497517D01*
X706250Y497767D01*
X706417Y498058D01*
X706500Y498350D01*
Y498642D01*
X706417Y498933D01*
X706292Y499183D01*
X706125Y499392D01*
G01X706500Y501950D02*
X704000D01*
X705792Y500408D01*
Y502492D01*
G01X705167Y504883D02*
X705042Y505050D01*
X704833Y505175D01*
X704542Y505258D01*
X704292Y505175D01*
X704125Y505008D01*
X704000Y504717D01*
Y503592D01*
X706500D01*
Y504967D01*
X706333Y505258D01*
X706083Y505425D01*
X705792Y505508D01*
X705500Y505425D01*
X705250Y505175D01*
X705167Y504883D01*
Y503592D01*
G01X706500Y507650D02*
X706458Y507942D01*
X706333Y508275D01*
X706125Y508483D01*
X705833Y508567D01*
X705542Y508483D01*
X705292Y508233D01*
X705167Y507858D01*
Y507442D01*
X705083Y507192D01*
X704875Y506983D01*
X704583Y506900D01*
X704292Y507025D01*
X704083Y507317D01*
X704000Y507650D01*
X704083Y507983D01*
X704292Y508275D01*
X704583Y508400D01*
X704875Y508317D01*
X705083Y508108D01*
X705167Y507858D01*
Y507442D01*
X705292Y507067D01*
X705542Y506817D01*
X705833Y506733D01*
X706125Y506817D01*
X706333Y507025D01*
X706458Y507358D01*
X706500Y507650D01*
G01X695850Y473005D02*
X695600Y473130D01*
X695308Y473213D01*
X694975D01*
X694600Y473088D01*
X694308Y472880D01*
X694100Y472630D01*
X693933Y472213D01*
X693891Y471838D01*
X693975Y471463D01*
X694100Y471213D01*
X694350Y470963D01*
X694641Y470796D01*
X694933Y470713D01*
X695225D01*
X695516Y470796D01*
X695766Y470921D01*
X695975Y471088D01*
G01X698533Y470713D02*
Y473213D01*
X696991Y471421D01*
X699075D01*
G01X701466Y472046D02*
X701633Y472171D01*
X701758Y472380D01*
X701841Y472671D01*
X701758Y472921D01*
X701591Y473088D01*
X701300Y473213D01*
X700175D01*
Y470713D01*
X701550D01*
X701841Y470880D01*
X702008Y471130D01*
X702091Y471421D01*
X702008Y471713D01*
X701758Y471963D01*
X701466Y472046D01*
X700175D01*
G01X704233Y470713D02*
Y473213D01*
X703733Y472713D01*
G01Y470713D02*
X704733D01*
G01X707833D02*
Y473213D01*
X706291Y471421D01*
X708375D01*
G01X688000Y481700D02*
Y479002D01*
G01Y481700D02*
X665425D01*
G01X724763Y472927D02*
X722263D01*
Y473968D01*
X722388Y474302D01*
X722555Y474510D01*
X722888Y474593D01*
X723221Y474510D01*
X723430Y474260D01*
X723555Y473968D01*
Y472927D01*
G01Y473968D02*
X724763Y474593D01*
G01Y476860D02*
X722263D01*
X722763Y476360D01*
G01X724763D02*
Y477360D01*
G01X722680Y479168D02*
X722430Y479418D01*
X722305Y479710D01*
X722263Y480043D01*
X722346Y480460D01*
X722555Y480752D01*
X722805Y480835D01*
X723055Y480793D01*
X723263Y480627D01*
X723680Y479793D01*
X723971Y479418D01*
X724388Y479168D01*
X724763Y479085D01*
Y480835D01*
G01X722263Y481810D02*
X724763Y482393D01*
X722263Y483060D01*
X724763Y483727D01*
X722263Y484310D01*
G01X724763Y486160D02*
X724721Y486452D01*
X724596Y486785D01*
X724388Y486993D01*
X724096Y487077D01*
X723805Y486993D01*
X723555Y486743D01*
X723430Y486368D01*
Y485952D01*
X723346Y485702D01*
X723138Y485493D01*
X722846Y485410D01*
X722555Y485535D01*
X722346Y485827D01*
X722263Y486160D01*
X722346Y486493D01*
X722555Y486785D01*
X722846Y486910D01*
X723138Y486827D01*
X723346Y486618D01*
X723430Y486368D01*
Y485952D01*
X723555Y485577D01*
X723805Y485327D01*
X724096Y485243D01*
X724388Y485327D01*
X724596Y485535D01*
X724721Y485868D01*
X724763Y486160D01*
G01X719319Y490850D02*
X723319D01*
Y498250D01*
G01X720833Y516453D02*
X720583Y516578D01*
X720291Y516661D01*
X719958D01*
X719583Y516536D01*
X719291Y516328D01*
X719083Y516078D01*
X718916Y515661D01*
X718874Y515286D01*
X718958Y514911D01*
X719083Y514661D01*
X719333Y514411D01*
X719624Y514244D01*
X719916Y514161D01*
X720208D01*
X720499Y514244D01*
X720749Y514369D01*
X720958Y514536D01*
G01X723516Y514161D02*
Y516661D01*
X721974Y514869D01*
X724058D01*
G01X726449Y515494D02*
X726616Y515619D01*
X726741Y515828D01*
X726824Y516119D01*
X726741Y516369D01*
X726574Y516536D01*
X726283Y516661D01*
X725158D01*
Y514161D01*
X726533D01*
X726824Y514328D01*
X726991Y514578D01*
X727074Y514869D01*
X726991Y515161D01*
X726741Y515411D01*
X726449Y515494D01*
X725158D01*
G01X729216Y514161D02*
Y516661D01*
X728716Y516161D01*
G01Y514161D02*
X729716D01*
G01X685850Y525100D02*
Y552400D01*
X713150D01*
Y525100D01*
X685850D01*
G01X720297Y550298D02*
X720172Y550048D01*
X720089Y549756D01*
Y549423D01*
X720214Y549048D01*
X720422Y548756D01*
X720672Y548548D01*
X721089Y548381D01*
X721464Y548339D01*
X721839Y548423D01*
X722089Y548548D01*
X722339Y548798D01*
X722506Y549089D01*
X722589Y549381D01*
Y549673D01*
X722506Y549964D01*
X722381Y550214D01*
X722214Y550423D01*
G01X722589Y552981D02*
X720089D01*
X721881Y551439D01*
Y553523D01*
G01X722589Y554539D02*
X720089Y555581D01*
X722589Y556623D01*
G01X721714Y556248D02*
Y554914D01*
G01X722589Y558681D02*
X720089D01*
X720589Y558181D01*
G01X722589D02*
Y559181D01*
G01X722297Y561073D02*
X722506Y561364D01*
X722589Y561698D01*
X722506Y562031D01*
X722256Y562323D01*
X721881Y562531D01*
X721506Y562614D01*
X721047D01*
X720672Y562531D01*
X720339Y562323D01*
X720172Y562073D01*
X720089Y561781D01*
X720172Y561448D01*
X720339Y561198D01*
X720589Y561031D01*
X720922Y560948D01*
X721214Y561031D01*
X721506Y561239D01*
X721672Y561489D01*
X721714Y561781D01*
X721631Y562114D01*
X721422Y562364D01*
X721047Y562614D01*
G01X686855Y557320D02*
Y559820D01*
X687896D01*
X688230Y559695D01*
X688438Y559528D01*
X688521Y559195D01*
X688438Y558862D01*
X688188Y558653D01*
X687896Y558528D01*
X686855D01*
G01X687896D02*
X688521Y557320D01*
G01X691288D02*
Y559820D01*
X689746Y558028D01*
X691830D01*
G01X692846Y557320D02*
X693888Y559820D01*
X694930Y557320D01*
G01X694555Y558195D02*
X693221D01*
G01X696905Y557320D02*
X696988Y557862D01*
X697113Y558320D01*
X697280Y558737D01*
X697488Y559195D01*
X697821Y559820D01*
X696155D01*
G01X689555Y565041D02*
Y567541D01*
X690596D01*
X690930Y567416D01*
X691138Y567249D01*
X691221Y566916D01*
X691138Y566583D01*
X690888Y566374D01*
X690596Y566249D01*
X689555D01*
G01X690596D02*
X691221Y565041D01*
G01X693988D02*
Y567541D01*
X692446Y565749D01*
X694530D01*
G01X695546Y565041D02*
X696588Y567541D01*
X697630Y565041D01*
G01X697255Y565916D02*
X695921D01*
G01X698980Y565333D02*
X699271Y565124D01*
X699605Y565041D01*
X699938Y565124D01*
X700230Y565374D01*
X700438Y565749D01*
X700521Y566124D01*
Y566583D01*
X700438Y566958D01*
X700230Y567291D01*
X699980Y567458D01*
X699688Y567541D01*
X699355Y567458D01*
X699105Y567291D01*
X698938Y567041D01*
X698855Y566708D01*
X698938Y566416D01*
X699146Y566124D01*
X699396Y565958D01*
X699688Y565916D01*
X700021Y565999D01*
X700271Y566208D01*
X700521Y566583D01*
G01X689485Y568521D02*
Y571021D01*
X690526D01*
X690860Y570896D01*
X691068Y570729D01*
X691151Y570396D01*
X691068Y570063D01*
X690818Y569854D01*
X690526Y569729D01*
X689485D01*
G01X690526D02*
X691151Y568521D01*
G01X693918D02*
Y571021D01*
X692376Y569229D01*
X694460D01*
G01X695476Y568521D02*
X696518Y571021D01*
X697560Y568521D01*
G01X697185Y569396D02*
X695851D01*
G01X699618Y568521D02*
X699910Y568563D01*
X700243Y568688D01*
X700451Y568896D01*
X700535Y569188D01*
X700451Y569479D01*
X700201Y569729D01*
X699826Y569854D01*
X699410D01*
X699160Y569938D01*
X698951Y570146D01*
X698868Y570438D01*
X698993Y570729D01*
X699285Y570938D01*
X699618Y571021D01*
X699951Y570938D01*
X700243Y570729D01*
X700368Y570438D01*
X700285Y570146D01*
X700076Y569938D01*
X699826Y569854D01*
X699410D01*
X699035Y569729D01*
X698785Y569479D01*
X698701Y569188D01*
X698785Y568896D01*
X698993Y568688D01*
X699326Y568563D01*
X699618Y568521D01*
G01X692368Y587103D02*
Y589603D01*
X693409D01*
X693743Y589478D01*
X693951Y589311D01*
X694034Y588978D01*
X693951Y588645D01*
X693701Y588436D01*
X693409Y588311D01*
X692368D01*
G01X693409D02*
X694034Y587103D01*
G01X696801D02*
Y589603D01*
X695259Y587811D01*
X697343D01*
G01X698359Y587103D02*
X699401Y589603D01*
X700443Y587103D01*
G01X700068Y587978D02*
X698734D01*
G01X701584Y587478D02*
X701834Y587270D01*
X702126Y587145D01*
X702501Y587103D01*
X702876Y587186D01*
X703168Y587353D01*
X703376Y587645D01*
X703418Y587978D01*
X703334Y588311D01*
X703126Y588520D01*
X702834Y588686D01*
X702543Y588728D01*
X702251Y588686D01*
X701876Y588520D01*
X702001Y589603D01*
X703126D01*
G01X666494Y558531D02*
Y561031D01*
X667535D01*
X667869Y560906D01*
X668077Y560739D01*
X668160Y560406D01*
X668077Y560073D01*
X667827Y559864D01*
X667535Y559739D01*
X666494D01*
G01X667535D02*
X668160Y558531D01*
G01X670927D02*
Y561031D01*
X669385Y559239D01*
X671469D01*
G01X673860Y559864D02*
X674027Y559989D01*
X674152Y560198D01*
X674235Y560489D01*
X674152Y560739D01*
X673985Y560906D01*
X673694Y561031D01*
X672569D01*
Y558531D01*
X673944D01*
X674235Y558698D01*
X674402Y558948D01*
X674485Y559239D01*
X674402Y559531D01*
X674152Y559781D01*
X673860Y559864D01*
X672569D01*
G01X676627Y558531D02*
Y561031D01*
X676127Y560531D01*
G01Y558531D02*
X677127D01*
G01X678810Y559031D02*
X679060Y558739D01*
X679394Y558573D01*
X679769Y558531D01*
X680102Y558573D01*
X680435Y558781D01*
X680644Y559031D01*
X680685Y559281D01*
X680602Y559573D01*
X680310Y559781D01*
X680019Y559864D01*
X679644D01*
G01X680019D02*
X680269Y559989D01*
X680477Y560198D01*
X680560Y560448D01*
X680477Y560698D01*
X680269Y560906D01*
X679894Y561031D01*
X679519Y560989D01*
X679144Y560823D01*
G01X721941Y567220D02*
X721816Y566970D01*
X721733Y566678D01*
Y566345D01*
X721858Y565970D01*
X722066Y565678D01*
X722316Y565470D01*
X722733Y565303D01*
X723108Y565261D01*
X723483Y565345D01*
X723733Y565470D01*
X723983Y565720D01*
X724150Y566011D01*
X724233Y566303D01*
Y566595D01*
X724150Y566886D01*
X724025Y567136D01*
X723858Y567345D01*
G01X724233Y569903D02*
X721733D01*
X723525Y568361D01*
Y570445D01*
G01X724233Y571461D02*
X721733Y572503D01*
X724233Y573545D01*
G01X723358Y573170D02*
Y571836D01*
G01X724233Y575603D02*
X721733D01*
X722233Y575103D01*
G01X724233D02*
Y576103D01*
G01Y578703D02*
X721733D01*
X722233Y578203D01*
G01X724233D02*
Y579203D01*
G01X694207Y585791D02*
X693957Y585916D01*
X693665Y585999D01*
X693332D01*
X692957Y585874D01*
X692665Y585666D01*
X692457Y585416D01*
X692290Y584999D01*
X692248Y584624D01*
X692332Y584249D01*
X692457Y583999D01*
X692707Y583749D01*
X692998Y583582D01*
X693290Y583499D01*
X693582D01*
X693873Y583582D01*
X694123Y583707D01*
X694332Y583874D01*
G01X696890Y583499D02*
Y585999D01*
X695348Y584207D01*
X697432D01*
G01X698448Y583499D02*
X699490Y585999D01*
X700532Y583499D01*
G01X700157Y584374D02*
X698823D01*
G01X702507Y583499D02*
X702590Y584041D01*
X702715Y584499D01*
X702882Y584916D01*
X703090Y585374D01*
X703423Y585999D01*
X701757D01*
G01X716569Y542255D02*
X716444Y542005D01*
X716361Y541713D01*
Y541380D01*
X716486Y541005D01*
X716694Y540713D01*
X716944Y540505D01*
X717361Y540338D01*
X717736Y540296D01*
X718111Y540380D01*
X718361Y540505D01*
X718611Y540755D01*
X718778Y541046D01*
X718861Y541338D01*
Y541630D01*
X718778Y541921D01*
X718653Y542171D01*
X718486Y542380D01*
G01X718861Y544938D02*
X716361D01*
X718153Y543396D01*
Y545480D01*
G01X718861Y546496D02*
X716361Y547538D01*
X718861Y548580D01*
G01X717986Y548205D02*
Y546871D01*
G01X716778Y549846D02*
X716528Y550096D01*
X716403Y550388D01*
X716361Y550721D01*
X716444Y551138D01*
X716653Y551430D01*
X716903Y551513D01*
X717153Y551471D01*
X717361Y551305D01*
X717778Y550471D01*
X718069Y550096D01*
X718486Y549846D01*
X718861Y549763D01*
Y551513D01*
G01X716361Y553738D02*
X716444Y553405D01*
X716653Y553155D01*
X716903Y552988D01*
X717236Y552863D01*
X717611Y552821D01*
X717986Y552863D01*
X718319Y552988D01*
X718569Y553155D01*
X718778Y553405D01*
X718861Y553738D01*
X718778Y554071D01*
X718569Y554321D01*
X718319Y554488D01*
X717986Y554613D01*
X717611Y554655D01*
X717236Y554613D01*
X716903Y554488D01*
X716653Y554321D01*
X716444Y554071D01*
X716361Y553738D01*
G01X683499Y563718D02*
X683249Y563843D01*
X682957Y563926D01*
X682624D01*
X682249Y563801D01*
X681957Y563593D01*
X681749Y563343D01*
X681582Y562926D01*
X681540Y562551D01*
X681624Y562176D01*
X681749Y561926D01*
X681999Y561676D01*
X682290Y561509D01*
X682582Y561426D01*
X682874D01*
X683165Y561509D01*
X683415Y561634D01*
X683624Y561801D01*
G01X686182Y561426D02*
Y563926D01*
X684640Y562134D01*
X686724D01*
G01X687740Y561426D02*
X688782Y563926D01*
X689824Y561426D01*
G01X689449Y562301D02*
X688115D01*
G01X691882Y561426D02*
Y563926D01*
X691382Y563426D01*
G01Y561426D02*
X692382D01*
G01X694190Y562468D02*
X694482Y562759D01*
X694732Y562926D01*
X695065Y563009D01*
X695357Y562926D01*
X695565Y562759D01*
X695732Y562509D01*
X695774Y562218D01*
X695732Y561968D01*
X695565Y561718D01*
X695315Y561509D01*
X695024Y561426D01*
X694690Y561509D01*
X694399Y561759D01*
X694232Y562134D01*
X694190Y562551D01*
X694274Y563093D01*
X694399Y563384D01*
X694607Y563676D01*
X694899Y563884D01*
X695190Y563926D01*
X695482Y563843D01*
X695690Y563634D01*
G01X715033Y557962D02*
X714908Y557712D01*
X714825Y557420D01*
Y557087D01*
X714950Y556712D01*
X715158Y556420D01*
X715408Y556212D01*
X715825Y556045D01*
X716200Y556003D01*
X716575Y556087D01*
X716825Y556212D01*
X717075Y556462D01*
X717242Y556753D01*
X717325Y557045D01*
Y557337D01*
X717242Y557628D01*
X717117Y557878D01*
X716950Y558087D01*
G01X717325Y560645D02*
X714825D01*
X716617Y559103D01*
Y561187D01*
G01X717325Y562203D02*
X714825Y563245D01*
X717325Y564287D01*
G01X716450Y563912D02*
Y562578D01*
G01X717325Y566345D02*
X714825D01*
X715325Y565845D01*
G01X717325D02*
Y566845D01*
G01X714825Y569445D02*
X714908Y569112D01*
X715117Y568862D01*
X715367Y568695D01*
X715700Y568570D01*
X716075Y568528D01*
X716450Y568570D01*
X716783Y568695D01*
X717033Y568862D01*
X717242Y569112D01*
X717325Y569445D01*
X717242Y569778D01*
X717033Y570028D01*
X716783Y570195D01*
X716450Y570320D01*
X716075Y570362D01*
X715700Y570320D01*
X715367Y570195D01*
X715117Y570028D01*
X714908Y569778D01*
X714825Y569445D01*
G01X708316Y581516D02*
X708191Y581266D01*
X708108Y580974D01*
Y580641D01*
X708233Y580266D01*
X708441Y579974D01*
X708691Y579766D01*
X709108Y579599D01*
X709483Y579557D01*
X709858Y579641D01*
X710108Y579766D01*
X710358Y580016D01*
X710525Y580307D01*
X710608Y580599D01*
Y580891D01*
X710525Y581182D01*
X710400Y581432D01*
X710233Y581641D01*
G01X710608Y584199D02*
X708108D01*
X709900Y582657D01*
Y584741D01*
G01X710608Y585757D02*
X708108Y586799D01*
X710608Y587841D01*
G01X709733Y587466D02*
Y586132D01*
G01X710316Y589191D02*
X710525Y589482D01*
X710608Y589816D01*
X710525Y590149D01*
X710275Y590441D01*
X709900Y590649D01*
X709525Y590732D01*
X709066D01*
X708691Y590649D01*
X708358Y590441D01*
X708191Y590191D01*
X708108Y589899D01*
X708191Y589566D01*
X708358Y589316D01*
X708608Y589149D01*
X708941Y589066D01*
X709233Y589149D01*
X709525Y589357D01*
X709691Y589607D01*
X709733Y589899D01*
X709650Y590232D01*
X709441Y590482D01*
X709066Y590732D01*
G01X696227Y582201D02*
X695977Y582326D01*
X695685Y582409D01*
X695352D01*
X694977Y582284D01*
X694685Y582076D01*
X694477Y581826D01*
X694310Y581409D01*
X694268Y581034D01*
X694352Y580659D01*
X694477Y580409D01*
X694727Y580159D01*
X695018Y579992D01*
X695310Y579909D01*
X695602D01*
X695893Y579992D01*
X696143Y580117D01*
X696352Y580284D01*
G01X698910Y579909D02*
Y582409D01*
X697368Y580617D01*
X699452D01*
G01X700468Y579909D02*
X701510Y582409D01*
X702552Y579909D01*
G01X702177Y580784D02*
X700843D01*
G01X704610Y579909D02*
X704902Y579951D01*
X705235Y580076D01*
X705443Y580284D01*
X705527Y580576D01*
X705443Y580867D01*
X705193Y581117D01*
X704818Y581242D01*
X704402D01*
X704152Y581326D01*
X703943Y581534D01*
X703860Y581826D01*
X703985Y582117D01*
X704277Y582326D01*
X704610Y582409D01*
X704943Y582326D01*
X705235Y582117D01*
X705360Y581826D01*
X705277Y581534D01*
X705068Y581326D01*
X704818Y581242D01*
X704402D01*
X704027Y581117D01*
X703777Y580867D01*
X703693Y580576D01*
X703777Y580284D01*
X703985Y580076D01*
X704318Y579951D01*
X704610Y579909D01*
G01X690481Y578790D02*
X690231Y578915D01*
X689939Y578998D01*
X689606D01*
X689231Y578873D01*
X688939Y578665D01*
X688731Y578415D01*
X688564Y577998D01*
X688522Y577623D01*
X688606Y577248D01*
X688731Y576998D01*
X688981Y576748D01*
X689272Y576581D01*
X689564Y576498D01*
X689856D01*
X690147Y576581D01*
X690397Y576706D01*
X690606Y576873D01*
G01X693164Y576498D02*
Y578998D01*
X691622Y577206D01*
X693706D01*
G01X694722Y576498D02*
X695764Y578998D01*
X696806Y576498D01*
G01X696431Y577373D02*
X695097D01*
G01X698864Y576498D02*
Y578998D01*
X698364Y578498D01*
G01Y576498D02*
X699364D01*
G01X702464D02*
Y578998D01*
X700922Y577206D01*
X703006D01*
G01X666720Y586808D02*
X665054D01*
Y589308D01*
X666720D01*
G01X666054Y588100D02*
X665054D01*
G01X668070Y589308D02*
Y587516D01*
X668237Y587141D01*
X668570Y586891D01*
X668987Y586808D01*
X669404Y586891D01*
X669737Y587141D01*
X669904Y587516D01*
Y589308D01*
G01X672587Y586808D02*
Y589308D01*
X671045Y587516D01*
X673129D01*
G01X674145Y586808D02*
X675187Y589308D01*
X676229Y586808D01*
G01X675854Y587683D02*
X674520D01*
G01X677495Y588891D02*
X677745Y589141D01*
X678037Y589266D01*
X678370Y589308D01*
X678787Y589225D01*
X679079Y589016D01*
X679162Y588766D01*
X679120Y588516D01*
X678954Y588308D01*
X678120Y587891D01*
X677745Y587600D01*
X677495Y587183D01*
X677412Y586808D01*
X679162D01*
G01X700838Y557191D02*
X699172D01*
Y559691D01*
X700838D01*
G01X700172Y558483D02*
X699172D01*
G01X702188Y559691D02*
Y557899D01*
X702355Y557524D01*
X702688Y557274D01*
X703105Y557191D01*
X703522Y557274D01*
X703855Y557524D01*
X704022Y557899D01*
Y559691D01*
G01X706705Y557191D02*
Y559691D01*
X705163Y557899D01*
X707247D01*
G01X708263Y557191D02*
X709305Y559691D01*
X710347Y557191D01*
G01X709972Y558066D02*
X708638D01*
G01X711488Y557691D02*
X711738Y557399D01*
X712072Y557233D01*
X712447Y557191D01*
X712780Y557233D01*
X713113Y557441D01*
X713322Y557691D01*
X713363Y557941D01*
X713280Y558233D01*
X712988Y558441D01*
X712697Y558524D01*
X712322D01*
G01X712697D02*
X712947Y558649D01*
X713155Y558858D01*
X713238Y559108D01*
X713155Y559358D01*
X712947Y559566D01*
X712572Y559691D01*
X712197Y559649D01*
X711822Y559483D01*
G01X711705Y527341D02*
Y526545D01*
X710907D01*
G01Y550955D02*
X711705D01*
Y550159D01*
G01X687295D02*
Y550955D01*
X688079D01*
G01Y526545D02*
X687295D01*
Y527341D01*
G01X709701Y619092D02*
X709451Y619217D01*
X709159Y619300D01*
X708826D01*
X708451Y619175D01*
X708159Y618967D01*
X707951Y618717D01*
X707784Y618300D01*
X707742Y617925D01*
X707826Y617550D01*
X707951Y617300D01*
X708201Y617050D01*
X708492Y616883D01*
X708784Y616800D01*
X709076D01*
X709367Y616883D01*
X709617Y617008D01*
X709826Y617175D01*
G01X712384Y616800D02*
Y619300D01*
X710842Y617508D01*
X712926D01*
G01X713942Y616800D02*
X714984Y619300D01*
X716026Y616800D01*
G01X715651Y617675D02*
X714317D01*
G01X718084Y616800D02*
Y619300D01*
X717584Y618800D01*
G01Y616800D02*
X718584D01*
G01X709559Y623024D02*
X709309Y623149D01*
X709017Y623232D01*
X708684D01*
X708309Y623107D01*
X708017Y622899D01*
X707809Y622649D01*
X707642Y622232D01*
X707600Y621857D01*
X707684Y621482D01*
X707809Y621232D01*
X708059Y620982D01*
X708350Y620815D01*
X708642Y620732D01*
X708934D01*
X709225Y620815D01*
X709475Y620940D01*
X709684Y621107D01*
G01X712242Y620732D02*
Y623232D01*
X710700Y621440D01*
X712784D01*
G01X713592Y623232D02*
X714175Y620732D01*
X714842Y623232D01*
X715509Y620732D01*
X716092Y623232D01*
G01X717025Y621107D02*
X717275Y620899D01*
X717567Y620774D01*
X717942Y620732D01*
X718317Y620815D01*
X718609Y620982D01*
X718817Y621274D01*
X718859Y621607D01*
X718775Y621940D01*
X718567Y622149D01*
X718275Y622315D01*
X717984Y622357D01*
X717692Y622315D01*
X717317Y622149D01*
X717442Y623232D01*
X718567D01*
G01X692368Y590603D02*
Y593103D01*
X693409D01*
X693743Y592978D01*
X693951Y592811D01*
X694034Y592478D01*
X693951Y592145D01*
X693701Y591936D01*
X693409Y591811D01*
X692368D01*
G01X693409D02*
X694034Y590603D01*
G01X696801D02*
Y593103D01*
X695259Y591311D01*
X697343D01*
G01X698359Y590603D02*
X699401Y593103D01*
X700443Y590603D01*
G01X700068Y591478D02*
X698734D01*
G01X703001Y590603D02*
Y593103D01*
X701459Y591311D01*
X703543D01*
G01X673371Y596138D02*
X673121Y596263D01*
X672829Y596346D01*
X672496D01*
X672121Y596221D01*
X671829Y596013D01*
X671621Y595763D01*
X671454Y595346D01*
X671412Y594971D01*
X671496Y594596D01*
X671621Y594346D01*
X671871Y594096D01*
X672162Y593929D01*
X672454Y593846D01*
X672746D01*
X673037Y593929D01*
X673287Y594054D01*
X673496Y594221D01*
G01X676054Y593846D02*
Y596346D01*
X674512Y594554D01*
X676596D01*
G01X677612Y593846D02*
X678654Y596346D01*
X679696Y593846D01*
G01X679321Y594721D02*
X677987D01*
G01X680837Y594346D02*
X681087Y594054D01*
X681421Y593888D01*
X681796Y593846D01*
X682129Y593888D01*
X682462Y594096D01*
X682671Y594346D01*
X682712Y594596D01*
X682629Y594888D01*
X682337Y595096D01*
X682046Y595179D01*
X681671D01*
G01X682046D02*
X682296Y595304D01*
X682504Y595513D01*
X682587Y595763D01*
X682504Y596013D01*
X682296Y596221D01*
X681921Y596346D01*
X681546Y596304D01*
X681171Y596138D01*
G01X802984Y-38057D02*
X784984D01*
Y-56057D01*
X802984D01*
Y-38057D01*
G01X734500Y31500D02*
Y30100D01*
X732800D01*
Y25600D01*
X728200D01*
Y12600D01*
X725600D01*
G01X777232Y15603D02*
X776982Y15728D01*
X776690Y15811D01*
X776357D01*
X775982Y15686D01*
X775690Y15478D01*
X775482Y15228D01*
X775315Y14811D01*
X775273Y14436D01*
X775357Y14061D01*
X775482Y13811D01*
X775732Y13561D01*
X776023Y13394D01*
X776315Y13311D01*
X776607D01*
X776898Y13394D01*
X777148Y13519D01*
X777357Y13686D01*
G01X779915Y13311D02*
Y15811D01*
X778373Y14019D01*
X780457D01*
G01X782765Y14561D02*
X783598D01*
Y13811D01*
X783348Y13561D01*
X783057Y13394D01*
X782640Y13311D01*
X782223Y13394D01*
X781932Y13561D01*
X781682Y13811D01*
X781515Y14103D01*
X781432Y14436D01*
Y14728D01*
X781515Y14978D01*
X781682Y15269D01*
X781932Y15519D01*
X782182Y15686D01*
X782515Y15811D01*
X782807D01*
X783140Y15728D01*
X783390Y15561D01*
G01X785615Y13311D02*
Y15811D01*
X785115Y15311D01*
G01Y13311D02*
X786115D01*
G01X788632D02*
X788715Y13853D01*
X788840Y14311D01*
X789007Y14728D01*
X789215Y15186D01*
X789548Y15811D01*
X787882D01*
G01X768602Y7550D02*
Y10650D01*
X768142Y10030D01*
G01Y7550D02*
X769062D01*
G01X772162D02*
Y10650D01*
X770744Y8428D01*
X772660D01*
G01X773959Y8015D02*
X774189Y7757D01*
X774457Y7602D01*
X774802Y7550D01*
X775147Y7653D01*
X775415Y7860D01*
X775607Y8222D01*
X775645Y8635D01*
X775569Y9048D01*
X775377Y9307D01*
X775109Y9513D01*
X774840Y9565D01*
X774572Y9513D01*
X774227Y9307D01*
X774342Y10650D01*
X775377D01*
G01X760710Y-18617D02*
X736320D01*
Y6973D01*
X760710D01*
G01X734534Y16400D02*
X731434D01*
X732054Y15940D01*
G01X734534D02*
Y16860D01*
G01Y19960D02*
X731434D01*
X733656Y18542D01*
Y20458D01*
G01X734069Y21757D02*
X734327Y21987D01*
X734482Y22255D01*
X734534Y22600D01*
X734431Y22945D01*
X734224Y23213D01*
X733862Y23405D01*
X733449Y23443D01*
X733036Y23367D01*
X732777Y23175D01*
X732571Y22907D01*
X732519Y22638D01*
X732571Y22370D01*
X732777Y22025D01*
X731434Y22140D01*
Y23175D01*
G01X760710Y19183D02*
X736320D01*
Y44773D01*
X760710D01*
G01X732089Y1477D02*
Y-189D01*
X729589D01*
Y1477D01*
G01X730797Y811D02*
Y-189D01*
G01X729589Y2827D02*
X731381D01*
X731756Y2994D01*
X732006Y3327D01*
X732089Y3744D01*
X732006Y4161D01*
X731756Y4494D01*
X731381Y4661D01*
X729589D01*
G01X732089Y7344D02*
X729589D01*
X731381Y5802D01*
Y7886D01*
G01X730839Y10194D02*
Y11027D01*
X731589D01*
X731839Y10777D01*
X732006Y10486D01*
X732089Y10069D01*
X732006Y9652D01*
X731839Y9361D01*
X731589Y9111D01*
X731297Y8944D01*
X730964Y8861D01*
X730672D01*
X730422Y8944D01*
X730131Y9111D01*
X729881Y9361D01*
X729714Y9611D01*
X729589Y9944D01*
Y10236D01*
X729672Y10569D01*
X729839Y10819D01*
G01X731589Y12127D02*
X731881Y12377D01*
X732047Y12711D01*
X732089Y13086D01*
X732047Y13419D01*
X731839Y13752D01*
X731589Y13961D01*
X731339Y14002D01*
X731047Y13919D01*
X730839Y13627D01*
X730756Y13336D01*
Y12961D01*
G01Y13336D02*
X730631Y13586D01*
X730422Y13794D01*
X730172Y13877D01*
X729922Y13794D01*
X729714Y13586D01*
X729589Y13211D01*
X729631Y12836D01*
X729797Y12461D01*
G01X725500Y47000D02*
X734500D01*
Y40500D01*
G01X785762Y46017D02*
X783262D01*
Y47058D01*
X783387Y47392D01*
X783554Y47600D01*
X783887Y47683D01*
X784220Y47600D01*
X784429Y47350D01*
X784554Y47058D01*
Y46017D01*
G01Y47058D02*
X785762Y47683D01*
G01Y50450D02*
X783262D01*
X785054Y48908D01*
Y50992D01*
G01X784512Y53300D02*
Y54133D01*
X785262D01*
X785512Y53883D01*
X785679Y53592D01*
X785762Y53175D01*
X785679Y52758D01*
X785512Y52467D01*
X785262Y52217D01*
X784970Y52050D01*
X784637Y51967D01*
X784345D01*
X784095Y52050D01*
X783804Y52217D01*
X783554Y52467D01*
X783387Y52717D01*
X783262Y53050D01*
Y53342D01*
X783345Y53675D01*
X783512Y53925D01*
G01X785762Y56150D02*
X783262D01*
X783762Y55650D01*
G01X785762D02*
Y56650D01*
G01X777207Y47514D02*
X777082Y47264D01*
X776999Y46972D01*
Y46639D01*
X777124Y46264D01*
X777332Y45972D01*
X777582Y45764D01*
X777999Y45597D01*
X778374Y45555D01*
X778749Y45639D01*
X778999Y45764D01*
X779249Y46014D01*
X779416Y46305D01*
X779499Y46597D01*
Y46889D01*
X779416Y47180D01*
X779291Y47430D01*
X779124Y47639D01*
G01X779499Y50197D02*
X776999D01*
X778791Y48655D01*
Y50739D01*
G01X778249Y53047D02*
Y53880D01*
X778999D01*
X779249Y53630D01*
X779416Y53339D01*
X779499Y52922D01*
X779416Y52505D01*
X779249Y52214D01*
X778999Y51964D01*
X778707Y51797D01*
X778374Y51714D01*
X778082D01*
X777832Y51797D01*
X777541Y51964D01*
X777291Y52214D01*
X777124Y52464D01*
X776999Y52797D01*
Y53089D01*
X777082Y53422D01*
X777249Y53672D01*
G01X779499Y55897D02*
X776999D01*
X777499Y55397D01*
G01X779499D02*
Y56397D01*
G01X769520Y97443D02*
X769270Y97568D01*
X768978Y97651D01*
X768645D01*
X768270Y97526D01*
X767978Y97318D01*
X767770Y97068D01*
X767603Y96651D01*
X767561Y96276D01*
X767645Y95901D01*
X767770Y95651D01*
X768020Y95401D01*
X768311Y95234D01*
X768603Y95151D01*
X768895D01*
X769186Y95234D01*
X769436Y95359D01*
X769645Y95526D01*
G01X772203Y95151D02*
Y97651D01*
X770661Y95859D01*
X772745D01*
G01X774011Y95151D02*
Y97651D01*
X775595D01*
G01X775011Y96443D02*
X774011D01*
G01X777903Y95151D02*
Y97651D01*
X777403Y97151D01*
G01Y95151D02*
X778403D01*
G01X781003Y97651D02*
X780670Y97568D01*
X780420Y97359D01*
X780253Y97109D01*
X780128Y96776D01*
X780086Y96401D01*
X780128Y96026D01*
X780253Y95693D01*
X780420Y95443D01*
X780670Y95234D01*
X781003Y95151D01*
X781336Y95234D01*
X781586Y95443D01*
X781753Y95693D01*
X781878Y96026D01*
X781920Y96401D01*
X781878Y96776D01*
X781753Y97109D01*
X781586Y97359D01*
X781336Y97568D01*
X781003Y97651D01*
G01X728888Y63540D02*
X726388D01*
Y65124D01*
G01X727596Y64540D02*
Y63540D01*
G01X727555Y67765D02*
X727430Y67932D01*
X727221Y68057D01*
X726930Y68140D01*
X726680Y68057D01*
X726513Y67890D01*
X726388Y67599D01*
Y66474D01*
X728888D01*
Y67849D01*
X728721Y68140D01*
X728471Y68307D01*
X728180Y68390D01*
X727888Y68307D01*
X727638Y68057D01*
X727555Y67765D01*
Y66474D01*
G01X728888Y71032D02*
X726388D01*
X728180Y69490D01*
Y71574D01*
G01X727638Y73882D02*
Y74715D01*
X728388D01*
X728638Y74465D01*
X728805Y74174D01*
X728888Y73757D01*
X728805Y73340D01*
X728638Y73049D01*
X728388Y72799D01*
X728096Y72632D01*
X727763Y72549D01*
X727471D01*
X727221Y72632D01*
X726930Y72799D01*
X726680Y73049D01*
X726513Y73299D01*
X726388Y73632D01*
Y73924D01*
X726471Y74257D01*
X726638Y74507D01*
G01X728888Y76732D02*
X726388D01*
X726888Y76232D01*
G01X728888D02*
Y77232D01*
G01X764842Y83220D02*
Y86320D01*
X764382Y85700D01*
G01Y83220D02*
X765302D01*
G01X768402D02*
Y86320D01*
X766984Y84098D01*
X768900D01*
G01X770199Y83685D02*
X770429Y83427D01*
X770697Y83272D01*
X771042Y83220D01*
X771387Y83323D01*
X771655Y83530D01*
X771847Y83892D01*
X771885Y84305D01*
X771809Y84718D01*
X771617Y84977D01*
X771349Y85183D01*
X771080Y85235D01*
X770812Y85183D01*
X770467Y84977D01*
X770582Y86320D01*
X771617D01*
G01X760710Y56983D02*
X736320D01*
Y82573D01*
X760710D01*
G01X755510Y95857D02*
X753010D01*
Y96898D01*
X753135Y97232D01*
X753302Y97440D01*
X753635Y97523D01*
X753968Y97440D01*
X754177Y97190D01*
X754302Y96898D01*
Y95857D01*
G01Y96898D02*
X755510Y97523D01*
G01Y100290D02*
X753010D01*
X754802Y98748D01*
Y100832D01*
G01X755510Y102098D02*
X753010D01*
Y103682D01*
G01X754218Y103098D02*
Y102098D01*
G01X755010Y105073D02*
X755302Y105323D01*
X755468Y105657D01*
X755510Y106032D01*
X755468Y106365D01*
X755260Y106698D01*
X755010Y106907D01*
X754760Y106948D01*
X754468Y106865D01*
X754260Y106573D01*
X754177Y106282D01*
Y105907D01*
G01Y106282D02*
X754052Y106532D01*
X753843Y106740D01*
X753593Y106823D01*
X753343Y106740D01*
X753135Y106532D01*
X753010Y106157D01*
X753052Y105782D01*
X753218Y105407D01*
G01X760666Y97548D02*
X758166D01*
Y98589D01*
X758291Y98923D01*
X758458Y99131D01*
X758791Y99214D01*
X759124Y99131D01*
X759333Y98881D01*
X759458Y98589D01*
Y97548D01*
G01Y98589D02*
X760666Y99214D01*
G01Y101981D02*
X758166D01*
X759958Y100439D01*
Y102523D01*
G01X760666Y103789D02*
X758166D01*
Y105373D01*
G01X759374Y104789D02*
Y103789D01*
G01X760666Y108181D02*
X758166D01*
X759958Y106639D01*
Y108723D01*
G01X764516Y97390D02*
X762016D01*
Y98431D01*
X762141Y98765D01*
X762308Y98973D01*
X762641Y99056D01*
X762974Y98973D01*
X763183Y98723D01*
X763308Y98431D01*
Y97390D01*
G01Y98431D02*
X764516Y99056D01*
G01Y101823D02*
X762016D01*
X763808Y100281D01*
Y102365D01*
G01X764516Y103631D02*
X762016D01*
Y105215D01*
G01X763224Y104631D02*
Y103631D01*
G01X764141Y106606D02*
X764349Y106856D01*
X764474Y107148D01*
X764516Y107523D01*
X764433Y107898D01*
X764266Y108190D01*
X763974Y108398D01*
X763641Y108440D01*
X763308Y108356D01*
X763099Y108148D01*
X762933Y107856D01*
X762891Y107565D01*
X762933Y107273D01*
X763099Y106898D01*
X762016Y107023D01*
Y108148D01*
G01X749427Y98200D02*
X749302Y97950D01*
X749219Y97658D01*
Y97325D01*
X749344Y96950D01*
X749552Y96658D01*
X749802Y96450D01*
X750219Y96283D01*
X750594Y96241D01*
X750969Y96325D01*
X751219Y96450D01*
X751469Y96700D01*
X751636Y96991D01*
X751719Y97283D01*
Y97575D01*
X751636Y97866D01*
X751511Y98116D01*
X751344Y98325D01*
G01X751719Y100883D02*
X749219D01*
X751011Y99341D01*
Y101425D01*
G01X751719Y102691D02*
X749219D01*
Y104275D01*
G01X750427Y103691D02*
Y102691D01*
G01X751427Y105875D02*
X751636Y106166D01*
X751719Y106500D01*
X751636Y106833D01*
X751386Y107125D01*
X751011Y107333D01*
X750636Y107416D01*
X750177D01*
X749802Y107333D01*
X749469Y107125D01*
X749302Y106875D01*
X749219Y106583D01*
X749302Y106250D01*
X749469Y106000D01*
X749719Y105833D01*
X750052Y105750D01*
X750344Y105833D01*
X750636Y106041D01*
X750802Y106291D01*
X750844Y106583D01*
X750761Y106916D01*
X750552Y107166D01*
X750177Y107416D01*
G01X728804Y142431D02*
X728554Y142556D01*
X728262Y142639D01*
X727929D01*
X727554Y142514D01*
X727262Y142306D01*
X727054Y142056D01*
X726887Y141639D01*
X726845Y141264D01*
X726929Y140889D01*
X727054Y140639D01*
X727304Y140389D01*
X727595Y140222D01*
X727887Y140139D01*
X728179D01*
X728470Y140222D01*
X728720Y140347D01*
X728929Y140514D01*
G01X731487Y140139D02*
Y142639D01*
X729945Y140847D01*
X732029D01*
G01X733295Y140139D02*
Y142639D01*
X734879D01*
G01X734295Y141431D02*
X733295D01*
G01X737687Y140139D02*
Y142639D01*
X736145Y140847D01*
X738229D01*
G01X745500Y120500D02*
Y123195D01*
G01Y138500D02*
Y135802D01*
G01X735486Y98167D02*
X732986D01*
Y99208D01*
X733111Y99542D01*
X733278Y99750D01*
X733611Y99833D01*
X733944Y99750D01*
X734153Y99500D01*
X734278Y99208D01*
Y98167D01*
G01Y99208D02*
X735486Y99833D01*
G01Y102600D02*
X732986D01*
X734778Y101058D01*
Y103142D01*
G01X735486Y104408D02*
X732986D01*
Y105992D01*
G01X734194Y105408D02*
Y104408D01*
G01X733403Y107508D02*
X733153Y107758D01*
X733028Y108050D01*
X732986Y108383D01*
X733069Y108800D01*
X733278Y109092D01*
X733528Y109175D01*
X733778Y109133D01*
X733986Y108967D01*
X734403Y108133D01*
X734694Y107758D01*
X735111Y107508D01*
X735486Y107425D01*
Y109175D01*
G01X731050Y96313D02*
Y100638D01*
G01X777440Y113250D02*
X775740D01*
Y129750D01*
X777440D01*
G01X775740Y117500D02*
X765740D01*
X762740Y121000D01*
Y158000D01*
X777440D01*
G01X763419Y197406D02*
X760919D01*
Y198447D01*
X761044Y198781D01*
X761211Y198989D01*
X761544Y199072D01*
X761877Y198989D01*
X762086Y198739D01*
X762211Y198447D01*
Y197406D01*
G01Y198447D02*
X763419Y199072D01*
G01Y201839D02*
X760919D01*
X762711Y200297D01*
Y202381D01*
G01X763419Y205272D02*
Y203606D01*
X760919D01*
Y205272D01*
G01X762127Y204606D02*
Y203606D01*
G01X761336Y206747D02*
X761086Y206997D01*
X760961Y207289D01*
X760919Y207622D01*
X761002Y208039D01*
X761211Y208331D01*
X761461Y208414D01*
X761711Y208372D01*
X761919Y208206D01*
X762336Y207372D01*
X762627Y206997D01*
X763044Y206747D01*
X763419Y206664D01*
Y208414D01*
G01X761336Y209847D02*
X761086Y210097D01*
X760961Y210389D01*
X760919Y210722D01*
X761002Y211139D01*
X761211Y211431D01*
X761461Y211514D01*
X761711Y211472D01*
X761919Y211306D01*
X762336Y210472D01*
X762627Y210097D01*
X763044Y209847D01*
X763419Y209764D01*
Y211514D01*
G01X730905Y208617D02*
X728405D01*
Y209658D01*
X728530Y209992D01*
X728697Y210200D01*
X729030Y210283D01*
X729363Y210200D01*
X729572Y209950D01*
X729697Y209658D01*
Y208617D01*
G01Y209658D02*
X730905Y210283D01*
G01Y213050D02*
X728405D01*
X730197Y211508D01*
Y213592D01*
G01X730905Y216483D02*
Y214817D01*
X728405D01*
Y216483D01*
G01X729613Y215817D02*
Y214817D01*
G01X728822Y217958D02*
X728572Y218208D01*
X728447Y218500D01*
X728405Y218833D01*
X728488Y219250D01*
X728697Y219542D01*
X728947Y219625D01*
X729197Y219583D01*
X729405Y219417D01*
X729822Y218583D01*
X730113Y218208D01*
X730530Y217958D01*
X730905Y217875D01*
Y219625D01*
G01Y221850D02*
X728405D01*
X728905Y221350D01*
G01X730905D02*
Y222350D01*
G01X757817Y195792D02*
X757567Y195917D01*
X757275Y196000D01*
X756942D01*
X756567Y195875D01*
X756275Y195667D01*
X756067Y195417D01*
X755900Y195000D01*
X755858Y194625D01*
X755942Y194250D01*
X756067Y194000D01*
X756317Y193750D01*
X756608Y193583D01*
X756900Y193500D01*
X757192D01*
X757483Y193583D01*
X757733Y193708D01*
X757942Y193875D01*
G01X760500Y193500D02*
Y196000D01*
X758958Y194208D01*
X761042D01*
G01X763933Y193500D02*
X762267D01*
Y196000D01*
X763933D01*
G01X763267Y194792D02*
X762267D01*
G01X766200Y193500D02*
Y196000D01*
X765700Y195500D01*
G01Y193500D02*
X766700D01*
G01X769300Y196000D02*
X768967Y195917D01*
X768717Y195708D01*
X768550Y195458D01*
X768425Y195125D01*
X768383Y194750D01*
X768425Y194375D01*
X768550Y194042D01*
X768717Y193792D01*
X768967Y193583D01*
X769300Y193500D01*
X769633Y193583D01*
X769883Y193792D01*
X770050Y194042D01*
X770175Y194375D01*
X770217Y194750D01*
X770175Y195125D01*
X770050Y195458D01*
X769883Y195708D01*
X769633Y195917D01*
X769300Y196000D01*
G01X765777Y198960D02*
X765652Y198710D01*
X765569Y198418D01*
Y198085D01*
X765694Y197710D01*
X765902Y197418D01*
X766152Y197210D01*
X766569Y197043D01*
X766944Y197001D01*
X767319Y197085D01*
X767569Y197210D01*
X767819Y197460D01*
X767986Y197751D01*
X768069Y198043D01*
Y198335D01*
X767986Y198626D01*
X767861Y198876D01*
X767694Y199085D01*
G01X765569Y201143D02*
X768069D01*
G01X765569Y200185D02*
Y202101D01*
G01X768069Y204243D02*
X765569D01*
X766069Y203743D01*
G01X768069D02*
Y204743D01*
G01X766137Y216016D02*
X766012Y215766D01*
X765929Y215474D01*
Y215141D01*
X766054Y214766D01*
X766262Y214474D01*
X766512Y214266D01*
X766929Y214099D01*
X767304Y214057D01*
X767679Y214141D01*
X767929Y214266D01*
X768179Y214516D01*
X768346Y214807D01*
X768429Y215099D01*
Y215391D01*
X768346Y215682D01*
X768221Y215932D01*
X768054Y216141D01*
G01X768429Y218699D02*
X765929D01*
X767721Y217157D01*
Y219241D01*
G01X768429Y222132D02*
Y220466D01*
X765929D01*
Y222132D01*
G01X767137Y221466D02*
Y220466D01*
G01X768429Y224399D02*
X765929D01*
X766429Y223899D01*
G01X768429D02*
Y224899D01*
G01Y227416D02*
X767887Y227499D01*
X767429Y227624D01*
X767012Y227791D01*
X766554Y227999D01*
X765929Y228332D01*
Y226666D01*
G01X727243Y181498D02*
X726993Y181623D01*
X726701Y181706D01*
X726368D01*
X725993Y181581D01*
X725701Y181373D01*
X725493Y181123D01*
X725326Y180706D01*
X725284Y180331D01*
X725368Y179956D01*
X725493Y179706D01*
X725743Y179456D01*
X726034Y179289D01*
X726326Y179206D01*
X726618D01*
X726909Y179289D01*
X727159Y179414D01*
X727368Y179581D01*
G01X729926Y179206D02*
Y181706D01*
X728384Y179914D01*
X730468D01*
G01X733359Y179206D02*
X731693D01*
Y181706D01*
X733359D01*
G01X732693Y180498D02*
X731693D01*
G01X735626Y179206D02*
Y181706D01*
X735126Y181206D01*
G01Y179206D02*
X736126D01*
G01X737809Y179581D02*
X738059Y179373D01*
X738351Y179248D01*
X738726Y179206D01*
X739101Y179289D01*
X739393Y179456D01*
X739601Y179748D01*
X739643Y180081D01*
X739559Y180414D01*
X739351Y180623D01*
X739059Y180789D01*
X738768Y180831D01*
X738476Y180789D01*
X738101Y180623D01*
X738226Y181706D01*
X739351D01*
G01X727243Y185548D02*
X726993Y185673D01*
X726701Y185756D01*
X726368D01*
X725993Y185631D01*
X725701Y185423D01*
X725493Y185173D01*
X725326Y184756D01*
X725284Y184381D01*
X725368Y184006D01*
X725493Y183756D01*
X725743Y183506D01*
X726034Y183339D01*
X726326Y183256D01*
X726618D01*
X726909Y183339D01*
X727159Y183464D01*
X727368Y183631D01*
G01X729926Y183256D02*
Y185756D01*
X728384Y183964D01*
X730468D01*
G01X733359Y183256D02*
X731693D01*
Y185756D01*
X733359D01*
G01X732693Y184548D02*
X731693D01*
G01X735626Y183256D02*
Y185756D01*
X735126Y185256D01*
G01Y183256D02*
X736126D01*
G01X738726D02*
X739018Y183298D01*
X739351Y183423D01*
X739559Y183631D01*
X739643Y183923D01*
X739559Y184214D01*
X739309Y184464D01*
X738934Y184589D01*
X738518D01*
X738268Y184673D01*
X738059Y184881D01*
X737976Y185173D01*
X738101Y185464D01*
X738393Y185673D01*
X738726Y185756D01*
X739059Y185673D01*
X739351Y185464D01*
X739476Y185173D01*
X739393Y184881D01*
X739184Y184673D01*
X738934Y184589D01*
X738518D01*
X738143Y184464D01*
X737893Y184214D01*
X737809Y183923D01*
X737893Y183631D01*
X738101Y183423D01*
X738434Y183298D01*
X738726Y183256D01*
G01X773967Y196892D02*
X773717Y197017D01*
X773425Y197100D01*
X773092D01*
X772717Y196975D01*
X772425Y196767D01*
X772217Y196517D01*
X772050Y196100D01*
X772008Y195725D01*
X772092Y195350D01*
X772217Y195100D01*
X772467Y194850D01*
X772758Y194683D01*
X773050Y194600D01*
X773342D01*
X773633Y194683D01*
X773883Y194808D01*
X774092Y194975D01*
G01X776650Y194600D02*
Y197100D01*
X775108Y195308D01*
X777192D01*
G01X780083Y194600D02*
X778417D01*
Y197100D01*
X780083D01*
G01X779417Y195892D02*
X778417D01*
G01X781433Y194975D02*
X781683Y194767D01*
X781975Y194642D01*
X782350Y194600D01*
X782725Y194683D01*
X783017Y194850D01*
X783225Y195142D01*
X783267Y195475D01*
X783183Y195808D01*
X782975Y196017D01*
X782683Y196183D01*
X782392Y196225D01*
X782100Y196183D01*
X781725Y196017D01*
X781850Y197100D01*
X782975D01*
G01X742413Y193644D02*
X742163Y193769D01*
X741871Y193852D01*
X741538D01*
X741163Y193727D01*
X740871Y193519D01*
X740663Y193269D01*
X740496Y192852D01*
X740454Y192477D01*
X740538Y192102D01*
X740663Y191852D01*
X740913Y191602D01*
X741204Y191435D01*
X741496Y191352D01*
X741788D01*
X742079Y191435D01*
X742329Y191560D01*
X742538Y191727D01*
G01X745096Y191352D02*
Y193852D01*
X743554Y192060D01*
X745638D01*
G01X748529Y191352D02*
X746863D01*
Y193852D01*
X748529D01*
G01X747863Y192644D02*
X746863D01*
G01X750796Y191352D02*
Y193852D01*
X750296Y193352D01*
G01Y191352D02*
X751296D01*
G01X753104Y192394D02*
X753396Y192685D01*
X753646Y192852D01*
X753979Y192935D01*
X754271Y192852D01*
X754479Y192685D01*
X754646Y192435D01*
X754688Y192144D01*
X754646Y191894D01*
X754479Y191644D01*
X754229Y191435D01*
X753938Y191352D01*
X753604Y191435D01*
X753313Y191685D01*
X753146Y192060D01*
X753104Y192477D01*
X753188Y193019D01*
X753313Y193310D01*
X753521Y193602D01*
X753813Y193810D01*
X754104Y193852D01*
X754396Y193769D01*
X754604Y193560D01*
G01X748850Y216749D02*
X749550D01*
Y229749D01*
X748850D01*
G01X743150D02*
X742450D01*
Y216749D01*
X743150D01*
G01X749550Y199115D02*
X759386D01*
Y222886D01*
X756386Y225886D01*
X749550D01*
G01X742450D02*
X735614D01*
X732614Y222886D01*
Y199115D01*
G01D02*
X742450D01*
G01X767014Y161761D02*
X766764Y161886D01*
X766472Y161969D01*
X766139D01*
X765764Y161844D01*
X765472Y161636D01*
X765264Y161386D01*
X765097Y160969D01*
X765055Y160594D01*
X765139Y160219D01*
X765264Y159969D01*
X765514Y159719D01*
X765805Y159552D01*
X766097Y159469D01*
X766389D01*
X766680Y159552D01*
X766930Y159677D01*
X767139Y159844D01*
G01X769697Y159469D02*
Y161969D01*
X768155Y160177D01*
X770239D01*
G01X771505Y159469D02*
Y161969D01*
X773089D01*
G01X772505Y160761D02*
X771505D01*
G01X774605Y160511D02*
X774897Y160802D01*
X775147Y160969D01*
X775480Y161052D01*
X775772Y160969D01*
X775980Y160802D01*
X776147Y160552D01*
X776189Y160261D01*
X776147Y160011D01*
X775980Y159761D01*
X775730Y159552D01*
X775439Y159469D01*
X775105Y159552D01*
X774814Y159802D01*
X774647Y160177D01*
X774605Y160594D01*
X774689Y161136D01*
X774814Y161427D01*
X775022Y161719D01*
X775314Y161927D01*
X775605Y161969D01*
X775897Y161886D01*
X776105Y161677D01*
G01X743983Y177525D02*
X744941Y180625D01*
X745899Y177525D01*
G01X745554Y178610D02*
X744328D01*
G01X747313Y180108D02*
X747543Y180418D01*
X747811Y180573D01*
X748118Y180625D01*
X748501Y180522D01*
X748769Y180263D01*
X748846Y179953D01*
X748808Y179643D01*
X748654Y179385D01*
X747888Y178868D01*
X747543Y178507D01*
X747313Y177990D01*
X747236Y177525D01*
X748846D01*
G01X751141Y180625D02*
X750834Y180522D01*
X750604Y180263D01*
X750451Y179953D01*
X750336Y179540D01*
X750298Y179075D01*
X750336Y178610D01*
X750451Y178197D01*
X750604Y177887D01*
X750834Y177628D01*
X751141Y177525D01*
X751448Y177628D01*
X751678Y177887D01*
X751831Y178197D01*
X751946Y178610D01*
X751984Y179075D01*
X751946Y179540D01*
X751831Y179953D01*
X751678Y180263D01*
X751448Y180522D01*
X751141Y180625D01*
G01X784924Y194923D02*
Y197423D01*
X785965D01*
X786299Y197298D01*
X786507Y197131D01*
X786590Y196798D01*
X786507Y196465D01*
X786257Y196256D01*
X785965Y196131D01*
X784924D01*
G01X785965D02*
X786590Y194923D01*
G01X788857Y197423D02*
Y194923D01*
G01X787899Y197423D02*
X789815D01*
G01X791165Y197006D02*
X791415Y197256D01*
X791707Y197381D01*
X792040Y197423D01*
X792457Y197340D01*
X792749Y197131D01*
X792832Y196881D01*
X792790Y196631D01*
X792624Y196423D01*
X791790Y196006D01*
X791415Y195715D01*
X791165Y195298D01*
X791082Y194923D01*
X792832D01*
G01X771333Y198366D02*
X769667D01*
Y200866D01*
X771333D01*
G01X770667Y199658D02*
X769667D01*
G01X772683Y200866D02*
Y199074D01*
X772850Y198699D01*
X773183Y198449D01*
X773600Y198366D01*
X774017Y198449D01*
X774350Y198699D01*
X774517Y199074D01*
Y200866D01*
G01X777200Y198366D02*
Y200866D01*
X775658Y199074D01*
X777742D01*
G01X780633Y198366D02*
X778967D01*
Y200866D01*
X780633D01*
G01X779967Y199658D02*
X778967D01*
G01X782900Y198366D02*
Y200866D01*
X782400Y200366D01*
G01Y198366D02*
X783400D01*
G01X796671Y212716D02*
X769371D01*
Y236266D01*
X796671D01*
Y212716D01*
G01X745286Y233760D02*
X745953Y233060D01*
X746753Y232593D01*
X747686Y232360D01*
X748753Y232593D01*
X749553Y233060D01*
X750353Y233760D01*
X750620Y234693D01*
Y239360D01*
G01X738000Y226900D02*
Y230699D01*
X738001Y230700D01*
X751590D01*
Y242901D01*
G01X754443Y284045D02*
X756932D01*
Y271423D01*
X752579D01*
Y255754D01*
X746194D01*
Y244841D01*
X749630D01*
G01X755260Y226896D02*
X752760D01*
Y227937D01*
X752885Y228271D01*
X753052Y228479D01*
X753385Y228562D01*
X753718Y228479D01*
X753927Y228229D01*
X754052Y227937D01*
Y226896D01*
G01Y227937D02*
X755260Y228562D01*
G01X752760Y230829D02*
X755260D01*
G01X752760Y229871D02*
Y231787D01*
G01X755260Y233929D02*
X752760D01*
X753260Y233429D01*
G01X755260D02*
Y234429D01*
G01X756917Y234676D02*
X756792Y234426D01*
X756709Y234134D01*
Y233801D01*
X756834Y233426D01*
X757042Y233134D01*
X757292Y232926D01*
X757709Y232759D01*
X758084Y232717D01*
X758459Y232801D01*
X758709Y232926D01*
X758959Y233176D01*
X759126Y233467D01*
X759209Y233759D01*
Y234051D01*
X759126Y234342D01*
X759001Y234592D01*
X758834Y234801D01*
G01X759209Y237359D02*
X756709D01*
X758501Y235817D01*
Y237901D01*
G01X759209Y240792D02*
Y239126D01*
X756709D01*
Y240792D01*
G01X757917Y240126D02*
Y239126D01*
G01X759209Y243059D02*
X756709D01*
X757209Y242559D01*
G01X759209D02*
Y243559D01*
G01X758917Y245451D02*
X759126Y245742D01*
X759209Y246076D01*
X759126Y246409D01*
X758876Y246701D01*
X758501Y246909D01*
X758126Y246992D01*
X757667D01*
X757292Y246909D01*
X756959Y246701D01*
X756792Y246451D01*
X756709Y246159D01*
X756792Y245826D01*
X756959Y245576D01*
X757209Y245409D01*
X757542Y245326D01*
X757834Y245409D01*
X758126Y245617D01*
X758292Y245867D01*
X758334Y246159D01*
X758251Y246492D01*
X758042Y246742D01*
X757667Y246992D01*
G01X737311Y264173D02*
Y263189D01*
X736327D01*
G01X796671Y244716D02*
X769371D01*
Y268266D01*
X796671D01*
Y244716D01*
G01Y276716D02*
X769371D01*
Y300266D01*
X796671D01*
Y276716D01*
G01X731457Y290087D02*
X740640D01*
Y284045D01*
X749480D01*
G01X753654Y288107D02*
X751154D01*
Y289148D01*
X751279Y289482D01*
X751446Y289690D01*
X751779Y289773D01*
X752112Y289690D01*
X752321Y289440D01*
X752446Y289148D01*
Y288107D01*
G01Y289148D02*
X753654Y289773D01*
G01Y292540D02*
X751154D01*
X752946Y290998D01*
Y293082D01*
G01X753654Y294223D02*
X751154D01*
Y295057D01*
X751279Y295390D01*
X751446Y295640D01*
X751696Y295848D01*
X751987Y296015D01*
X752404Y296057D01*
X752821Y296015D01*
X753112Y295848D01*
X753362Y295640D01*
X753529Y295390D01*
X753654Y295057D01*
Y294223D01*
G01X753154Y297323D02*
X753446Y297573D01*
X753612Y297907D01*
X753654Y298282D01*
X753612Y298615D01*
X753404Y298948D01*
X753154Y299157D01*
X752904Y299198D01*
X752612Y299115D01*
X752404Y298823D01*
X752321Y298532D01*
Y298157D01*
G01Y298532D02*
X752196Y298782D01*
X751987Y298990D01*
X751737Y299073D01*
X751487Y298990D01*
X751279Y298782D01*
X751154Y298407D01*
X751196Y298032D01*
X751362Y297657D01*
G01X753362Y300632D02*
X753571Y300923D01*
X753654Y301257D01*
X753571Y301590D01*
X753321Y301882D01*
X752946Y302090D01*
X752571Y302173D01*
X752112D01*
X751737Y302090D01*
X751404Y301882D01*
X751237Y301632D01*
X751154Y301340D01*
X751237Y301007D01*
X751404Y300757D01*
X751654Y300590D01*
X751987Y300507D01*
X752279Y300590D01*
X752571Y300798D01*
X752737Y301048D01*
X752779Y301340D01*
X752696Y301673D01*
X752487Y301923D01*
X752112Y302173D01*
G01X738163Y300295D02*
Y302795D01*
X739204D01*
X739538Y302670D01*
X739746Y302503D01*
X739829Y302170D01*
X739746Y301837D01*
X739496Y301628D01*
X739204Y301503D01*
X738163D01*
G01X739204D02*
X739829Y300295D01*
G01X741304D02*
Y302795D01*
X742888D01*
G01X742304Y301587D02*
X741304D01*
G01X744404Y301337D02*
X744696Y301628D01*
X744946Y301795D01*
X745279Y301878D01*
X745571Y301795D01*
X745779Y301628D01*
X745946Y301378D01*
X745988Y301087D01*
X745946Y300837D01*
X745779Y300587D01*
X745529Y300378D01*
X745238Y300295D01*
X744904Y300378D01*
X744613Y300628D01*
X744446Y301003D01*
X744404Y301420D01*
X744488Y301962D01*
X744613Y302253D01*
X744821Y302545D01*
X745113Y302753D01*
X745404Y302795D01*
X745696Y302712D01*
X745904Y302503D01*
G01X749986Y310473D02*
X747486D01*
Y311514D01*
X747611Y311848D01*
X747778Y312056D01*
X748111Y312139D01*
X748444Y312056D01*
X748653Y311806D01*
X748778Y311514D01*
Y310473D01*
G01Y311514D02*
X749986Y312139D01*
G01Y314906D02*
X747486D01*
X749278Y313364D01*
Y315448D01*
G01X749986Y316589D02*
X747486D01*
Y317423D01*
X747611Y317756D01*
X747778Y318006D01*
X748028Y318214D01*
X748319Y318381D01*
X748736Y318423D01*
X749153Y318381D01*
X749444Y318214D01*
X749694Y318006D01*
X749861Y317756D01*
X749986Y317423D01*
Y316589D01*
G01X749486Y319689D02*
X749778Y319939D01*
X749944Y320273D01*
X749986Y320648D01*
X749944Y320981D01*
X749736Y321314D01*
X749486Y321523D01*
X749236Y321564D01*
X748944Y321481D01*
X748736Y321189D01*
X748653Y320898D01*
Y320523D01*
G01Y320898D02*
X748528Y321148D01*
X748319Y321356D01*
X748069Y321439D01*
X747819Y321356D01*
X747611Y321148D01*
X747486Y320773D01*
X747528Y320398D01*
X747694Y320023D01*
G01X749986Y323706D02*
X747486D01*
X747986Y323206D01*
G01X749986D02*
Y324206D01*
G01X732442Y308287D02*
X729942D01*
Y309328D01*
X730067Y309662D01*
X730234Y309870D01*
X730567Y309953D01*
X730900Y309870D01*
X731109Y309620D01*
X731234Y309328D01*
Y308287D01*
G01Y309328D02*
X732442Y309953D01*
G01Y312720D02*
X729942D01*
X731734Y311178D01*
Y313262D01*
G01X732442Y314403D02*
X729942D01*
Y315237D01*
X730067Y315570D01*
X730234Y315820D01*
X730484Y316028D01*
X730775Y316195D01*
X731192Y316237D01*
X731609Y316195D01*
X731900Y316028D01*
X732150Y315820D01*
X732317Y315570D01*
X732442Y315237D01*
Y314403D01*
G01X731942Y317503D02*
X732234Y317753D01*
X732400Y318087D01*
X732442Y318462D01*
X732400Y318795D01*
X732192Y319128D01*
X731942Y319337D01*
X731692Y319378D01*
X731400Y319295D01*
X731192Y319003D01*
X731109Y318712D01*
Y318337D01*
G01Y318712D02*
X730984Y318962D01*
X730775Y319170D01*
X730525Y319253D01*
X730275Y319170D01*
X730067Y318962D01*
X729942Y318587D01*
X729984Y318212D01*
X730150Y317837D01*
G01X730359Y320728D02*
X730109Y320978D01*
X729984Y321270D01*
X729942Y321603D01*
X730025Y322020D01*
X730234Y322312D01*
X730484Y322395D01*
X730734Y322353D01*
X730942Y322187D01*
X731359Y321353D01*
X731650Y320978D01*
X732067Y320728D01*
X732442Y320645D01*
Y322395D01*
G01X743911Y312023D02*
X743786Y311773D01*
X743703Y311481D01*
Y311148D01*
X743828Y310773D01*
X744036Y310481D01*
X744286Y310273D01*
X744703Y310106D01*
X745078Y310064D01*
X745453Y310148D01*
X745703Y310273D01*
X745953Y310523D01*
X746120Y310814D01*
X746203Y311106D01*
Y311398D01*
X746120Y311689D01*
X745995Y311939D01*
X745828Y312148D01*
G01X746203Y314706D02*
X743703D01*
X745495Y313164D01*
Y315248D01*
G01X746203Y316389D02*
X743703D01*
Y317223D01*
X743828Y317556D01*
X743995Y317806D01*
X744245Y318014D01*
X744536Y318181D01*
X744953Y318223D01*
X745370Y318181D01*
X745661Y318014D01*
X745911Y317806D01*
X746078Y317556D01*
X746203Y317223D01*
Y316389D01*
G01Y320406D02*
X743703D01*
X744203Y319906D01*
G01X746203D02*
Y320906D01*
G01Y323506D02*
X746161Y323798D01*
X746036Y324131D01*
X745828Y324339D01*
X745536Y324423D01*
X745245Y324339D01*
X744995Y324089D01*
X744870Y323714D01*
Y323298D01*
X744786Y323048D01*
X744578Y322839D01*
X744286Y322756D01*
X743995Y322881D01*
X743786Y323173D01*
X743703Y323506D01*
X743786Y323839D01*
X743995Y324131D01*
X744286Y324256D01*
X744578Y324173D01*
X744786Y323964D01*
X744870Y323714D01*
Y323298D01*
X744995Y322923D01*
X745245Y322673D01*
X745536Y322589D01*
X745828Y322673D01*
X746036Y322881D01*
X746161Y323214D01*
X746203Y323506D01*
G01X747475Y294489D02*
X747350Y294239D01*
X747267Y293947D01*
Y293614D01*
X747392Y293239D01*
X747600Y292947D01*
X747850Y292739D01*
X748267Y292572D01*
X748642Y292530D01*
X749017Y292614D01*
X749267Y292739D01*
X749517Y292989D01*
X749684Y293280D01*
X749767Y293572D01*
Y293864D01*
X749684Y294155D01*
X749559Y294405D01*
X749392Y294614D01*
G01X749767Y297172D02*
X747267D01*
X749059Y295630D01*
Y297714D01*
G01X749767Y298855D02*
X747267D01*
Y299689D01*
X747392Y300022D01*
X747559Y300272D01*
X747809Y300480D01*
X748100Y300647D01*
X748517Y300689D01*
X748934Y300647D01*
X749225Y300480D01*
X749475Y300272D01*
X749642Y300022D01*
X749767Y299689D01*
Y298855D01*
G01X747684Y302080D02*
X747434Y302330D01*
X747309Y302622D01*
X747267Y302955D01*
X747350Y303372D01*
X747559Y303664D01*
X747809Y303747D01*
X748059Y303705D01*
X748267Y303539D01*
X748684Y302705D01*
X748975Y302330D01*
X749392Y302080D01*
X749767Y301997D01*
Y303747D01*
G01X749475Y305264D02*
X749684Y305555D01*
X749767Y305889D01*
X749684Y306222D01*
X749434Y306514D01*
X749059Y306722D01*
X748684Y306805D01*
X748225D01*
X747850Y306722D01*
X747517Y306514D01*
X747350Y306264D01*
X747267Y305972D01*
X747350Y305639D01*
X747517Y305389D01*
X747767Y305222D01*
X748100Y305139D01*
X748392Y305222D01*
X748684Y305430D01*
X748850Y305680D01*
X748892Y305972D01*
X748809Y306305D01*
X748600Y306555D01*
X748225Y306805D01*
G01X739427Y311934D02*
X739302Y311684D01*
X739219Y311392D01*
Y311059D01*
X739344Y310684D01*
X739552Y310392D01*
X739802Y310184D01*
X740219Y310017D01*
X740594Y309975D01*
X740969Y310059D01*
X741219Y310184D01*
X741469Y310434D01*
X741636Y310725D01*
X741719Y311017D01*
Y311309D01*
X741636Y311600D01*
X741511Y311850D01*
X741344Y312059D01*
G01X741719Y314617D02*
X739219D01*
X741011Y313075D01*
Y315159D01*
G01X741719Y316300D02*
X739219D01*
Y317134D01*
X739344Y317467D01*
X739511Y317717D01*
X739761Y317925D01*
X740052Y318092D01*
X740469Y318134D01*
X740886Y318092D01*
X741177Y317925D01*
X741427Y317717D01*
X741594Y317467D01*
X741719Y317134D01*
Y316300D01*
G01Y320317D02*
X739219D01*
X739719Y319817D01*
G01X741719D02*
Y320817D01*
G01Y323334D02*
X741177Y323417D01*
X740719Y323542D01*
X740302Y323709D01*
X739844Y323917D01*
X739219Y324250D01*
Y322584D01*
G01X726266Y310656D02*
X726141Y310406D01*
X726058Y310114D01*
Y309781D01*
X726183Y309406D01*
X726391Y309114D01*
X726641Y308906D01*
X727058Y308739D01*
X727433Y308697D01*
X727808Y308781D01*
X728058Y308906D01*
X728308Y309156D01*
X728475Y309447D01*
X728558Y309739D01*
Y310031D01*
X728475Y310322D01*
X728350Y310572D01*
X728183Y310781D01*
G01X728558Y313339D02*
X726058D01*
X727850Y311797D01*
Y313881D01*
G01X728558Y315022D02*
X726058D01*
Y315856D01*
X726183Y316189D01*
X726350Y316439D01*
X726600Y316647D01*
X726891Y316814D01*
X727308Y316856D01*
X727725Y316814D01*
X728016Y316647D01*
X728266Y316439D01*
X728433Y316189D01*
X728558Y315856D01*
Y315022D01*
G01Y319039D02*
X726058D01*
X726558Y318539D01*
G01X728558D02*
Y319539D01*
G01X728183Y321222D02*
X728391Y321472D01*
X728516Y321764D01*
X728558Y322139D01*
X728475Y322514D01*
X728308Y322806D01*
X728016Y323014D01*
X727683Y323056D01*
X727350Y322972D01*
X727141Y322764D01*
X726975Y322472D01*
X726933Y322181D01*
X726975Y321889D01*
X727141Y321514D01*
X726058Y321639D01*
Y322764D01*
G01X733817Y308393D02*
X733692Y308143D01*
X733609Y307851D01*
Y307518D01*
X733734Y307143D01*
X733942Y306851D01*
X734192Y306643D01*
X734609Y306476D01*
X734984Y306434D01*
X735359Y306518D01*
X735609Y306643D01*
X735859Y306893D01*
X736026Y307184D01*
X736109Y307476D01*
Y307768D01*
X736026Y308059D01*
X735901Y308309D01*
X735734Y308518D01*
G01X736109Y311076D02*
X733609D01*
X735401Y309534D01*
Y311618D01*
G01X736109Y312759D02*
X733609D01*
Y313593D01*
X733734Y313926D01*
X733901Y314176D01*
X734151Y314384D01*
X734442Y314551D01*
X734859Y314593D01*
X735276Y314551D01*
X735567Y314384D01*
X735817Y314176D01*
X735984Y313926D01*
X736109Y313593D01*
Y312759D01*
G01X734026Y315984D02*
X733776Y316234D01*
X733651Y316526D01*
X733609Y316859D01*
X733692Y317276D01*
X733901Y317568D01*
X734151Y317651D01*
X734401Y317609D01*
X734609Y317443D01*
X735026Y316609D01*
X735317Y316234D01*
X735734Y315984D01*
X736109Y315901D01*
Y317651D01*
G01X733609Y319876D02*
X733692Y319543D01*
X733901Y319293D01*
X734151Y319126D01*
X734484Y319001D01*
X734859Y318959D01*
X735234Y319001D01*
X735567Y319126D01*
X735817Y319293D01*
X736026Y319543D01*
X736109Y319876D01*
X736026Y320209D01*
X735817Y320459D01*
X735567Y320626D01*
X735234Y320751D01*
X734859Y320793D01*
X734484Y320751D01*
X734151Y320626D01*
X733901Y320459D01*
X733692Y320209D01*
X733609Y319876D01*
G01X744749Y338650D02*
Y337950D01*
X757749D01*
Y338650D01*
G01X727114Y337950D02*
Y328114D01*
X750886D01*
X753886Y331114D01*
Y337950D01*
G01X740054Y307334D02*
X739804Y307459D01*
X739512Y307542D01*
X739179D01*
X738804Y307417D01*
X738512Y307209D01*
X738304Y306959D01*
X738137Y306542D01*
X738095Y306167D01*
X738179Y305792D01*
X738304Y305542D01*
X738554Y305292D01*
X738845Y305125D01*
X739137Y305042D01*
X739429D01*
X739720Y305125D01*
X739970Y305250D01*
X740179Y305417D01*
G01X741445Y305042D02*
Y307542D01*
X743029D01*
G01X742445Y306334D02*
X741445D01*
G01X744545Y306084D02*
X744837Y306375D01*
X745087Y306542D01*
X745420Y306625D01*
X745712Y306542D01*
X745920Y306375D01*
X746087Y306125D01*
X746129Y305834D01*
X746087Y305584D01*
X745920Y305334D01*
X745670Y305125D01*
X745379Y305042D01*
X745045Y305125D01*
X744754Y305375D01*
X744587Y305750D01*
X744545Y306167D01*
X744629Y306709D01*
X744754Y307000D01*
X744962Y307292D01*
X745254Y307500D01*
X745545Y307542D01*
X745837Y307459D01*
X746045Y307250D01*
G01X736327Y286811D02*
X737311D01*
Y285827D01*
G01X796671Y308716D02*
X769371D01*
Y332266D01*
X796671D01*
Y308716D01*
G01Y340716D02*
X769371D01*
Y364266D01*
X796671D01*
Y340716D01*
G01X746992Y391213D02*
Y393713D01*
X748033D01*
X748367Y393588D01*
X748575Y393421D01*
X748658Y393088D01*
X748575Y392755D01*
X748325Y392546D01*
X748033Y392421D01*
X746992D01*
G01X748033D02*
X748658Y391213D01*
G01X751425D02*
Y393713D01*
X749883Y391921D01*
X751967D01*
G01X754942Y393505D02*
X754692Y393630D01*
X754400Y393713D01*
X754067D01*
X753692Y393588D01*
X753400Y393380D01*
X753192Y393130D01*
X753025Y392713D01*
X752983Y392338D01*
X753067Y391963D01*
X753192Y391713D01*
X753442Y391463D01*
X753733Y391296D01*
X754025Y391213D01*
X754317D01*
X754608Y391296D01*
X754858Y391421D01*
X755067Y391588D01*
G01X757125Y391213D02*
Y393713D01*
X756625Y393213D01*
G01Y391213D02*
X757625D01*
G01X759308Y391713D02*
X759558Y391421D01*
X759892Y391255D01*
X760267Y391213D01*
X760600Y391255D01*
X760933Y391463D01*
X761142Y391713D01*
X761183Y391963D01*
X761100Y392255D01*
X760808Y392463D01*
X760517Y392546D01*
X760142D01*
G01X760517D02*
X760767Y392671D01*
X760975Y392880D01*
X761058Y393130D01*
X760975Y393380D01*
X760767Y393588D01*
X760392Y393713D01*
X760017Y393671D01*
X759642Y393505D01*
G01X746992Y394713D02*
Y397213D01*
X748033D01*
X748367Y397088D01*
X748575Y396921D01*
X748658Y396588D01*
X748575Y396255D01*
X748325Y396046D01*
X748033Y395921D01*
X746992D01*
G01X748033D02*
X748658Y394713D01*
G01X750925Y397213D02*
Y394713D01*
G01X749967Y397213D02*
X751883D01*
G01X754525Y394713D02*
Y397213D01*
X752983Y395421D01*
X755067D01*
G01X757125Y397213D02*
X756792Y397130D01*
X756542Y396921D01*
X756375Y396671D01*
X756250Y396338D01*
X756208Y395963D01*
X756250Y395588D01*
X756375Y395255D01*
X756542Y395005D01*
X756792Y394796D01*
X757125Y394713D01*
X757458Y394796D01*
X757708Y395005D01*
X757875Y395255D01*
X758000Y395588D01*
X758042Y395963D01*
X758000Y396338D01*
X757875Y396671D01*
X757708Y396921D01*
X757458Y397130D01*
X757125Y397213D01*
G01X748742Y400505D02*
X748492Y400630D01*
X748200Y400713D01*
X747867D01*
X747492Y400588D01*
X747200Y400380D01*
X746992Y400130D01*
X746825Y399713D01*
X746783Y399338D01*
X746867Y398963D01*
X746992Y398713D01*
X747242Y398463D01*
X747533Y398296D01*
X747825Y398213D01*
X748117D01*
X748408Y398296D01*
X748658Y398421D01*
X748867Y398588D01*
G01X751425Y398213D02*
Y400713D01*
X749883Y398921D01*
X751967D01*
G01X754942Y400505D02*
X754692Y400630D01*
X754400Y400713D01*
X754067D01*
X753692Y400588D01*
X753400Y400380D01*
X753192Y400130D01*
X753025Y399713D01*
X752983Y399338D01*
X753067Y398963D01*
X753192Y398713D01*
X753442Y398463D01*
X753733Y398296D01*
X754025Y398213D01*
X754317D01*
X754608Y398296D01*
X754858Y398421D01*
X755067Y398588D01*
G01X757125Y398213D02*
X757417Y398255D01*
X757750Y398380D01*
X757958Y398588D01*
X758042Y398880D01*
X757958Y399171D01*
X757708Y399421D01*
X757333Y399546D01*
X756917D01*
X756667Y399630D01*
X756458Y399838D01*
X756375Y400130D01*
X756500Y400421D01*
X756792Y400630D01*
X757125Y400713D01*
X757458Y400630D01*
X757750Y400421D01*
X757875Y400130D01*
X757792Y399838D01*
X757583Y399630D01*
X757333Y399546D01*
X756917D01*
X756542Y399421D01*
X756292Y399171D01*
X756208Y398880D01*
X756292Y398588D01*
X756500Y398380D01*
X756833Y398255D01*
X757125Y398213D01*
G01X757749Y344350D02*
Y345050D01*
X744749D01*
Y344350D01*
G01X753886Y345050D02*
Y351886D01*
X750886Y354886D01*
X727114D01*
G01D02*
Y345050D01*
G01X759109Y366232D02*
X758984Y365982D01*
X758901Y365690D01*
Y365357D01*
X759026Y364982D01*
X759234Y364690D01*
X759484Y364482D01*
X759901Y364315D01*
X760276Y364273D01*
X760651Y364357D01*
X760901Y364482D01*
X761151Y364732D01*
X761318Y365023D01*
X761401Y365315D01*
Y365607D01*
X761318Y365898D01*
X761193Y366148D01*
X761026Y366357D01*
G01X761401Y368915D02*
X758901D01*
X760693Y367373D01*
Y369457D01*
G01X759109Y372432D02*
X758984Y372182D01*
X758901Y371890D01*
Y371557D01*
X759026Y371182D01*
X759234Y370890D01*
X759484Y370682D01*
X759901Y370515D01*
X760276Y370473D01*
X760651Y370557D01*
X760901Y370682D01*
X761151Y370932D01*
X761318Y371223D01*
X761401Y371515D01*
Y371807D01*
X761318Y372098D01*
X761193Y372348D01*
X761026Y372557D01*
G01X761401Y374615D02*
X758901D01*
X759401Y374115D01*
G01X761401D02*
Y375115D01*
G01X759318Y376923D02*
X759068Y377173D01*
X758943Y377465D01*
X758901Y377798D01*
X758984Y378215D01*
X759193Y378507D01*
X759443Y378590D01*
X759693Y378548D01*
X759901Y378382D01*
X760318Y377548D01*
X760609Y377173D01*
X761026Y376923D01*
X761401Y376840D01*
Y378590D01*
G01X744749Y367650D02*
Y366950D01*
X757749D01*
Y367650D01*
G01Y373350D02*
Y374050D01*
X744749D01*
Y373350D01*
G01X727114Y366950D02*
Y357114D01*
X750886D01*
X753886Y360114D01*
Y366950D01*
G01Y374050D02*
Y380886D01*
X750886Y383886D01*
X727114D01*
G01D02*
Y374050D01*
G01X768778Y400236D02*
Y398570D01*
X766278D01*
Y400236D01*
G01X767486Y399570D02*
Y398570D01*
G01X766278Y401586D02*
X768070D01*
X768445Y401753D01*
X768695Y402086D01*
X768778Y402503D01*
X768695Y402920D01*
X768445Y403253D01*
X768070Y403420D01*
X766278D01*
G01X768778Y406103D02*
X766278D01*
X768070Y404561D01*
Y406645D01*
G01X766486Y409620D02*
X766361Y409370D01*
X766278Y409078D01*
Y408745D01*
X766403Y408370D01*
X766611Y408078D01*
X766861Y407870D01*
X767278Y407703D01*
X767653Y407661D01*
X768028Y407745D01*
X768278Y407870D01*
X768528Y408120D01*
X768695Y408411D01*
X768778Y408703D01*
Y408995D01*
X768695Y409286D01*
X768570Y409536D01*
X768403Y409745D01*
G01X768778Y411803D02*
X766278D01*
X766778Y411303D01*
G01X768778D02*
Y412303D01*
G01X796621Y372716D02*
X769321D01*
Y396266D01*
X796621D01*
Y372716D01*
G01X777664Y409562D02*
X777414Y409687D01*
X777122Y409770D01*
X776789D01*
X776414Y409645D01*
X776122Y409437D01*
X775914Y409187D01*
X775747Y408770D01*
X775705Y408395D01*
X775789Y408020D01*
X775914Y407770D01*
X776164Y407520D01*
X776455Y407353D01*
X776747Y407270D01*
X777039D01*
X777330Y407353D01*
X777580Y407478D01*
X777789Y407645D01*
G01X780347Y407270D02*
Y409770D01*
X778805Y407978D01*
X780889D01*
G01X783864Y409562D02*
X783614Y409687D01*
X783322Y409770D01*
X782989D01*
X782614Y409645D01*
X782322Y409437D01*
X782114Y409187D01*
X781947Y408770D01*
X781905Y408395D01*
X781989Y408020D01*
X782114Y407770D01*
X782364Y407520D01*
X782655Y407353D01*
X782947Y407270D01*
X783239D01*
X783530Y407353D01*
X783780Y407478D01*
X783989Y407645D01*
G01X786047Y407270D02*
Y409770D01*
X785547Y409270D01*
G01Y407270D02*
X786547D01*
G01X789147Y409770D02*
X788814Y409687D01*
X788564Y409478D01*
X788397Y409228D01*
X788272Y408895D01*
X788230Y408520D01*
X788272Y408145D01*
X788397Y407812D01*
X788564Y407562D01*
X788814Y407353D01*
X789147Y407270D01*
X789480Y407353D01*
X789730Y407562D01*
X789897Y407812D01*
X790022Y408145D01*
X790064Y408520D01*
X790022Y408895D01*
X789897Y409228D01*
X789730Y409478D01*
X789480Y409687D01*
X789147Y409770D01*
G01X779248Y406287D02*
X778998Y406412D01*
X778706Y406495D01*
X778373D01*
X777998Y406370D01*
X777706Y406162D01*
X777498Y405912D01*
X777331Y405495D01*
X777289Y405120D01*
X777373Y404745D01*
X777498Y404495D01*
X777748Y404245D01*
X778039Y404078D01*
X778331Y403995D01*
X778623D01*
X778914Y404078D01*
X779164Y404203D01*
X779373Y404370D01*
G01X781931Y403995D02*
Y406495D01*
X780389Y404703D01*
X782473D01*
G01X785448Y406287D02*
X785198Y406412D01*
X784906Y406495D01*
X784573D01*
X784198Y406370D01*
X783906Y406162D01*
X783698Y405912D01*
X783531Y405495D01*
X783489Y405120D01*
X783573Y404745D01*
X783698Y404495D01*
X783948Y404245D01*
X784239Y404078D01*
X784531Y403995D01*
X784823D01*
X785114Y404078D01*
X785364Y404203D01*
X785573Y404370D01*
G01X786923Y404287D02*
X787214Y404078D01*
X787548Y403995D01*
X787881Y404078D01*
X788173Y404328D01*
X788381Y404703D01*
X788464Y405078D01*
Y405537D01*
X788381Y405912D01*
X788173Y406245D01*
X787923Y406412D01*
X787631Y406495D01*
X787298Y406412D01*
X787048Y406245D01*
X786881Y405995D01*
X786798Y405662D01*
X786881Y405370D01*
X787089Y405078D01*
X787339Y404912D01*
X787631Y404870D01*
X787964Y404953D01*
X788214Y405162D01*
X788464Y405537D01*
G01X758826Y463871D02*
X758701Y463621D01*
X758618Y463329D01*
Y462996D01*
X758743Y462621D01*
X758951Y462329D01*
X759201Y462121D01*
X759618Y461954D01*
X759993Y461912D01*
X760368Y461996D01*
X760618Y462121D01*
X760868Y462371D01*
X761035Y462662D01*
X761118Y462954D01*
Y463246D01*
X761035Y463537D01*
X760910Y463787D01*
X760743Y463996D01*
G01X761118Y466554D02*
X758618D01*
X760410Y465012D01*
Y467096D01*
G01X759785Y469487D02*
X759660Y469654D01*
X759451Y469779D01*
X759160Y469862D01*
X758910Y469779D01*
X758743Y469612D01*
X758618Y469321D01*
Y468196D01*
X761118D01*
Y469571D01*
X760951Y469862D01*
X760701Y470029D01*
X760410Y470112D01*
X760118Y470029D01*
X759868Y469779D01*
X759785Y469487D01*
Y468196D01*
G01X761118Y472254D02*
X758618D01*
X759118Y471754D01*
G01X761118D02*
Y472754D01*
G01X760618Y474437D02*
X760910Y474687D01*
X761076Y475021D01*
X761118Y475396D01*
X761076Y475729D01*
X760868Y476062D01*
X760618Y476271D01*
X760368Y476312D01*
X760076Y476229D01*
X759868Y475937D01*
X759785Y475646D01*
Y475271D01*
G01Y475646D02*
X759660Y475896D01*
X759451Y476104D01*
X759201Y476187D01*
X758951Y476104D01*
X758743Y475896D01*
X758618Y475521D01*
X758660Y475146D01*
X758826Y474771D01*
G01X777434Y445000D02*
X762734D01*
Y482000D01*
G01X751827Y518598D02*
X751577Y518723D01*
X751285Y518806D01*
X750952D01*
X750577Y518681D01*
X750285Y518473D01*
X750077Y518223D01*
X749910Y517806D01*
X749868Y517431D01*
X749952Y517056D01*
X750077Y516806D01*
X750327Y516556D01*
X750618Y516389D01*
X750910Y516306D01*
X751202D01*
X751493Y516389D01*
X751743Y516514D01*
X751952Y516681D01*
G01X754510Y516306D02*
Y518806D01*
X752968Y517014D01*
X755052D01*
G01X757443Y517639D02*
X757610Y517764D01*
X757735Y517973D01*
X757818Y518264D01*
X757735Y518514D01*
X757568Y518681D01*
X757277Y518806D01*
X756152D01*
Y516306D01*
X757527D01*
X757818Y516473D01*
X757985Y516723D01*
X758068Y517014D01*
X757985Y517306D01*
X757735Y517556D01*
X757443Y517639D01*
X756152D01*
G01X760210Y516306D02*
Y518806D01*
X759710Y518306D01*
G01Y516306D02*
X760710D01*
G01X763310D02*
Y518806D01*
X762810Y518306D01*
G01Y516306D02*
X763810D01*
G01X767152Y508398D02*
X766902Y508523D01*
X766610Y508606D01*
X766277D01*
X765902Y508481D01*
X765610Y508273D01*
X765402Y508023D01*
X765235Y507606D01*
X765193Y507231D01*
X765277Y506856D01*
X765402Y506606D01*
X765652Y506356D01*
X765943Y506189D01*
X766235Y506106D01*
X766527D01*
X766818Y506189D01*
X767068Y506314D01*
X767277Y506481D01*
G01X769835Y506106D02*
Y508606D01*
X768293Y506814D01*
X770377D01*
G01X772768Y507439D02*
X772935Y507564D01*
X773060Y507773D01*
X773143Y508064D01*
X773060Y508314D01*
X772893Y508481D01*
X772602Y508606D01*
X771477D01*
Y506106D01*
X772852D01*
X773143Y506273D01*
X773310Y506523D01*
X773393Y506814D01*
X773310Y507106D01*
X773060Y507356D01*
X772768Y507439D01*
X771477D01*
G01X775535Y506106D02*
Y508606D01*
X775035Y508106D01*
G01Y506106D02*
X776035D01*
G01X777843Y508189D02*
X778093Y508439D01*
X778385Y508564D01*
X778718Y508606D01*
X779135Y508523D01*
X779427Y508314D01*
X779510Y508064D01*
X779468Y507814D01*
X779302Y507606D01*
X778468Y507189D01*
X778093Y506898D01*
X777843Y506481D01*
X777760Y506106D01*
X779510D01*
G01X753882Y491277D02*
X751382D01*
Y492318D01*
X751507Y492652D01*
X751674Y492860D01*
X752007Y492943D01*
X752340Y492860D01*
X752549Y492610D01*
X752674Y492318D01*
Y491277D01*
G01Y492318D02*
X753882Y492943D01*
G01Y495710D02*
X751382D01*
X753174Y494168D01*
Y496252D01*
G01X752549Y498643D02*
X752424Y498810D01*
X752215Y498935D01*
X751924Y499018D01*
X751674Y498935D01*
X751507Y498768D01*
X751382Y498477D01*
Y497352D01*
X753882D01*
Y498727D01*
X753715Y499018D01*
X753465Y499185D01*
X753174Y499268D01*
X752882Y499185D01*
X752632Y498935D01*
X752549Y498643D01*
Y497352D01*
G01X753882Y501410D02*
X751382D01*
X751882Y500910D01*
G01X753882D02*
Y501910D01*
G01X751799Y503718D02*
X751549Y503968D01*
X751424Y504260D01*
X751382Y504593D01*
X751465Y505010D01*
X751674Y505302D01*
X751924Y505385D01*
X752174Y505343D01*
X752382Y505177D01*
X752799Y504343D01*
X753090Y503968D01*
X753507Y503718D01*
X753882Y503635D01*
Y505385D01*
G01X755053Y502864D02*
Y498539D01*
G01X762153Y502861D02*
Y498419D01*
G01X762734Y482000D02*
X765734Y485500D01*
X775734D01*
G01X777434Y489750D02*
X775734D01*
Y473250D01*
X777434D01*
G01X734872Y513183D02*
X735122Y513391D01*
X735289Y513641D01*
X735372Y513933D01*
X735289Y514266D01*
X735122Y514516D01*
X734872Y514766D01*
X734539Y514849D01*
X732872D01*
G01X735372Y517616D02*
X732872D01*
X734664Y516074D01*
Y518158D01*
G01X734039Y520549D02*
X733914Y520716D01*
X733705Y520841D01*
X733414Y520924D01*
X733164Y520841D01*
X732997Y520674D01*
X732872Y520383D01*
Y519258D01*
X735372D01*
Y520633D01*
X735205Y520924D01*
X734955Y521091D01*
X734664Y521174D01*
X734372Y521091D01*
X734122Y520841D01*
X734039Y520549D01*
Y519258D01*
G01X735372Y523316D02*
X732872D01*
X733372Y522816D01*
G01X735372D02*
Y523816D01*
G01X760710Y520160D02*
X736320D01*
Y545750D01*
X760710D01*
G01X731672Y487963D02*
X731339Y488005D01*
X731047Y488171D01*
X730797Y488421D01*
X730630Y488713D01*
X730547Y489046D01*
Y489380D01*
X730630Y489713D01*
X730797Y490005D01*
X731047Y490255D01*
X731339Y490421D01*
X731672Y490463D01*
X732005Y490421D01*
X732297Y490255D01*
X732547Y490005D01*
X732714Y489713D01*
X732797Y489380D01*
Y489046D01*
X732714Y488713D01*
X732547Y488421D01*
X732297Y488171D01*
X732005Y488005D01*
X731672Y487963D01*
G01X732005Y488630D02*
X732505Y487963D01*
G01X734772D02*
Y490463D01*
X734272Y489963D01*
G01Y487963D02*
X735272D01*
G01X737080Y490046D02*
X737330Y490296D01*
X737622Y490421D01*
X737955Y490463D01*
X738372Y490380D01*
X738664Y490171D01*
X738747Y489921D01*
X738705Y489671D01*
X738539Y489463D01*
X737705Y489046D01*
X737330Y488755D01*
X737080Y488338D01*
X736997Y487963D01*
X738747D01*
G01X739722Y490463D02*
X740305Y487963D01*
X740972Y490463D01*
X741639Y487963D01*
X742222Y490463D01*
G01X743280Y490046D02*
X743530Y490296D01*
X743822Y490421D01*
X744155Y490463D01*
X744572Y490380D01*
X744864Y490171D01*
X744947Y489921D01*
X744905Y489671D01*
X744739Y489463D01*
X743905Y489046D01*
X743530Y488755D01*
X743280Y488338D01*
X743197Y487963D01*
X744947D01*
G01X731516Y492495D02*
Y504237D01*
X732158D01*
Y492495D01*
X731516D01*
X731837Y493895D01*
X732158Y492495D01*
G01X777172Y554565D02*
X776922Y554690D01*
X776630Y554773D01*
X776297D01*
X775922Y554648D01*
X775630Y554440D01*
X775422Y554190D01*
X775255Y553773D01*
X775213Y553398D01*
X775297Y553023D01*
X775422Y552773D01*
X775672Y552523D01*
X775963Y552356D01*
X776255Y552273D01*
X776547D01*
X776838Y552356D01*
X777088Y552481D01*
X777297Y552648D01*
G01X779855Y552273D02*
Y554773D01*
X778313Y552981D01*
X780397D01*
G01X781413Y552273D02*
X782455Y554773D01*
X783497Y552273D01*
G01X783122Y553148D02*
X781788D01*
G01X785555Y552273D02*
Y554773D01*
X785055Y554273D01*
G01Y552273D02*
X786055D01*
G01X788572D02*
X788655Y552815D01*
X788780Y553273D01*
X788947Y553690D01*
X789155Y554148D01*
X789488Y554773D01*
X787822D01*
G01X779554Y591216D02*
X779304Y591341D01*
X779012Y591424D01*
X778679D01*
X778304Y591299D01*
X778012Y591091D01*
X777804Y590841D01*
X777637Y590424D01*
X777595Y590049D01*
X777679Y589674D01*
X777804Y589424D01*
X778054Y589174D01*
X778345Y589007D01*
X778637Y588924D01*
X778929D01*
X779220Y589007D01*
X779470Y589132D01*
X779679Y589299D01*
G01X782237Y588924D02*
Y591424D01*
X780695Y589632D01*
X782779D01*
G01X783795Y588924D02*
X784837Y591424D01*
X785879Y588924D01*
G01X785504Y589799D02*
X784170D01*
G01X788437Y588924D02*
Y591424D01*
X786895Y589632D01*
X788979D01*
G01X731663Y561031D02*
X729163D01*
Y562072D01*
X729288Y562406D01*
X729455Y562614D01*
X729788Y562697D01*
X730121Y562614D01*
X730330Y562364D01*
X730455Y562072D01*
Y561031D01*
G01Y562072D02*
X731663Y562697D01*
G01Y565464D02*
X729163D01*
X730955Y563922D01*
Y566006D01*
G01X731663Y567022D02*
X729163Y568064D01*
X731663Y569106D01*
G01X730788Y568731D02*
Y567397D01*
G01X730621Y570372D02*
X730330Y570664D01*
X730163Y570914D01*
X730080Y571247D01*
X730163Y571539D01*
X730330Y571747D01*
X730580Y571914D01*
X730871Y571956D01*
X731121Y571914D01*
X731371Y571747D01*
X731580Y571497D01*
X731663Y571206D01*
X731580Y570872D01*
X731330Y570581D01*
X730955Y570414D01*
X730538Y570372D01*
X729996Y570456D01*
X729705Y570581D01*
X729413Y570789D01*
X729205Y571081D01*
X729163Y571372D01*
X729246Y571664D01*
X729455Y571872D01*
G01X725665Y558089D02*
X725540Y557839D01*
X725457Y557547D01*
Y557214D01*
X725582Y556839D01*
X725790Y556547D01*
X726040Y556339D01*
X726457Y556172D01*
X726832Y556130D01*
X727207Y556214D01*
X727457Y556339D01*
X727707Y556589D01*
X727874Y556880D01*
X727957Y557172D01*
Y557464D01*
X727874Y557755D01*
X727749Y558005D01*
X727582Y558214D01*
G01X727957Y560772D02*
X725457D01*
X727249Y559230D01*
Y561314D01*
G01X727957Y562330D02*
X725457Y563372D01*
X727957Y564414D01*
G01X727082Y564039D02*
Y562705D01*
G01X727957Y566472D02*
X725457D01*
X725957Y565972D01*
G01X727957D02*
Y566972D01*
G01X725874Y568780D02*
X725624Y569030D01*
X725499Y569322D01*
X725457Y569655D01*
X725540Y570072D01*
X725749Y570364D01*
X725999Y570447D01*
X726249Y570405D01*
X726457Y570239D01*
X726874Y569405D01*
X727165Y569030D01*
X727582Y568780D01*
X727957Y568697D01*
Y570447D01*
G01X735577Y542879D02*
X733077D01*
Y544463D01*
G01X734285Y543879D02*
Y542879D01*
G01X734244Y547104D02*
X734119Y547271D01*
X733910Y547396D01*
X733619Y547479D01*
X733369Y547396D01*
X733202Y547229D01*
X733077Y546938D01*
Y545813D01*
X735577D01*
Y547188D01*
X735410Y547479D01*
X735160Y547646D01*
X734869Y547729D01*
X734577Y547646D01*
X734327Y547396D01*
X734244Y547104D01*
Y545813D01*
G01X735577Y550371D02*
X733077D01*
X734869Y548829D01*
Y550913D01*
G01X735577Y551929D02*
X733077Y552971D01*
X735577Y554013D01*
G01X734702Y553638D02*
Y552304D01*
G01X735577Y556071D02*
X733077D01*
X733577Y555571D01*
G01X735577D02*
Y556571D01*
G01X764712Y584177D02*
Y587277D01*
X764252Y586657D01*
G01Y584177D02*
X765172D01*
G01X768272D02*
Y587277D01*
X766854Y585055D01*
X768770D01*
G01X770069Y584642D02*
X770299Y584384D01*
X770567Y584229D01*
X770912Y584177D01*
X771257Y584280D01*
X771525Y584487D01*
X771717Y584849D01*
X771755Y585262D01*
X771679Y585675D01*
X771487Y585934D01*
X771219Y586140D01*
X770950Y586192D01*
X770682Y586140D01*
X770337Y585934D01*
X770452Y587277D01*
X771487D01*
G01X734930Y568198D02*
X735180Y568406D01*
X735347Y568656D01*
X735430Y568948D01*
X735347Y569281D01*
X735180Y569531D01*
X734930Y569781D01*
X734597Y569864D01*
X732930D01*
G01X735430Y572631D02*
X732930D01*
X734722Y571089D01*
Y573173D01*
G01X735430Y574189D02*
X732930Y575231D01*
X735430Y576273D01*
G01X734555Y575898D02*
Y574564D01*
G01X733347Y577539D02*
X733097Y577789D01*
X732972Y578081D01*
X732930Y578414D01*
X733013Y578831D01*
X733222Y579123D01*
X733472Y579206D01*
X733722Y579164D01*
X733930Y578998D01*
X734347Y578164D01*
X734638Y577789D01*
X735055Y577539D01*
X735430Y577456D01*
Y579206D01*
G01X760710Y557960D02*
X736320D01*
Y583550D01*
X760710D01*
G01X763652Y546277D02*
Y549377D01*
X763192Y548757D01*
G01Y546277D02*
X764112D01*
G01X767212D02*
Y549377D01*
X765794Y547155D01*
X767710D01*
G01X769009Y546742D02*
X769239Y546484D01*
X769507Y546329D01*
X769852Y546277D01*
X770197Y546380D01*
X770465Y546587D01*
X770657Y546949D01*
X770695Y547362D01*
X770619Y547775D01*
X770427Y548034D01*
X770159Y548240D01*
X769890Y548292D01*
X769622Y548240D01*
X769277Y548034D01*
X769392Y549377D01*
X770427D01*
G01X728855Y586675D02*
Y585009D01*
X726355D01*
Y586675D01*
G01X727563Y586009D02*
Y585009D01*
G01X726355Y588025D02*
X728147D01*
X728522Y588192D01*
X728772Y588525D01*
X728855Y588942D01*
X728772Y589359D01*
X728522Y589692D01*
X728147Y589859D01*
X726355D01*
G01X728855Y592542D02*
X726355D01*
X728147Y591000D01*
Y593084D01*
G01X728855Y594100D02*
X726355Y595142D01*
X728855Y596184D01*
G01X727980Y595809D02*
Y594475D01*
G01X728855Y598242D02*
X726355D01*
X726855Y597742D01*
G01X728855D02*
Y598742D01*
G01X731839Y608037D02*
X729339D01*
Y609078D01*
X729464Y609412D01*
X729631Y609620D01*
X729964Y609703D01*
X730297Y609620D01*
X730506Y609370D01*
X730631Y609078D01*
Y608037D01*
G01Y609078D02*
X731839Y609703D01*
G01Y612470D02*
X729339D01*
X731131Y610928D01*
Y613012D01*
G01X731839Y614028D02*
X729339Y615070D01*
X731839Y616112D01*
G01X730964Y615737D02*
Y614403D01*
G01X729756Y617378D02*
X729506Y617628D01*
X729381Y617920D01*
X729339Y618253D01*
X729422Y618670D01*
X729631Y618962D01*
X729881Y619045D01*
X730131Y619003D01*
X730339Y618837D01*
X730756Y618003D01*
X731047Y617628D01*
X731464Y617378D01*
X731839Y617295D01*
Y619045D01*
G01X726068Y610335D02*
X725943Y610085D01*
X725860Y609793D01*
Y609460D01*
X725985Y609085D01*
X726193Y608793D01*
X726443Y608585D01*
X726860Y608418D01*
X727235Y608376D01*
X727610Y608460D01*
X727860Y608585D01*
X728110Y608835D01*
X728277Y609126D01*
X728360Y609418D01*
Y609710D01*
X728277Y610001D01*
X728152Y610251D01*
X727985Y610460D01*
G01X728360Y613018D02*
X725860D01*
X727652Y611476D01*
Y613560D01*
G01X728360Y614576D02*
X725860Y615618D01*
X728360Y616660D01*
G01X727485Y616285D02*
Y614951D01*
G01X726277Y617926D02*
X726027Y618176D01*
X725902Y618468D01*
X725860Y618801D01*
X725943Y619218D01*
X726152Y619510D01*
X726402Y619593D01*
X726652Y619551D01*
X726860Y619385D01*
X727277Y618551D01*
X727568Y618176D01*
X727985Y617926D01*
X728360Y617843D01*
Y619593D01*
G01X764392Y622287D02*
Y625387D01*
X763932Y624767D01*
G01Y622287D02*
X764852D01*
G01X767952D02*
Y625387D01*
X766534Y623165D01*
X768450D01*
G01X769749Y622752D02*
X769979Y622494D01*
X770247Y622339D01*
X770592Y622287D01*
X770937Y622390D01*
X771205Y622597D01*
X771397Y622959D01*
X771435Y623372D01*
X771359Y623785D01*
X771167Y624044D01*
X770899Y624250D01*
X770630Y624302D01*
X770362Y624250D01*
X770017Y624044D01*
X770132Y625387D01*
X771167D01*
G01X734791Y595134D02*
X735041Y595342D01*
X735208Y595592D01*
X735291Y595884D01*
X735208Y596217D01*
X735041Y596467D01*
X734791Y596717D01*
X734458Y596800D01*
X732791D01*
G01X735291Y599567D02*
X732791D01*
X734583Y598025D01*
Y600109D01*
G01X735291Y601125D02*
X732791Y602167D01*
X735291Y603209D01*
G01X734416Y602834D02*
Y601500D01*
G01X735291Y605267D02*
X732791D01*
X733291Y604767D01*
G01X735291D02*
Y605767D01*
G01X760710Y595760D02*
X736320D01*
Y621350D01*
X760710D01*
G01X740700Y657300D02*
Y660300D01*
X741700D01*
X742100Y660150D01*
X742400Y659950D01*
X742650Y659650D01*
X742850Y659300D01*
X742900Y658800D01*
X742850Y658300D01*
X742650Y657950D01*
X742400Y657650D01*
X742100Y657450D01*
X741700Y657300D01*
X740700D01*
G01X744650Y658650D02*
X746250D01*
X746100Y659000D01*
X745850Y659200D01*
X745500Y659300D01*
X745150Y659250D01*
X744850Y659100D01*
X744650Y658750D01*
X744550Y658450D01*
Y658150D01*
X744650Y657850D01*
X744900Y657550D01*
X745200Y657350D01*
X745550Y657300D01*
X745900Y657400D01*
X746250Y657700D01*
G01X749000Y657300D02*
Y660300D01*
G01X752600D02*
Y657300D01*
G01X751900Y659300D02*
X753300D01*
G01X757100Y657300D02*
Y659300D01*
G01Y658950D02*
X756900Y659150D01*
X756600Y659250D01*
X756250Y659300D01*
X755900Y659200D01*
X755600Y659000D01*
X755400Y658700D01*
X755300Y658300D01*
X755400Y657900D01*
X755600Y657600D01*
X755900Y657400D01*
X756250Y657300D01*
X756600Y657350D01*
X756900Y657500D01*
X757100Y657700D01*
G01X758300Y656300D02*
X761300D01*
G01X762400Y660300D02*
Y657300D01*
X764400D01*
G01X767000D02*
Y660300D01*
X766400Y659700D01*
G01Y657300D02*
X767600D01*
G01X769100Y656300D02*
X772100D01*
G01X774200Y657300D02*
Y660300D01*
X773600Y659700D01*
G01Y657300D02*
X774800D01*
G01X777800Y660300D02*
X777400Y660200D01*
X777100Y659950D01*
X776900Y659650D01*
X776750Y659250D01*
X776700Y658800D01*
X776750Y658350D01*
X776900Y657950D01*
X777100Y657650D01*
X777400Y657400D01*
X777800Y657300D01*
X778200Y657400D01*
X778500Y657650D01*
X778700Y657950D01*
X778850Y658350D01*
X778900Y658800D01*
X778850Y659250D01*
X778700Y659650D01*
X778500Y659950D01*
X778200Y660200D01*
X777800Y660300D01*
G01X781400Y659300D02*
Y657300D01*
G01Y660100D02*
X781300Y660150D01*
Y660250D01*
X781400Y660300D01*
X781500Y660250D01*
Y660150D01*
X781400Y660100D01*
G01X784150Y657300D02*
Y659300D01*
G01Y658800D02*
X784350Y659050D01*
X784650Y659250D01*
X785050Y659300D01*
X785400Y659250D01*
X785700Y659050D01*
X785850Y658700D01*
Y657300D01*
G01X789400Y659050D02*
X789050Y659250D01*
X788750Y659300D01*
X788350Y659200D01*
X788050Y659000D01*
X787850Y658650D01*
X787800Y658300D01*
X787850Y657950D01*
X788050Y657650D01*
X788350Y657400D01*
X788750Y657300D01*
X789100Y657400D01*
X789400Y657600D01*
G01X791350Y657300D02*
Y660300D01*
G01Y658850D02*
X791600Y659100D01*
X791850Y659250D01*
X792250Y659300D01*
X792550Y659250D01*
X792900Y659050D01*
X793050Y658750D01*
Y657300D01*
G01X822984Y-38057D02*
X804984D01*
Y-56057D01*
X822984D01*
Y-38057D01*
G01X842984D02*
X824984D01*
Y-56057D01*
X842984D01*
Y-38057D01*
G01X862984D02*
X844984D01*
Y-56057D01*
X862984D01*
Y-38057D01*
G01X793112Y11134D02*
Y13634D01*
X794153D01*
X794487Y13509D01*
X794695Y13342D01*
X794778Y13009D01*
X794695Y12676D01*
X794445Y12467D01*
X794153Y12342D01*
X793112D01*
G01X794153D02*
X794778Y11134D01*
G01X797545D02*
Y13634D01*
X796003Y11842D01*
X798087D01*
G01X800395Y12384D02*
X801228D01*
Y11634D01*
X800978Y11384D01*
X800687Y11217D01*
X800270Y11134D01*
X799853Y11217D01*
X799562Y11384D01*
X799312Y11634D01*
X799145Y11926D01*
X799062Y12259D01*
Y12551D01*
X799145Y12801D01*
X799312Y13092D01*
X799562Y13342D01*
X799812Y13509D01*
X800145Y13634D01*
X800437D01*
X800770Y13551D01*
X801020Y13384D01*
G01X802453Y13217D02*
X802703Y13467D01*
X802995Y13592D01*
X803328Y13634D01*
X803745Y13551D01*
X804037Y13342D01*
X804120Y13092D01*
X804078Y12842D01*
X803912Y12634D01*
X803078Y12217D01*
X802703Y11926D01*
X802453Y11509D01*
X802370Y11134D01*
X804120D01*
G01X806345Y13634D02*
X806012Y13551D01*
X805762Y13342D01*
X805595Y13092D01*
X805470Y12759D01*
X805428Y12384D01*
X805470Y12009D01*
X805595Y11676D01*
X805762Y11426D01*
X806012Y11217D01*
X806345Y11134D01*
X806678Y11217D01*
X806928Y11426D01*
X807095Y11676D01*
X807220Y12009D01*
X807262Y12384D01*
X807220Y12759D01*
X807095Y13092D01*
X806928Y13342D01*
X806678Y13551D01*
X806345Y13634D01*
G01X825295Y12503D02*
Y15003D01*
X826336D01*
X826670Y14878D01*
X826878Y14711D01*
X826961Y14378D01*
X826878Y14045D01*
X826628Y13836D01*
X826336Y13711D01*
X825295D01*
G01X826336D02*
X826961Y12503D01*
G01X829728D02*
Y15003D01*
X828186Y13211D01*
X830270D01*
G01X832578Y13753D02*
X833411D01*
Y13003D01*
X833161Y12753D01*
X832870Y12586D01*
X832453Y12503D01*
X832036Y12586D01*
X831745Y12753D01*
X831495Y13003D01*
X831328Y13295D01*
X831245Y13628D01*
Y13920D01*
X831328Y14170D01*
X831495Y14461D01*
X831745Y14711D01*
X831995Y14878D01*
X832328Y15003D01*
X832620D01*
X832953Y14920D01*
X833203Y14753D01*
G01X834636Y14586D02*
X834886Y14836D01*
X835178Y14961D01*
X835511Y15003D01*
X835928Y14920D01*
X836220Y14711D01*
X836303Y14461D01*
X836261Y14211D01*
X836095Y14003D01*
X835261Y13586D01*
X834886Y13295D01*
X834636Y12878D01*
X834553Y12503D01*
X836303D01*
G01X837736Y14586D02*
X837986Y14836D01*
X838278Y14961D01*
X838611Y15003D01*
X839028Y14920D01*
X839320Y14711D01*
X839403Y14461D01*
X839361Y14211D01*
X839195Y14003D01*
X838361Y13586D01*
X837986Y13295D01*
X837736Y12878D01*
X837653Y12503D01*
X839403D01*
G01X808815Y13841D02*
Y16341D01*
X809856D01*
X810190Y16216D01*
X810398Y16049D01*
X810481Y15716D01*
X810398Y15383D01*
X810148Y15174D01*
X809856Y15049D01*
X808815D01*
G01X809856D02*
X810481Y13841D01*
G01X813248D02*
Y16341D01*
X811706Y14549D01*
X813790D01*
G01X816098Y15091D02*
X816931D01*
Y14341D01*
X816681Y14091D01*
X816390Y13924D01*
X815973Y13841D01*
X815556Y13924D01*
X815265Y14091D01*
X815015Y14341D01*
X814848Y14633D01*
X814765Y14966D01*
Y15258D01*
X814848Y15508D01*
X815015Y15799D01*
X815265Y16049D01*
X815515Y16216D01*
X815848Y16341D01*
X816140D01*
X816473Y16258D01*
X816723Y16091D01*
G01X818156Y15924D02*
X818406Y16174D01*
X818698Y16299D01*
X819031Y16341D01*
X819448Y16258D01*
X819740Y16049D01*
X819823Y15799D01*
X819781Y15549D01*
X819615Y15341D01*
X818781Y14924D01*
X818406Y14633D01*
X818156Y14216D01*
X818073Y13841D01*
X819823D01*
G01X822048D02*
Y16341D01*
X821548Y15841D01*
G01Y13841D02*
X822548D01*
G01X842717Y15604D02*
X842467Y15729D01*
X842175Y15812D01*
X841842D01*
X841467Y15687D01*
X841175Y15479D01*
X840967Y15229D01*
X840800Y14812D01*
X840758Y14437D01*
X840842Y14062D01*
X840967Y13812D01*
X841217Y13562D01*
X841508Y13395D01*
X841800Y13312D01*
X842092D01*
X842383Y13395D01*
X842633Y13520D01*
X842842Y13687D01*
G01X845400Y13312D02*
Y15812D01*
X843858Y14020D01*
X845942D01*
G01X848250Y14562D02*
X849083D01*
Y13812D01*
X848833Y13562D01*
X848542Y13395D01*
X848125Y13312D01*
X847708Y13395D01*
X847417Y13562D01*
X847167Y13812D01*
X847000Y14104D01*
X846917Y14437D01*
Y14729D01*
X847000Y14979D01*
X847167Y15270D01*
X847417Y15520D01*
X847667Y15687D01*
X848000Y15812D01*
X848292D01*
X848625Y15729D01*
X848875Y15562D01*
G01X851100Y13312D02*
Y15812D01*
X850600Y15312D01*
G01Y13312D02*
X851600D01*
G01X853492Y13604D02*
X853783Y13395D01*
X854117Y13312D01*
X854450Y13395D01*
X854742Y13645D01*
X854950Y14020D01*
X855033Y14395D01*
Y14854D01*
X854950Y15229D01*
X854742Y15562D01*
X854492Y15729D01*
X854200Y15812D01*
X853867Y15729D01*
X853617Y15562D01*
X853450Y15312D01*
X853367Y14979D01*
X853450Y14687D01*
X853658Y14395D01*
X853908Y14229D01*
X854200Y14187D01*
X854533Y14270D01*
X854783Y14479D01*
X855033Y14854D01*
G01X864200Y89200D02*
X862701D01*
X862700Y89201D01*
Y94199D01*
X862699Y94200D01*
X801301D01*
X801300Y94201D01*
Y96400D01*
G01X795046Y45546D02*
X792546D01*
Y46587D01*
X792671Y46921D01*
X792838Y47129D01*
X793171Y47212D01*
X793504Y47129D01*
X793713Y46879D01*
X793838Y46587D01*
Y45546D01*
G01Y46587D02*
X795046Y47212D01*
G01Y49979D02*
X792546D01*
X794338Y48437D01*
Y50521D01*
G01X793796Y52829D02*
Y53662D01*
X794546D01*
X794796Y53412D01*
X794963Y53121D01*
X795046Y52704D01*
X794963Y52287D01*
X794796Y51996D01*
X794546Y51746D01*
X794254Y51579D01*
X793921Y51496D01*
X793629D01*
X793379Y51579D01*
X793088Y51746D01*
X792838Y51996D01*
X792671Y52246D01*
X792546Y52579D01*
Y52871D01*
X792629Y53204D01*
X792796Y53454D01*
G01X794546Y54762D02*
X794838Y55012D01*
X795004Y55346D01*
X795046Y55721D01*
X795004Y56054D01*
X794796Y56387D01*
X794546Y56596D01*
X794296Y56637D01*
X794004Y56554D01*
X793796Y56262D01*
X793713Y55971D01*
Y55596D01*
G01Y55971D02*
X793588Y56221D01*
X793379Y56429D01*
X793129Y56512D01*
X792879Y56429D01*
X792671Y56221D01*
X792546Y55846D01*
X792588Y55471D01*
X792754Y55096D01*
G01X790262Y45417D02*
X787762D01*
Y46458D01*
X787887Y46792D01*
X788054Y47000D01*
X788387Y47083D01*
X788720Y47000D01*
X788929Y46750D01*
X789054Y46458D01*
Y45417D01*
G01Y46458D02*
X790262Y47083D01*
G01Y49850D02*
X787762D01*
X789554Y48308D01*
Y50392D01*
G01X789012Y52700D02*
Y53533D01*
X789762D01*
X790012Y53283D01*
X790179Y52992D01*
X790262Y52575D01*
X790179Y52158D01*
X790012Y51867D01*
X789762Y51617D01*
X789470Y51450D01*
X789137Y51367D01*
X788845D01*
X788595Y51450D01*
X788304Y51617D01*
X788054Y51867D01*
X787887Y52117D01*
X787762Y52450D01*
Y52742D01*
X787845Y53075D01*
X788012Y53325D01*
G01X788179Y54758D02*
X787929Y55008D01*
X787804Y55300D01*
X787762Y55633D01*
X787845Y56050D01*
X788054Y56342D01*
X788304Y56425D01*
X788554Y56383D01*
X788762Y56217D01*
X789179Y55383D01*
X789470Y55008D01*
X789887Y54758D01*
X790262Y54675D01*
Y56425D01*
G01X799472Y50606D02*
X799222Y50731D01*
X798930Y50814D01*
X798597D01*
X798222Y50689D01*
X797930Y50481D01*
X797722Y50231D01*
X797555Y49814D01*
X797513Y49439D01*
X797597Y49064D01*
X797722Y48814D01*
X797972Y48564D01*
X798263Y48397D01*
X798555Y48314D01*
X798847D01*
X799138Y48397D01*
X799388Y48522D01*
X799597Y48689D01*
G01X802155Y48314D02*
Y50814D01*
X800613Y49022D01*
X802697D01*
G01X805005Y49564D02*
X805838D01*
Y48814D01*
X805588Y48564D01*
X805297Y48397D01*
X804880Y48314D01*
X804463Y48397D01*
X804172Y48564D01*
X803922Y48814D01*
X803755Y49106D01*
X803672Y49439D01*
Y49731D01*
X803755Y49981D01*
X803922Y50272D01*
X804172Y50522D01*
X804422Y50689D01*
X804755Y50814D01*
X805047D01*
X805380Y50731D01*
X805630Y50564D01*
G01X806938Y48814D02*
X807188Y48522D01*
X807522Y48356D01*
X807897Y48314D01*
X808230Y48356D01*
X808563Y48564D01*
X808772Y48814D01*
X808813Y49064D01*
X808730Y49356D01*
X808438Y49564D01*
X808147Y49647D01*
X807772D01*
G01X808147D02*
X808397Y49772D01*
X808605Y49981D01*
X808688Y50231D01*
X808605Y50481D01*
X808397Y50689D01*
X808022Y50814D01*
X807647Y50772D01*
X807272Y50606D01*
G01X801300Y111400D02*
Y116500D01*
G01X882100Y119500D02*
X878401D01*
X878400Y119501D01*
Y123899D01*
X878399Y123900D01*
X859901D01*
X859900Y123899D01*
Y119501D01*
X859899Y119500D01*
X832911D01*
Y121423D01*
X831900D01*
G01X804400Y119500D02*
X829209D01*
Y121423D01*
X831900D01*
Y158100D01*
G01X837767Y95700D02*
Y98200D01*
X838808D01*
X839142Y98075D01*
X839350Y97908D01*
X839433Y97575D01*
X839350Y97242D01*
X839100Y97033D01*
X838808Y96908D01*
X837767D01*
G01X838808D02*
X839433Y95700D01*
G01X842200D02*
Y98200D01*
X840658Y96408D01*
X842742D01*
G01X845050Y96950D02*
X845883D01*
Y96200D01*
X845633Y95950D01*
X845342Y95783D01*
X844925Y95700D01*
X844508Y95783D01*
X844217Y95950D01*
X843967Y96200D01*
X843800Y96492D01*
X843717Y96825D01*
Y97117D01*
X843800Y97367D01*
X843967Y97658D01*
X844217Y97908D01*
X844467Y98075D01*
X844800Y98200D01*
X845092D01*
X845425Y98117D01*
X845675Y97950D01*
G01X847900Y95700D02*
Y98200D01*
X847400Y97700D01*
G01Y95700D02*
X848400D01*
G01X850917D02*
X851000Y96242D01*
X851125Y96700D01*
X851292Y97117D01*
X851500Y97575D01*
X851833Y98200D01*
X850167D01*
G01X821118Y97036D02*
X818618D01*
Y98077D01*
X818743Y98411D01*
X818910Y98619D01*
X819243Y98702D01*
X819576Y98619D01*
X819785Y98369D01*
X819910Y98077D01*
Y97036D01*
G01Y98077D02*
X821118Y98702D01*
G01Y101469D02*
X818618D01*
X820410Y99927D01*
Y102011D01*
G01X819868Y104319D02*
Y105152D01*
X820618D01*
X820868Y104902D01*
X821035Y104611D01*
X821118Y104194D01*
X821035Y103777D01*
X820868Y103486D01*
X820618Y103236D01*
X820326Y103069D01*
X819993Y102986D01*
X819701D01*
X819451Y103069D01*
X819160Y103236D01*
X818910Y103486D01*
X818743Y103736D01*
X818618Y104069D01*
Y104361D01*
X818701Y104694D01*
X818868Y104944D01*
G01X820743Y106252D02*
X820951Y106502D01*
X821076Y106794D01*
X821118Y107169D01*
X821035Y107544D01*
X820868Y107836D01*
X820576Y108044D01*
X820243Y108086D01*
X819910Y108002D01*
X819701Y107794D01*
X819535Y107502D01*
X819493Y107211D01*
X819535Y106919D01*
X819701Y106544D01*
X818618Y106669D01*
Y107794D01*
G01X822623Y101935D02*
Y104435D01*
X823664D01*
X823998Y104310D01*
X824206Y104143D01*
X824289Y103810D01*
X824206Y103477D01*
X823956Y103268D01*
X823664Y103143D01*
X822623D01*
G01X823664D02*
X824289Y101935D01*
G01X827056D02*
Y104435D01*
X825514Y102643D01*
X827598D01*
G01X829906Y103185D02*
X830739D01*
Y102435D01*
X830489Y102185D01*
X830198Y102018D01*
X829781Y101935D01*
X829364Y102018D01*
X829073Y102185D01*
X828823Y102435D01*
X828656Y102727D01*
X828573Y103060D01*
Y103352D01*
X828656Y103602D01*
X828823Y103893D01*
X829073Y104143D01*
X829323Y104310D01*
X829656Y104435D01*
X829948D01*
X830281Y104352D01*
X830531Y104185D01*
G01X832756Y101935D02*
Y104435D01*
X832256Y103935D01*
G01Y101935D02*
X833256D01*
G01X834939Y102310D02*
X835189Y102102D01*
X835481Y101977D01*
X835856Y101935D01*
X836231Y102018D01*
X836523Y102185D01*
X836731Y102477D01*
X836773Y102810D01*
X836689Y103143D01*
X836481Y103352D01*
X836189Y103518D01*
X835898Y103560D01*
X835606Y103518D01*
X835231Y103352D01*
X835356Y104435D01*
X836481D01*
G01X820517Y111667D02*
Y114167D01*
X821558D01*
X821892Y114042D01*
X822100Y113875D01*
X822183Y113542D01*
X822100Y113209D01*
X821850Y113000D01*
X821558Y112875D01*
X820517D01*
G01X821558D02*
X822183Y111667D01*
G01X824950D02*
Y114167D01*
X823408Y112375D01*
X825492D01*
G01X827800Y112917D02*
X828633D01*
Y112167D01*
X828383Y111917D01*
X828092Y111750D01*
X827675Y111667D01*
X827258Y111750D01*
X826967Y111917D01*
X826717Y112167D01*
X826550Y112459D01*
X826467Y112792D01*
Y113084D01*
X826550Y113334D01*
X826717Y113625D01*
X826967Y113875D01*
X827217Y114042D01*
X827550Y114167D01*
X827842D01*
X828175Y114084D01*
X828425Y113917D01*
G01X831150Y111667D02*
Y114167D01*
X829608Y112375D01*
X831692D01*
G01X806517Y112667D02*
Y115167D01*
X807558D01*
X807892Y115042D01*
X808100Y114875D01*
X808183Y114542D01*
X808100Y114209D01*
X807850Y114000D01*
X807558Y113875D01*
X806517D01*
G01X807558D02*
X808183Y112667D01*
G01X810950D02*
Y115167D01*
X809408Y113375D01*
X811492D01*
G01X813800Y113917D02*
X814633D01*
Y113167D01*
X814383Y112917D01*
X814092Y112750D01*
X813675Y112667D01*
X813258Y112750D01*
X812967Y112917D01*
X812717Y113167D01*
X812550Y113459D01*
X812467Y113792D01*
Y114084D01*
X812550Y114334D01*
X812717Y114625D01*
X812967Y114875D01*
X813217Y115042D01*
X813550Y115167D01*
X813842D01*
X814175Y115084D01*
X814425Y114917D01*
G01X816567Y112667D02*
X816650Y113209D01*
X816775Y113667D01*
X816942Y114084D01*
X817150Y114542D01*
X817483Y115167D01*
X815817D01*
G01X843800Y103517D02*
X841300D01*
Y104558D01*
X841425Y104892D01*
X841592Y105100D01*
X841925Y105183D01*
X842258Y105100D01*
X842467Y104850D01*
X842592Y104558D01*
Y103517D01*
G01Y104558D02*
X843800Y105183D01*
G01Y107950D02*
X841300D01*
X843092Y106408D01*
Y108492D01*
G01X842550Y110800D02*
Y111633D01*
X843300D01*
X843550Y111383D01*
X843717Y111092D01*
X843800Y110675D01*
X843717Y110258D01*
X843550Y109967D01*
X843300Y109717D01*
X843008Y109550D01*
X842675Y109467D01*
X842383D01*
X842133Y109550D01*
X841842Y109717D01*
X841592Y109967D01*
X841425Y110217D01*
X841300Y110550D01*
Y110842D01*
X841383Y111175D01*
X841550Y111425D01*
G01X843508Y112942D02*
X843717Y113233D01*
X843800Y113567D01*
X843717Y113900D01*
X843467Y114192D01*
X843092Y114400D01*
X842717Y114483D01*
X842258D01*
X841883Y114400D01*
X841550Y114192D01*
X841383Y113942D01*
X841300Y113650D01*
X841383Y113317D01*
X841550Y113067D01*
X841800Y112900D01*
X842133Y112817D01*
X842425Y112900D01*
X842717Y113108D01*
X842883Y113358D01*
X842925Y113650D01*
X842842Y113983D01*
X842633Y114233D01*
X842258Y114483D01*
G01X847200Y103517D02*
X844700D01*
Y104558D01*
X844825Y104892D01*
X844992Y105100D01*
X845325Y105183D01*
X845658Y105100D01*
X845867Y104850D01*
X845992Y104558D01*
Y103517D01*
G01Y104558D02*
X847200Y105183D01*
G01Y107950D02*
X844700D01*
X846492Y106408D01*
Y108492D01*
G01X845950Y110800D02*
Y111633D01*
X846700D01*
X846950Y111383D01*
X847117Y111092D01*
X847200Y110675D01*
X847117Y110258D01*
X846950Y109967D01*
X846700Y109717D01*
X846408Y109550D01*
X846075Y109467D01*
X845783D01*
X845533Y109550D01*
X845242Y109717D01*
X844992Y109967D01*
X844825Y110217D01*
X844700Y110550D01*
Y110842D01*
X844783Y111175D01*
X844950Y111425D01*
G01X847200Y113650D02*
X844700D01*
X845200Y113150D01*
G01X847200D02*
Y114150D01*
G01X846700Y115833D02*
X846992Y116083D01*
X847158Y116417D01*
X847200Y116792D01*
X847158Y117125D01*
X846950Y117458D01*
X846700Y117667D01*
X846450Y117708D01*
X846158Y117625D01*
X845950Y117333D01*
X845867Y117042D01*
Y116667D01*
G01Y117042D02*
X845742Y117292D01*
X845533Y117500D01*
X845283Y117583D01*
X845033Y117500D01*
X844825Y117292D01*
X844700Y116917D01*
X844742Y116542D01*
X844908Y116167D01*
G01X837764Y99269D02*
Y101769D01*
X838805D01*
X839139Y101644D01*
X839347Y101477D01*
X839430Y101144D01*
X839347Y100811D01*
X839097Y100602D01*
X838805Y100477D01*
X837764D01*
G01X838805D02*
X839430Y99269D01*
G01X842197D02*
Y101769D01*
X840655Y99977D01*
X842739D01*
G01X845047Y100519D02*
X845880D01*
Y99769D01*
X845630Y99519D01*
X845339Y99352D01*
X844922Y99269D01*
X844505Y99352D01*
X844214Y99519D01*
X843964Y99769D01*
X843797Y100061D01*
X843714Y100394D01*
Y100686D01*
X843797Y100936D01*
X843964Y101227D01*
X844214Y101477D01*
X844464Y101644D01*
X844797Y101769D01*
X845089D01*
X845422Y101686D01*
X845672Y101519D01*
G01X847105Y101352D02*
X847355Y101602D01*
X847647Y101727D01*
X847980Y101769D01*
X848397Y101686D01*
X848689Y101477D01*
X848772Y101227D01*
X848730Y100977D01*
X848564Y100769D01*
X847730Y100352D01*
X847355Y100061D01*
X847105Y99644D01*
X847022Y99269D01*
X848772D01*
G01X850080Y99644D02*
X850330Y99436D01*
X850622Y99311D01*
X850997Y99269D01*
X851372Y99352D01*
X851664Y99519D01*
X851872Y99811D01*
X851914Y100144D01*
X851830Y100477D01*
X851622Y100686D01*
X851330Y100852D01*
X851039Y100894D01*
X850747Y100852D01*
X850372Y100686D01*
X850497Y101769D01*
X851622D01*
G01X806918Y96736D02*
X804418D01*
Y97777D01*
X804543Y98111D01*
X804710Y98319D01*
X805043Y98402D01*
X805376Y98319D01*
X805585Y98069D01*
X805710Y97777D01*
Y96736D01*
G01Y97777D02*
X806918Y98402D01*
G01Y101169D02*
X804418D01*
X806210Y99627D01*
Y101711D01*
G01X805668Y104019D02*
Y104852D01*
X806418D01*
X806668Y104602D01*
X806835Y104311D01*
X806918Y103894D01*
X806835Y103477D01*
X806668Y103186D01*
X806418Y102936D01*
X806126Y102769D01*
X805793Y102686D01*
X805501D01*
X805251Y102769D01*
X804960Y102936D01*
X804710Y103186D01*
X804543Y103436D01*
X804418Y103769D01*
Y104061D01*
X804501Y104394D01*
X804668Y104644D01*
G01X806918Y106869D02*
X804418D01*
X804918Y106369D01*
G01X806918D02*
Y107369D01*
G01X805876Y109177D02*
X805585Y109469D01*
X805418Y109719D01*
X805335Y110052D01*
X805418Y110344D01*
X805585Y110552D01*
X805835Y110719D01*
X806126Y110761D01*
X806376Y110719D01*
X806626Y110552D01*
X806835Y110302D01*
X806918Y110011D01*
X806835Y109677D01*
X806585Y109386D01*
X806210Y109219D01*
X805793Y109177D01*
X805251Y109261D01*
X804960Y109386D01*
X804668Y109594D01*
X804460Y109886D01*
X804418Y110177D01*
X804501Y110469D01*
X804710Y110677D01*
G01X814318Y97036D02*
X811818D01*
Y98077D01*
X811943Y98411D01*
X812110Y98619D01*
X812443Y98702D01*
X812776Y98619D01*
X812985Y98369D01*
X813110Y98077D01*
Y97036D01*
G01Y98077D02*
X814318Y98702D01*
G01Y101469D02*
X811818D01*
X813610Y99927D01*
Y102011D01*
G01X813068Y104319D02*
Y105152D01*
X813818D01*
X814068Y104902D01*
X814235Y104611D01*
X814318Y104194D01*
X814235Y103777D01*
X814068Y103486D01*
X813818Y103236D01*
X813526Y103069D01*
X813193Y102986D01*
X812901D01*
X812651Y103069D01*
X812360Y103236D01*
X812110Y103486D01*
X811943Y103736D01*
X811818Y104069D01*
Y104361D01*
X811901Y104694D01*
X812068Y104944D01*
G01X814318Y107169D02*
X811818D01*
X812318Y106669D01*
G01X814318D02*
Y107669D01*
G01X811818Y110269D02*
X811901Y109936D01*
X812110Y109686D01*
X812360Y109519D01*
X812693Y109394D01*
X813068Y109352D01*
X813443Y109394D01*
X813776Y109519D01*
X814026Y109686D01*
X814235Y109936D01*
X814318Y110269D01*
X814235Y110602D01*
X814026Y110852D01*
X813776Y111019D01*
X813443Y111144D01*
X813068Y111186D01*
X812693Y111144D01*
X812360Y111019D01*
X812110Y110852D01*
X811901Y110602D01*
X811818Y110269D01*
G01X821467Y115167D02*
Y117667D01*
X822508D01*
X822842Y117542D01*
X823050Y117375D01*
X823133Y117042D01*
X823050Y116709D01*
X822800Y116500D01*
X822508Y116375D01*
X821467D01*
G01X822508D02*
X823133Y115167D01*
G01X825900D02*
Y117667D01*
X824358Y115875D01*
X826442D01*
G01X828750Y116417D02*
X829583D01*
Y115667D01*
X829333Y115417D01*
X829042Y115250D01*
X828625Y115167D01*
X828208Y115250D01*
X827917Y115417D01*
X827667Y115667D01*
X827500Y115959D01*
X827417Y116292D01*
Y116584D01*
X827500Y116834D01*
X827667Y117125D01*
X827917Y117375D01*
X828167Y117542D01*
X828500Y117667D01*
X828792D01*
X829125Y117584D01*
X829375Y117417D01*
G01X830808Y117250D02*
X831058Y117500D01*
X831350Y117625D01*
X831683Y117667D01*
X832100Y117584D01*
X832392Y117375D01*
X832475Y117125D01*
X832433Y116875D01*
X832267Y116667D01*
X831433Y116250D01*
X831058Y115959D01*
X830808Y115542D01*
X830725Y115167D01*
X832475D01*
G01X835200D02*
Y117667D01*
X833658Y115875D01*
X835742D01*
G01X844208Y143617D02*
X844083Y143367D01*
X844000Y143075D01*
Y142742D01*
X844125Y142367D01*
X844333Y142075D01*
X844583Y141867D01*
X845000Y141700D01*
X845375Y141658D01*
X845750Y141742D01*
X846000Y141867D01*
X846250Y142117D01*
X846417Y142408D01*
X846500Y142700D01*
Y142992D01*
X846417Y143283D01*
X846292Y143533D01*
X846125Y143742D01*
G01Y144883D02*
X846333Y145133D01*
X846458Y145425D01*
X846500Y145800D01*
X846417Y146175D01*
X846250Y146467D01*
X845958Y146675D01*
X845625Y146717D01*
X845292Y146633D01*
X845083Y146425D01*
X844917Y146133D01*
X844875Y145842D01*
X844917Y145550D01*
X845083Y145175D01*
X844000Y145300D01*
Y146425D01*
G01X846500Y147983D02*
X844000D01*
Y148817D01*
X844125Y149150D01*
X844292Y149400D01*
X844542Y149608D01*
X844833Y149775D01*
X845250Y149817D01*
X845667Y149775D01*
X845958Y149608D01*
X846208Y149400D01*
X846375Y149150D01*
X846500Y148817D01*
Y147983D01*
G01Y152500D02*
X844000D01*
X845792Y150958D01*
Y153042D01*
G01X844417Y154308D02*
X844167Y154558D01*
X844042Y154850D01*
X844000Y155183D01*
X844083Y155600D01*
X844292Y155892D01*
X844542Y155975D01*
X844792Y155933D01*
X845000Y155767D01*
X845417Y154933D01*
X845708Y154558D01*
X846125Y154308D01*
X846500Y154225D01*
Y155975D01*
G01X835417Y131992D02*
X835167Y132117D01*
X834875Y132200D01*
X834542D01*
X834167Y132075D01*
X833875Y131867D01*
X833667Y131617D01*
X833500Y131200D01*
X833458Y130825D01*
X833542Y130450D01*
X833667Y130200D01*
X833917Y129950D01*
X834208Y129783D01*
X834500Y129700D01*
X834792D01*
X835083Y129783D01*
X835333Y129908D01*
X835542Y130075D01*
G01X836683D02*
X836933Y129867D01*
X837225Y129742D01*
X837600Y129700D01*
X837975Y129783D01*
X838267Y129950D01*
X838475Y130242D01*
X838517Y130575D01*
X838433Y130908D01*
X838225Y131117D01*
X837933Y131283D01*
X837642Y131325D01*
X837350Y131283D01*
X836975Y131117D01*
X837100Y132200D01*
X838225D01*
G01X839783Y129700D02*
Y132200D01*
X840617D01*
X840950Y132075D01*
X841200Y131908D01*
X841408Y131658D01*
X841575Y131367D01*
X841617Y130950D01*
X841575Y130533D01*
X841408Y130242D01*
X841200Y129992D01*
X840950Y129825D01*
X840617Y129700D01*
X839783D01*
G01X842883Y130075D02*
X843133Y129867D01*
X843425Y129742D01*
X843800Y129700D01*
X844175Y129783D01*
X844467Y129950D01*
X844675Y130242D01*
X844717Y130575D01*
X844633Y130908D01*
X844425Y131117D01*
X844133Y131283D01*
X843842Y131325D01*
X843550Y131283D01*
X843175Y131117D01*
X843300Y132200D01*
X844425D01*
G01X845983Y130075D02*
X846233Y129867D01*
X846525Y129742D01*
X846900Y129700D01*
X847275Y129783D01*
X847567Y129950D01*
X847775Y130242D01*
X847817Y130575D01*
X847733Y130908D01*
X847525Y131117D01*
X847233Y131283D01*
X846942Y131325D01*
X846650Y131283D01*
X846275Y131117D01*
X846400Y132200D01*
X847525D01*
G01X837408Y143617D02*
X837283Y143367D01*
X837200Y143075D01*
Y142742D01*
X837325Y142367D01*
X837533Y142075D01*
X837783Y141867D01*
X838200Y141700D01*
X838575Y141658D01*
X838950Y141742D01*
X839200Y141867D01*
X839450Y142117D01*
X839617Y142408D01*
X839700Y142700D01*
Y142992D01*
X839617Y143283D01*
X839492Y143533D01*
X839325Y143742D01*
G01Y144883D02*
X839533Y145133D01*
X839658Y145425D01*
X839700Y145800D01*
X839617Y146175D01*
X839450Y146467D01*
X839158Y146675D01*
X838825Y146717D01*
X838492Y146633D01*
X838283Y146425D01*
X838117Y146133D01*
X838075Y145842D01*
X838117Y145550D01*
X838283Y145175D01*
X837200Y145300D01*
Y146425D01*
G01X839700Y147983D02*
X837200D01*
Y148817D01*
X837325Y149150D01*
X837492Y149400D01*
X837742Y149608D01*
X838033Y149775D01*
X838450Y149817D01*
X838867Y149775D01*
X839158Y149608D01*
X839408Y149400D01*
X839575Y149150D01*
X839700Y148817D01*
Y147983D01*
G01Y152500D02*
X837200D01*
X838992Y150958D01*
Y153042D01*
G01X837200Y155100D02*
X837283Y154767D01*
X837492Y154517D01*
X837742Y154350D01*
X838075Y154225D01*
X838450Y154183D01*
X838825Y154225D01*
X839158Y154350D01*
X839408Y154517D01*
X839617Y154767D01*
X839700Y155100D01*
X839617Y155433D01*
X839408Y155683D01*
X839158Y155850D01*
X838825Y155975D01*
X838450Y156017D01*
X838075Y155975D01*
X837742Y155850D01*
X837492Y155683D01*
X837283Y155433D01*
X837200Y155100D01*
G01X834008Y143617D02*
X833883Y143367D01*
X833800Y143075D01*
Y142742D01*
X833925Y142367D01*
X834133Y142075D01*
X834383Y141867D01*
X834800Y141700D01*
X835175Y141658D01*
X835550Y141742D01*
X835800Y141867D01*
X836050Y142117D01*
X836217Y142408D01*
X836300Y142700D01*
Y142992D01*
X836217Y143283D01*
X836092Y143533D01*
X835925Y143742D01*
G01Y144883D02*
X836133Y145133D01*
X836258Y145425D01*
X836300Y145800D01*
X836217Y146175D01*
X836050Y146467D01*
X835758Y146675D01*
X835425Y146717D01*
X835092Y146633D01*
X834883Y146425D01*
X834717Y146133D01*
X834675Y145842D01*
X834717Y145550D01*
X834883Y145175D01*
X833800Y145300D01*
Y146425D01*
G01X836300Y147983D02*
X833800D01*
Y148817D01*
X833925Y149150D01*
X834092Y149400D01*
X834342Y149608D01*
X834633Y149775D01*
X835050Y149817D01*
X835467Y149775D01*
X835758Y149608D01*
X836008Y149400D01*
X836175Y149150D01*
X836300Y148817D01*
Y147983D01*
G01X835800Y151083D02*
X836092Y151333D01*
X836258Y151667D01*
X836300Y152042D01*
X836258Y152375D01*
X836050Y152708D01*
X835800Y152917D01*
X835550Y152958D01*
X835258Y152875D01*
X835050Y152583D01*
X834967Y152292D01*
Y151917D01*
G01Y152292D02*
X834842Y152542D01*
X834633Y152750D01*
X834383Y152833D01*
X834133Y152750D01*
X833925Y152542D01*
X833800Y152167D01*
X833842Y151792D01*
X834008Y151417D01*
G01X836008Y154392D02*
X836217Y154683D01*
X836300Y155017D01*
X836217Y155350D01*
X835967Y155642D01*
X835592Y155850D01*
X835217Y155933D01*
X834758D01*
X834383Y155850D01*
X834050Y155642D01*
X833883Y155392D01*
X833800Y155100D01*
X833883Y154767D01*
X834050Y154517D01*
X834300Y154350D01*
X834633Y154267D01*
X834925Y154350D01*
X835217Y154558D01*
X835383Y154808D01*
X835425Y155100D01*
X835342Y155433D01*
X835133Y155683D01*
X834758Y155933D01*
G01X840808Y143617D02*
X840683Y143367D01*
X840600Y143075D01*
Y142742D01*
X840725Y142367D01*
X840933Y142075D01*
X841183Y141867D01*
X841600Y141700D01*
X841975Y141658D01*
X842350Y141742D01*
X842600Y141867D01*
X842850Y142117D01*
X843017Y142408D01*
X843100Y142700D01*
Y142992D01*
X843017Y143283D01*
X842892Y143533D01*
X842725Y143742D01*
G01Y144883D02*
X842933Y145133D01*
X843058Y145425D01*
X843100Y145800D01*
X843017Y146175D01*
X842850Y146467D01*
X842558Y146675D01*
X842225Y146717D01*
X841892Y146633D01*
X841683Y146425D01*
X841517Y146133D01*
X841475Y145842D01*
X841517Y145550D01*
X841683Y145175D01*
X840600Y145300D01*
Y146425D01*
G01X843100Y147983D02*
X840600D01*
Y148817D01*
X840725Y149150D01*
X840892Y149400D01*
X841142Y149608D01*
X841433Y149775D01*
X841850Y149817D01*
X842267Y149775D01*
X842558Y149608D01*
X842808Y149400D01*
X842975Y149150D01*
X843100Y148817D01*
Y147983D01*
G01Y152500D02*
X840600D01*
X842392Y150958D01*
Y153042D01*
G01X843100Y155100D02*
X840600D01*
X841100Y154600D01*
G01X843100D02*
Y155600D01*
G01X835417Y135392D02*
X835167Y135517D01*
X834875Y135600D01*
X834542D01*
X834167Y135475D01*
X833875Y135267D01*
X833667Y135017D01*
X833500Y134600D01*
X833458Y134225D01*
X833542Y133850D01*
X833667Y133600D01*
X833917Y133350D01*
X834208Y133183D01*
X834500Y133100D01*
X834792D01*
X835083Y133183D01*
X835333Y133308D01*
X835542Y133475D01*
G01X836683D02*
X836933Y133267D01*
X837225Y133142D01*
X837600Y133100D01*
X837975Y133183D01*
X838267Y133350D01*
X838475Y133642D01*
X838517Y133975D01*
X838433Y134308D01*
X838225Y134517D01*
X837933Y134683D01*
X837642Y134725D01*
X837350Y134683D01*
X836975Y134517D01*
X837100Y135600D01*
X838225D01*
G01X839783Y133100D02*
Y135600D01*
X840617D01*
X840950Y135475D01*
X841200Y135308D01*
X841408Y135058D01*
X841575Y134767D01*
X841617Y134350D01*
X841575Y133933D01*
X841408Y133642D01*
X841200Y133392D01*
X840950Y133225D01*
X840617Y133100D01*
X839783D01*
G01X842883Y133475D02*
X843133Y133267D01*
X843425Y133142D01*
X843800Y133100D01*
X844175Y133183D01*
X844467Y133350D01*
X844675Y133642D01*
X844717Y133975D01*
X844633Y134308D01*
X844425Y134517D01*
X844133Y134683D01*
X843842Y134725D01*
X843550Y134683D01*
X843175Y134517D01*
X843300Y135600D01*
X844425D01*
G01X847400Y133100D02*
Y135600D01*
X845858Y133808D01*
X847942D01*
G01X847608Y143617D02*
X847483Y143367D01*
X847400Y143075D01*
Y142742D01*
X847525Y142367D01*
X847733Y142075D01*
X847983Y141867D01*
X848400Y141700D01*
X848775Y141658D01*
X849150Y141742D01*
X849400Y141867D01*
X849650Y142117D01*
X849817Y142408D01*
X849900Y142700D01*
Y142992D01*
X849817Y143283D01*
X849692Y143533D01*
X849525Y143742D01*
G01Y144883D02*
X849733Y145133D01*
X849858Y145425D01*
X849900Y145800D01*
X849817Y146175D01*
X849650Y146467D01*
X849358Y146675D01*
X849025Y146717D01*
X848692Y146633D01*
X848483Y146425D01*
X848317Y146133D01*
X848275Y145842D01*
X848317Y145550D01*
X848483Y145175D01*
X847400Y145300D01*
Y146425D01*
G01X849900Y147983D02*
X847400D01*
Y148817D01*
X847525Y149150D01*
X847692Y149400D01*
X847942Y149608D01*
X848233Y149775D01*
X848650Y149817D01*
X849067Y149775D01*
X849358Y149608D01*
X849608Y149400D01*
X849775Y149150D01*
X849900Y148817D01*
Y147983D01*
G01Y152500D02*
X847400D01*
X849192Y150958D01*
Y153042D01*
G01X849400Y154183D02*
X849692Y154433D01*
X849858Y154767D01*
X849900Y155142D01*
X849858Y155475D01*
X849650Y155808D01*
X849400Y156017D01*
X849150Y156058D01*
X848858Y155975D01*
X848650Y155683D01*
X848567Y155392D01*
Y155017D01*
G01Y155392D02*
X848442Y155642D01*
X848233Y155850D01*
X847983Y155933D01*
X847733Y155850D01*
X847525Y155642D01*
X847400Y155267D01*
X847442Y154892D01*
X847608Y154517D01*
G01X806717Y118459D02*
X806467Y118584D01*
X806175Y118667D01*
X805842D01*
X805467Y118542D01*
X805175Y118334D01*
X804967Y118084D01*
X804800Y117667D01*
X804758Y117292D01*
X804842Y116917D01*
X804967Y116667D01*
X805217Y116417D01*
X805508Y116250D01*
X805800Y116167D01*
X806092D01*
X806383Y116250D01*
X806633Y116375D01*
X806842Y116542D01*
G01X809400Y116167D02*
Y118667D01*
X807858Y116875D01*
X809942D01*
G01X812250Y117417D02*
X813083D01*
Y116667D01*
X812833Y116417D01*
X812542Y116250D01*
X812125Y116167D01*
X811708Y116250D01*
X811417Y116417D01*
X811167Y116667D01*
X811000Y116959D01*
X810917Y117292D01*
Y117584D01*
X811000Y117834D01*
X811167Y118125D01*
X811417Y118375D01*
X811667Y118542D01*
X812000Y118667D01*
X812292D01*
X812625Y118584D01*
X812875Y118417D01*
G01X814308Y118250D02*
X814558Y118500D01*
X814850Y118625D01*
X815183Y118667D01*
X815600Y118584D01*
X815892Y118375D01*
X815975Y118125D01*
X815933Y117875D01*
X815767Y117667D01*
X814933Y117250D01*
X814558Y116959D01*
X814308Y116542D01*
X814225Y116167D01*
X815975D01*
G01X817408Y117209D02*
X817700Y117500D01*
X817950Y117667D01*
X818283Y117750D01*
X818575Y117667D01*
X818783Y117500D01*
X818950Y117250D01*
X818992Y116959D01*
X818950Y116709D01*
X818783Y116459D01*
X818533Y116250D01*
X818242Y116167D01*
X817908Y116250D01*
X817617Y116500D01*
X817450Y116875D01*
X817408Y117292D01*
X817492Y117834D01*
X817617Y118125D01*
X817825Y118417D01*
X818117Y118625D01*
X818408Y118667D01*
X818700Y118584D01*
X818908Y118375D01*
G01X815426Y98786D02*
X815301Y98536D01*
X815218Y98244D01*
Y97911D01*
X815343Y97536D01*
X815551Y97244D01*
X815801Y97036D01*
X816218Y96869D01*
X816593Y96827D01*
X816968Y96911D01*
X817218Y97036D01*
X817468Y97286D01*
X817635Y97577D01*
X817718Y97869D01*
Y98161D01*
X817635Y98452D01*
X817510Y98702D01*
X817343Y98911D01*
G01X817718Y101469D02*
X815218D01*
X817010Y99927D01*
Y102011D01*
G01X816468Y104319D02*
Y105152D01*
X817218D01*
X817468Y104902D01*
X817635Y104611D01*
X817718Y104194D01*
X817635Y103777D01*
X817468Y103486D01*
X817218Y103236D01*
X816926Y103069D01*
X816593Y102986D01*
X816301D01*
X816051Y103069D01*
X815760Y103236D01*
X815510Y103486D01*
X815343Y103736D01*
X815218Y104069D01*
Y104361D01*
X815301Y104694D01*
X815468Y104944D01*
G01X817718Y107169D02*
X815218D01*
X815718Y106669D01*
G01X817718D02*
Y107669D01*
G01Y110269D02*
X815218D01*
X815718Y109769D01*
G01X817718D02*
Y110769D01*
G01X824873Y107627D02*
X824623Y107752D01*
X824331Y107835D01*
X823998D01*
X823623Y107710D01*
X823331Y107502D01*
X823123Y107252D01*
X822956Y106835D01*
X822914Y106460D01*
X822998Y106085D01*
X823123Y105835D01*
X823373Y105585D01*
X823664Y105418D01*
X823956Y105335D01*
X824248D01*
X824539Y105418D01*
X824789Y105543D01*
X824998Y105710D01*
G01X827556Y105335D02*
Y107835D01*
X826014Y106043D01*
X828098D01*
G01X830406Y106585D02*
X831239D01*
Y105835D01*
X830989Y105585D01*
X830698Y105418D01*
X830281Y105335D01*
X829864Y105418D01*
X829573Y105585D01*
X829323Y105835D01*
X829156Y106127D01*
X829073Y106460D01*
Y106752D01*
X829156Y107002D01*
X829323Y107293D01*
X829573Y107543D01*
X829823Y107710D01*
X830156Y107835D01*
X830448D01*
X830781Y107752D01*
X831031Y107585D01*
G01X833173Y105335D02*
X833256Y105877D01*
X833381Y106335D01*
X833548Y106752D01*
X833756Y107210D01*
X834089Y107835D01*
X832423D01*
G01X838108Y105267D02*
X837983Y105017D01*
X837900Y104725D01*
Y104392D01*
X838025Y104017D01*
X838233Y103725D01*
X838483Y103517D01*
X838900Y103350D01*
X839275Y103308D01*
X839650Y103392D01*
X839900Y103517D01*
X840150Y103767D01*
X840317Y104058D01*
X840400Y104350D01*
Y104642D01*
X840317Y104933D01*
X840192Y105183D01*
X840025Y105392D01*
G01X840400Y107950D02*
X837900D01*
X839692Y106408D01*
Y108492D01*
G01X839150Y110800D02*
Y111633D01*
X839900D01*
X840150Y111383D01*
X840317Y111092D01*
X840400Y110675D01*
X840317Y110258D01*
X840150Y109967D01*
X839900Y109717D01*
X839608Y109550D01*
X839275Y109467D01*
X838983D01*
X838733Y109550D01*
X838442Y109717D01*
X838192Y109967D01*
X838025Y110217D01*
X837900Y110550D01*
Y110842D01*
X837983Y111175D01*
X838150Y111425D01*
G01X840400Y113650D02*
X840358Y113942D01*
X840233Y114275D01*
X840025Y114483D01*
X839733Y114567D01*
X839442Y114483D01*
X839192Y114233D01*
X839067Y113858D01*
Y113442D01*
X838983Y113192D01*
X838775Y112983D01*
X838483Y112900D01*
X838192Y113025D01*
X837983Y113317D01*
X837900Y113650D01*
X837983Y113983D01*
X838192Y114275D01*
X838483Y114400D01*
X838775Y114317D01*
X838983Y114108D01*
X839067Y113858D01*
Y113442D01*
X839192Y113067D01*
X839442Y112817D01*
X839733Y112733D01*
X840025Y112817D01*
X840233Y113025D01*
X840358Y113358D01*
X840400Y113650D01*
G01X808626Y98786D02*
X808501Y98536D01*
X808418Y98244D01*
Y97911D01*
X808543Y97536D01*
X808751Y97244D01*
X809001Y97036D01*
X809418Y96869D01*
X809793Y96827D01*
X810168Y96911D01*
X810418Y97036D01*
X810668Y97286D01*
X810835Y97577D01*
X810918Y97869D01*
Y98161D01*
X810835Y98452D01*
X810710Y98702D01*
X810543Y98911D01*
G01X810918Y101469D02*
X808418D01*
X810210Y99927D01*
Y102011D01*
G01X809668Y104319D02*
Y105152D01*
X810418D01*
X810668Y104902D01*
X810835Y104611D01*
X810918Y104194D01*
X810835Y103777D01*
X810668Y103486D01*
X810418Y103236D01*
X810126Y103069D01*
X809793Y102986D01*
X809501D01*
X809251Y103069D01*
X808960Y103236D01*
X808710Y103486D01*
X808543Y103736D01*
X808418Y104069D01*
Y104361D01*
X808501Y104694D01*
X808668Y104944D01*
G01X810918Y107169D02*
X808418D01*
X808918Y106669D01*
G01X810918D02*
Y107669D01*
G01X808835Y109477D02*
X808585Y109727D01*
X808460Y110019D01*
X808418Y110352D01*
X808501Y110769D01*
X808710Y111061D01*
X808960Y111144D01*
X809210Y111102D01*
X809418Y110936D01*
X809835Y110102D01*
X810126Y109727D01*
X810543Y109477D01*
X810918Y109394D01*
Y111144D01*
G01X788540Y113250D02*
X790240D01*
Y129750D01*
X788540D01*
G01Y158000D02*
X803240D01*
Y121000D01*
G01D02*
X800240Y117500D01*
X790240D01*
G01X831900Y186600D02*
Y190999D01*
X831901Y191000D01*
X843099D01*
X843100Y191001D01*
Y206899D01*
X843101Y206900D01*
X853599D01*
X853600Y206901D01*
Y244300D01*
X859900D01*
Y254200D01*
X867800D01*
G01X831900Y161800D02*
Y175600D01*
G01X827349Y194184D02*
Y196684D01*
X828390D01*
X828724Y196559D01*
X828932Y196392D01*
X829015Y196059D01*
X828932Y195726D01*
X828682Y195517D01*
X828390Y195392D01*
X827349D01*
G01X828390D02*
X829015Y194184D01*
G01X831782D02*
Y196684D01*
X830240Y194892D01*
X832324D01*
G01X835215Y194184D02*
X833549D01*
Y196684D01*
X835215D01*
G01X834549Y195476D02*
X833549D01*
G01X837482Y194184D02*
Y196684D01*
X836982Y196184D01*
G01Y194184D02*
X837982D01*
G01X840499D02*
X840582Y194726D01*
X840707Y195184D01*
X840874Y195601D01*
X841082Y196059D01*
X841415Y196684D01*
X839749D01*
G01X796851Y182208D02*
X794351D01*
Y183249D01*
X794476Y183583D01*
X794643Y183791D01*
X794976Y183874D01*
X795309Y183791D01*
X795518Y183541D01*
X795643Y183249D01*
Y182208D01*
G01Y183249D02*
X796851Y183874D01*
G01Y186641D02*
X794351D01*
X796143Y185099D01*
Y187183D01*
G01X796851Y190074D02*
Y188408D01*
X794351D01*
Y190074D01*
G01X795559Y189408D02*
Y188408D01*
G01X796851Y192341D02*
X794351D01*
X794851Y191841D01*
G01X796851D02*
Y192841D01*
G01X796476Y194524D02*
X796684Y194774D01*
X796809Y195066D01*
X796851Y195441D01*
X796768Y195816D01*
X796601Y196108D01*
X796309Y196316D01*
X795976Y196358D01*
X795643Y196274D01*
X795434Y196066D01*
X795268Y195774D01*
X795226Y195483D01*
X795268Y195191D01*
X795434Y194816D01*
X794351Y194941D01*
Y196066D01*
G01X827467Y197767D02*
Y200267D01*
X828508D01*
X828842Y200142D01*
X829050Y199975D01*
X829133Y199642D01*
X829050Y199309D01*
X828800Y199100D01*
X828508Y198975D01*
X827467D01*
G01X828508D02*
X829133Y197767D01*
G01X831900D02*
Y200267D01*
X830358Y198475D01*
X832442D01*
G01X835333Y197767D02*
X833667D01*
Y200267D01*
X835333D01*
G01X834667Y199059D02*
X833667D01*
G01X837600Y197767D02*
Y200267D01*
X837100Y199767D01*
G01Y197767D02*
X838100D01*
G01X839908Y198809D02*
X840200Y199100D01*
X840450Y199267D01*
X840783Y199350D01*
X841075Y199267D01*
X841283Y199100D01*
X841450Y198850D01*
X841492Y198559D01*
X841450Y198309D01*
X841283Y198059D01*
X841033Y197850D01*
X840742Y197767D01*
X840408Y197850D01*
X840117Y198100D01*
X839950Y198475D01*
X839908Y198892D01*
X839992Y199434D01*
X840117Y199725D01*
X840325Y200017D01*
X840617Y200225D01*
X840908Y200267D01*
X841200Y200184D01*
X841408Y199975D01*
G01X828001Y202071D02*
Y204571D01*
X829042D01*
X829376Y204446D01*
X829584Y204279D01*
X829667Y203946D01*
X829584Y203613D01*
X829334Y203404D01*
X829042Y203279D01*
X828001D01*
G01X829042D02*
X829667Y202071D01*
G01X831017Y202446D02*
X831267Y202238D01*
X831559Y202113D01*
X831934Y202071D01*
X832309Y202154D01*
X832601Y202321D01*
X832809Y202613D01*
X832851Y202946D01*
X832767Y203279D01*
X832559Y203488D01*
X832267Y203654D01*
X831976Y203696D01*
X831684Y203654D01*
X831309Y203488D01*
X831434Y204571D01*
X832559D01*
G01X834201Y202071D02*
Y204571D01*
X835201D01*
X835534Y204446D01*
X835784Y204154D01*
X835867Y203821D01*
X835784Y203488D01*
X835576Y203238D01*
X835201Y203113D01*
X834201D01*
G01X838134Y202071D02*
Y204571D01*
X837634Y204071D01*
G01Y202071D02*
X838634D01*
G01X826816Y206582D02*
Y209082D01*
X827857D01*
X828191Y208957D01*
X828399Y208790D01*
X828482Y208457D01*
X828399Y208124D01*
X828149Y207915D01*
X827857Y207790D01*
X826816D01*
G01X827857D02*
X828482Y206582D01*
G01X831249D02*
Y209082D01*
X829707Y207290D01*
X831791D01*
G01X834682Y206582D02*
X833016D01*
Y209082D01*
X834682D01*
G01X834016Y207874D02*
X833016D01*
G01X836949Y206582D02*
Y209082D01*
X836449Y208582D01*
G01Y206582D02*
X837449D01*
G01X839132Y207082D02*
X839382Y206790D01*
X839716Y206624D01*
X840091Y206582D01*
X840424Y206624D01*
X840757Y206832D01*
X840966Y207082D01*
X841007Y207332D01*
X840924Y207624D01*
X840632Y207832D01*
X840341Y207915D01*
X839966D01*
G01X840341D02*
X840591Y208040D01*
X840799Y208249D01*
X840882Y208499D01*
X840799Y208749D01*
X840591Y208957D01*
X840216Y209082D01*
X839841Y209040D01*
X839466Y208874D01*
G01X845408Y159817D02*
X845283Y159567D01*
X845200Y159275D01*
Y158942D01*
X845325Y158567D01*
X845533Y158275D01*
X845783Y158067D01*
X846200Y157900D01*
X846575Y157858D01*
X846950Y157942D01*
X847200Y158067D01*
X847450Y158317D01*
X847617Y158608D01*
X847700Y158900D01*
Y159192D01*
X847617Y159483D01*
X847492Y159733D01*
X847325Y159942D01*
G01Y161083D02*
X847533Y161333D01*
X847658Y161625D01*
X847700Y162000D01*
X847617Y162375D01*
X847450Y162667D01*
X847158Y162875D01*
X846825Y162917D01*
X846492Y162833D01*
X846283Y162625D01*
X846117Y162333D01*
X846075Y162042D01*
X846117Y161750D01*
X846283Y161375D01*
X845200Y161500D01*
Y162625D01*
G01X847700Y164183D02*
X845200D01*
Y165017D01*
X845325Y165350D01*
X845492Y165600D01*
X845742Y165808D01*
X846033Y165975D01*
X846450Y166017D01*
X846867Y165975D01*
X847158Y165808D01*
X847408Y165600D01*
X847575Y165350D01*
X847700Y165017D01*
Y164183D01*
G01X845617Y167408D02*
X845367Y167658D01*
X845242Y167950D01*
X845200Y168283D01*
X845283Y168700D01*
X845492Y168992D01*
X845742Y169075D01*
X845992Y169033D01*
X846200Y168867D01*
X846617Y168033D01*
X846908Y167658D01*
X847325Y167408D01*
X847700Y167325D01*
Y169075D01*
G01Y171217D02*
X847158Y171300D01*
X846700Y171425D01*
X846283Y171592D01*
X845825Y171800D01*
X845200Y172133D01*
Y170467D01*
G01X837964Y176893D02*
X837839Y176643D01*
X837756Y176351D01*
Y176018D01*
X837881Y175643D01*
X838089Y175351D01*
X838339Y175143D01*
X838756Y174976D01*
X839131Y174934D01*
X839506Y175018D01*
X839756Y175143D01*
X840006Y175393D01*
X840173Y175684D01*
X840256Y175976D01*
Y176268D01*
X840173Y176559D01*
X840048Y176809D01*
X839881Y177018D01*
G01Y178159D02*
X840089Y178409D01*
X840214Y178701D01*
X840256Y179076D01*
X840173Y179451D01*
X840006Y179743D01*
X839714Y179951D01*
X839381Y179993D01*
X839048Y179909D01*
X838839Y179701D01*
X838673Y179409D01*
X838631Y179118D01*
X838673Y178826D01*
X838839Y178451D01*
X837756Y178576D01*
Y179701D01*
G01X840256Y181259D02*
X837756D01*
Y182093D01*
X837881Y182426D01*
X838048Y182676D01*
X838298Y182884D01*
X838589Y183051D01*
X839006Y183093D01*
X839423Y183051D01*
X839714Y182884D01*
X839964Y182676D01*
X840131Y182426D01*
X840256Y182093D01*
Y181259D01*
G01Y185276D02*
X837756D01*
X838256Y184776D01*
G01X840256D02*
Y185776D01*
G01Y188376D02*
X837756D01*
X838256Y187876D01*
G01X840256D02*
Y188876D01*
G01X841364Y176893D02*
X841239Y176643D01*
X841156Y176351D01*
Y176018D01*
X841281Y175643D01*
X841489Y175351D01*
X841739Y175143D01*
X842156Y174976D01*
X842531Y174934D01*
X842906Y175018D01*
X843156Y175143D01*
X843406Y175393D01*
X843573Y175684D01*
X843656Y175976D01*
Y176268D01*
X843573Y176559D01*
X843448Y176809D01*
X843281Y177018D01*
G01Y178159D02*
X843489Y178409D01*
X843614Y178701D01*
X843656Y179076D01*
X843573Y179451D01*
X843406Y179743D01*
X843114Y179951D01*
X842781Y179993D01*
X842448Y179909D01*
X842239Y179701D01*
X842073Y179409D01*
X842031Y179118D01*
X842073Y178826D01*
X842239Y178451D01*
X841156Y178576D01*
Y179701D01*
G01X843656Y181259D02*
X841156D01*
Y182093D01*
X841281Y182426D01*
X841448Y182676D01*
X841698Y182884D01*
X841989Y183051D01*
X842406Y183093D01*
X842823Y183051D01*
X843114Y182884D01*
X843364Y182676D01*
X843531Y182426D01*
X843656Y182093D01*
Y181259D01*
G01Y185276D02*
X841156D01*
X841656Y184776D01*
G01X843656D02*
Y185776D01*
G01X841573Y187584D02*
X841323Y187834D01*
X841198Y188126D01*
X841156Y188459D01*
X841239Y188876D01*
X841448Y189168D01*
X841698Y189251D01*
X841948Y189209D01*
X842156Y189043D01*
X842573Y188209D01*
X842864Y187834D01*
X843281Y187584D01*
X843656Y187501D01*
Y189251D01*
G01X834564Y176893D02*
X834439Y176643D01*
X834356Y176351D01*
Y176018D01*
X834481Y175643D01*
X834689Y175351D01*
X834939Y175143D01*
X835356Y174976D01*
X835731Y174934D01*
X836106Y175018D01*
X836356Y175143D01*
X836606Y175393D01*
X836773Y175684D01*
X836856Y175976D01*
Y176268D01*
X836773Y176559D01*
X836648Y176809D01*
X836481Y177018D01*
G01Y178159D02*
X836689Y178409D01*
X836814Y178701D01*
X836856Y179076D01*
X836773Y179451D01*
X836606Y179743D01*
X836314Y179951D01*
X835981Y179993D01*
X835648Y179909D01*
X835439Y179701D01*
X835273Y179409D01*
X835231Y179118D01*
X835273Y178826D01*
X835439Y178451D01*
X834356Y178576D01*
Y179701D01*
G01X836856Y181259D02*
X834356D01*
Y182093D01*
X834481Y182426D01*
X834648Y182676D01*
X834898Y182884D01*
X835189Y183051D01*
X835606Y183093D01*
X836023Y183051D01*
X836314Y182884D01*
X836564Y182676D01*
X836731Y182426D01*
X836856Y182093D01*
Y181259D01*
G01Y185276D02*
X834356D01*
X834856Y184776D01*
G01X836856D02*
Y185776D01*
G01X836356Y187459D02*
X836648Y187709D01*
X836814Y188043D01*
X836856Y188418D01*
X836814Y188751D01*
X836606Y189084D01*
X836356Y189293D01*
X836106Y189334D01*
X835814Y189251D01*
X835606Y188959D01*
X835523Y188668D01*
Y188293D01*
G01Y188668D02*
X835398Y188918D01*
X835189Y189126D01*
X834939Y189209D01*
X834689Y189126D01*
X834481Y188918D01*
X834356Y188543D01*
X834398Y188168D01*
X834564Y187793D01*
G01X844808Y177017D02*
X844683Y176767D01*
X844600Y176475D01*
Y176142D01*
X844725Y175767D01*
X844933Y175475D01*
X845183Y175267D01*
X845600Y175100D01*
X845975Y175058D01*
X846350Y175142D01*
X846600Y175267D01*
X846850Y175517D01*
X847017Y175808D01*
X847100Y176100D01*
Y176392D01*
X847017Y176683D01*
X846892Y176933D01*
X846725Y177142D01*
G01Y178283D02*
X846933Y178533D01*
X847058Y178825D01*
X847100Y179200D01*
X847017Y179575D01*
X846850Y179867D01*
X846558Y180075D01*
X846225Y180117D01*
X845892Y180033D01*
X845683Y179825D01*
X845517Y179533D01*
X845475Y179242D01*
X845517Y178950D01*
X845683Y178575D01*
X844600Y178700D01*
Y179825D01*
G01X847100Y181383D02*
X844600D01*
Y182217D01*
X844725Y182550D01*
X844892Y182800D01*
X845142Y183008D01*
X845433Y183175D01*
X845850Y183217D01*
X846267Y183175D01*
X846558Y183008D01*
X846808Y182800D01*
X846975Y182550D01*
X847100Y182217D01*
Y181383D01*
G01Y185400D02*
X844600D01*
X845100Y184900D01*
G01X847100D02*
Y185900D01*
G01Y189000D02*
X844600D01*
X846392Y187458D01*
Y189542D01*
G01X848108Y177017D02*
X847983Y176767D01*
X847900Y176475D01*
Y176142D01*
X848025Y175767D01*
X848233Y175475D01*
X848483Y175267D01*
X848900Y175100D01*
X849275Y175058D01*
X849650Y175142D01*
X849900Y175267D01*
X850150Y175517D01*
X850317Y175808D01*
X850400Y176100D01*
Y176392D01*
X850317Y176683D01*
X850192Y176933D01*
X850025Y177142D01*
G01Y178283D02*
X850233Y178533D01*
X850358Y178825D01*
X850400Y179200D01*
X850317Y179575D01*
X850150Y179867D01*
X849858Y180075D01*
X849525Y180117D01*
X849192Y180033D01*
X848983Y179825D01*
X848817Y179533D01*
X848775Y179242D01*
X848817Y178950D01*
X848983Y178575D01*
X847900Y178700D01*
Y179825D01*
G01X850400Y181383D02*
X847900D01*
Y182217D01*
X848025Y182550D01*
X848192Y182800D01*
X848442Y183008D01*
X848733Y183175D01*
X849150Y183217D01*
X849567Y183175D01*
X849858Y183008D01*
X850108Y182800D01*
X850275Y182550D01*
X850400Y182217D01*
Y181383D01*
G01Y185400D02*
X847900D01*
X848400Y184900D01*
G01X850400D02*
Y185900D01*
G01X850025Y187583D02*
X850233Y187833D01*
X850358Y188125D01*
X850400Y188500D01*
X850317Y188875D01*
X850150Y189167D01*
X849858Y189375D01*
X849525Y189417D01*
X849192Y189333D01*
X848983Y189125D01*
X848817Y188833D01*
X848775Y188542D01*
X848817Y188250D01*
X848983Y187875D01*
X847900Y188000D01*
Y189125D01*
G01X848008Y193017D02*
X847883Y192767D01*
X847800Y192475D01*
Y192142D01*
X847925Y191767D01*
X848133Y191475D01*
X848383Y191267D01*
X848800Y191100D01*
X849175Y191058D01*
X849550Y191142D01*
X849800Y191267D01*
X850050Y191517D01*
X850217Y191808D01*
X850300Y192100D01*
Y192392D01*
X850217Y192683D01*
X850092Y192933D01*
X849925Y193142D01*
G01Y194283D02*
X850133Y194533D01*
X850258Y194825D01*
X850300Y195200D01*
X850217Y195575D01*
X850050Y195867D01*
X849758Y196075D01*
X849425Y196117D01*
X849092Y196033D01*
X848883Y195825D01*
X848717Y195533D01*
X848675Y195242D01*
X848717Y194950D01*
X848883Y194575D01*
X847800Y194700D01*
Y195825D01*
G01X850300Y197383D02*
X847800D01*
Y198217D01*
X847925Y198550D01*
X848092Y198800D01*
X848342Y199008D01*
X848633Y199175D01*
X849050Y199217D01*
X849467Y199175D01*
X849758Y199008D01*
X850008Y198800D01*
X850175Y198550D01*
X850300Y198217D01*
Y197383D01*
G01X850008Y200692D02*
X850217Y200983D01*
X850300Y201317D01*
X850217Y201650D01*
X849967Y201942D01*
X849592Y202150D01*
X849217Y202233D01*
X848758D01*
X848383Y202150D01*
X848050Y201942D01*
X847883Y201692D01*
X847800Y201400D01*
X847883Y201067D01*
X848050Y200817D01*
X848300Y200650D01*
X848633Y200567D01*
X848925Y200650D01*
X849217Y200858D01*
X849383Y201108D01*
X849425Y201400D01*
X849342Y201733D01*
X849133Y201983D01*
X848758Y202233D01*
G01X844608Y193017D02*
X844483Y192767D01*
X844400Y192475D01*
Y192142D01*
X844525Y191767D01*
X844733Y191475D01*
X844983Y191267D01*
X845400Y191100D01*
X845775Y191058D01*
X846150Y191142D01*
X846400Y191267D01*
X846650Y191517D01*
X846817Y191808D01*
X846900Y192100D01*
Y192392D01*
X846817Y192683D01*
X846692Y192933D01*
X846525Y193142D01*
G01Y194283D02*
X846733Y194533D01*
X846858Y194825D01*
X846900Y195200D01*
X846817Y195575D01*
X846650Y195867D01*
X846358Y196075D01*
X846025Y196117D01*
X845692Y196033D01*
X845483Y195825D01*
X845317Y195533D01*
X845275Y195242D01*
X845317Y194950D01*
X845483Y194575D01*
X844400Y194700D01*
Y195825D01*
G01X846900Y197383D02*
X844400D01*
Y198217D01*
X844525Y198550D01*
X844692Y198800D01*
X844942Y199008D01*
X845233Y199175D01*
X845650Y199217D01*
X846067Y199175D01*
X846358Y199008D01*
X846608Y198800D01*
X846775Y198550D01*
X846900Y198217D01*
Y197383D01*
G01Y201400D02*
X844400D01*
X844900Y200900D01*
G01X846900D02*
Y201900D01*
G01X844400Y204500D02*
X844483Y204167D01*
X844692Y203917D01*
X844942Y203750D01*
X845275Y203625D01*
X845650Y203583D01*
X846025Y203625D01*
X846358Y203750D01*
X846608Y203917D01*
X846817Y204167D01*
X846900Y204500D01*
X846817Y204833D01*
X846608Y205083D01*
X846358Y205250D01*
X846025Y205375D01*
X845650Y205417D01*
X845275Y205375D01*
X844942Y205250D01*
X844692Y205083D01*
X844483Y204833D01*
X844400Y204500D01*
G01X835208Y159817D02*
X835083Y159567D01*
X835000Y159275D01*
Y158942D01*
X835125Y158567D01*
X835333Y158275D01*
X835583Y158067D01*
X836000Y157900D01*
X836375Y157858D01*
X836750Y157942D01*
X837000Y158067D01*
X837250Y158317D01*
X837417Y158608D01*
X837500Y158900D01*
Y159192D01*
X837417Y159483D01*
X837292Y159733D01*
X837125Y159942D01*
G01Y161083D02*
X837333Y161333D01*
X837458Y161625D01*
X837500Y162000D01*
X837417Y162375D01*
X837250Y162667D01*
X836958Y162875D01*
X836625Y162917D01*
X836292Y162833D01*
X836083Y162625D01*
X835917Y162333D01*
X835875Y162042D01*
X835917Y161750D01*
X836083Y161375D01*
X835000Y161500D01*
Y162625D01*
G01X837500Y164183D02*
X835000D01*
Y165017D01*
X835125Y165350D01*
X835292Y165600D01*
X835542Y165808D01*
X835833Y165975D01*
X836250Y166017D01*
X836667Y165975D01*
X836958Y165808D01*
X837208Y165600D01*
X837375Y165350D01*
X837500Y165017D01*
Y164183D01*
G01X835417Y167408D02*
X835167Y167658D01*
X835042Y167950D01*
X835000Y168283D01*
X835083Y168700D01*
X835292Y168992D01*
X835542Y169075D01*
X835792Y169033D01*
X836000Y168867D01*
X836417Y168033D01*
X836708Y167658D01*
X837125Y167408D01*
X837500Y167325D01*
Y169075D01*
G01Y171800D02*
X835000D01*
X836792Y170258D01*
Y172342D01*
G01X842008Y159817D02*
X841883Y159567D01*
X841800Y159275D01*
Y158942D01*
X841925Y158567D01*
X842133Y158275D01*
X842383Y158067D01*
X842800Y157900D01*
X843175Y157858D01*
X843550Y157942D01*
X843800Y158067D01*
X844050Y158317D01*
X844217Y158608D01*
X844300Y158900D01*
Y159192D01*
X844217Y159483D01*
X844092Y159733D01*
X843925Y159942D01*
G01Y161083D02*
X844133Y161333D01*
X844258Y161625D01*
X844300Y162000D01*
X844217Y162375D01*
X844050Y162667D01*
X843758Y162875D01*
X843425Y162917D01*
X843092Y162833D01*
X842883Y162625D01*
X842717Y162333D01*
X842675Y162042D01*
X842717Y161750D01*
X842883Y161375D01*
X841800Y161500D01*
Y162625D01*
G01X844300Y164183D02*
X841800D01*
Y165017D01*
X841925Y165350D01*
X842092Y165600D01*
X842342Y165808D01*
X842633Y165975D01*
X843050Y166017D01*
X843467Y165975D01*
X843758Y165808D01*
X844008Y165600D01*
X844175Y165350D01*
X844300Y165017D01*
Y164183D01*
G01X842217Y167408D02*
X841967Y167658D01*
X841842Y167950D01*
X841800Y168283D01*
X841883Y168700D01*
X842092Y168992D01*
X842342Y169075D01*
X842592Y169033D01*
X842800Y168867D01*
X843217Y168033D01*
X843508Y167658D01*
X843925Y167408D01*
X844300Y167325D01*
Y169075D01*
G01X843258Y170508D02*
X842967Y170800D01*
X842800Y171050D01*
X842717Y171383D01*
X842800Y171675D01*
X842967Y171883D01*
X843217Y172050D01*
X843508Y172092D01*
X843758Y172050D01*
X844008Y171883D01*
X844217Y171633D01*
X844300Y171342D01*
X844217Y171008D01*
X843967Y170717D01*
X843592Y170550D01*
X843175Y170508D01*
X842633Y170592D01*
X842342Y170717D01*
X842050Y170925D01*
X841842Y171217D01*
X841800Y171508D01*
X841883Y171800D01*
X842092Y172008D01*
G01X838608Y159817D02*
X838483Y159567D01*
X838400Y159275D01*
Y158942D01*
X838525Y158567D01*
X838733Y158275D01*
X838983Y158067D01*
X839400Y157900D01*
X839775Y157858D01*
X840150Y157942D01*
X840400Y158067D01*
X840650Y158317D01*
X840817Y158608D01*
X840900Y158900D01*
Y159192D01*
X840817Y159483D01*
X840692Y159733D01*
X840525Y159942D01*
G01Y161083D02*
X840733Y161333D01*
X840858Y161625D01*
X840900Y162000D01*
X840817Y162375D01*
X840650Y162667D01*
X840358Y162875D01*
X840025Y162917D01*
X839692Y162833D01*
X839483Y162625D01*
X839317Y162333D01*
X839275Y162042D01*
X839317Y161750D01*
X839483Y161375D01*
X838400Y161500D01*
Y162625D01*
G01X840900Y164183D02*
X838400D01*
Y165017D01*
X838525Y165350D01*
X838692Y165600D01*
X838942Y165808D01*
X839233Y165975D01*
X839650Y166017D01*
X840067Y165975D01*
X840358Y165808D01*
X840608Y165600D01*
X840775Y165350D01*
X840900Y165017D01*
Y164183D01*
G01X838817Y167408D02*
X838567Y167658D01*
X838442Y167950D01*
X838400Y168283D01*
X838483Y168700D01*
X838692Y168992D01*
X838942Y169075D01*
X839192Y169033D01*
X839400Y168867D01*
X839817Y168033D01*
X840108Y167658D01*
X840525Y167408D01*
X840900Y167325D01*
Y169075D01*
G01X840525Y170383D02*
X840733Y170633D01*
X840858Y170925D01*
X840900Y171300D01*
X840817Y171675D01*
X840650Y171967D01*
X840358Y172175D01*
X840025Y172217D01*
X839692Y172133D01*
X839483Y171925D01*
X839317Y171633D01*
X839275Y171342D01*
X839317Y171050D01*
X839483Y170675D01*
X838400Y170800D01*
Y171925D01*
G01X807943Y209759D02*
X807693Y209884D01*
X807401Y209967D01*
X807068D01*
X806693Y209842D01*
X806401Y209634D01*
X806193Y209384D01*
X806026Y208967D01*
X805984Y208592D01*
X806068Y208217D01*
X806193Y207967D01*
X806443Y207717D01*
X806734Y207550D01*
X807026Y207467D01*
X807318D01*
X807609Y207550D01*
X807859Y207675D01*
X808068Y207842D01*
G01X810126Y209967D02*
Y207467D01*
G01X809168Y209967D02*
X811084D01*
G01X812309Y207967D02*
X812559Y207675D01*
X812893Y207509D01*
X813268Y207467D01*
X813601Y207509D01*
X813934Y207717D01*
X814143Y207967D01*
X814184Y208217D01*
X814101Y208509D01*
X813809Y208717D01*
X813518Y208800D01*
X813143D01*
G01X813518D02*
X813768Y208925D01*
X813976Y209134D01*
X814059Y209384D01*
X813976Y209634D01*
X813768Y209842D01*
X813393Y209967D01*
X813018Y209925D01*
X812643Y209759D01*
G01X843833Y210617D02*
X846333D01*
Y212283D01*
G01Y215050D02*
X843833D01*
X845625Y213508D01*
Y215592D01*
G01X846333Y218483D02*
Y216817D01*
X843833D01*
Y218483D01*
G01X845041Y217817D02*
Y216817D01*
G01X846333Y220750D02*
X843833D01*
X844333Y220250D01*
G01X846333D02*
Y221250D01*
G01X840182Y217983D02*
Y211935D01*
X802782D01*
Y217983D01*
G01X846775Y251664D02*
X844275D01*
Y252705D01*
X844400Y253039D01*
X844567Y253247D01*
X844900Y253330D01*
X845233Y253247D01*
X845442Y252997D01*
X845567Y252705D01*
Y251664D01*
G01Y252705D02*
X846775Y253330D01*
G01Y256097D02*
X844275D01*
X846067Y254555D01*
Y256639D01*
G01X846775Y259530D02*
Y257864D01*
X844275D01*
Y259530D01*
G01X845483Y258864D02*
Y257864D01*
G01X846775Y261797D02*
X844275D01*
X844775Y261297D01*
G01X846775D02*
Y262297D01*
G01X846483Y264189D02*
X846692Y264480D01*
X846775Y264814D01*
X846692Y265147D01*
X846442Y265439D01*
X846067Y265647D01*
X845692Y265730D01*
X845233D01*
X844858Y265647D01*
X844525Y265439D01*
X844358Y265189D01*
X844275Y264897D01*
X844358Y264564D01*
X844525Y264314D01*
X844775Y264147D01*
X845108Y264064D01*
X845400Y264147D01*
X845692Y264355D01*
X845858Y264605D01*
X845900Y264897D01*
X845817Y265230D01*
X845608Y265480D01*
X845233Y265730D01*
G01X848463Y262234D02*
Y264734D01*
X849504D01*
X849838Y264609D01*
X850046Y264442D01*
X850129Y264109D01*
X850046Y263776D01*
X849796Y263567D01*
X849504Y263442D01*
X848463D01*
G01X849504D02*
X850129Y262234D01*
G01X852396Y264734D02*
Y262234D01*
G01X851438Y264734D02*
X853354D01*
G01X854579Y262734D02*
X854829Y262442D01*
X855163Y262276D01*
X855538Y262234D01*
X855871Y262276D01*
X856204Y262484D01*
X856413Y262734D01*
X856454Y262984D01*
X856371Y263276D01*
X856079Y263484D01*
X855788Y263567D01*
X855413D01*
G01X855788D02*
X856038Y263692D01*
X856246Y263901D01*
X856329Y264151D01*
X856246Y264401D01*
X856038Y264609D01*
X855663Y264734D01*
X855288Y264692D01*
X854913Y264526D01*
G01X847820Y254746D02*
X847695Y254496D01*
X847612Y254204D01*
Y253871D01*
X847737Y253496D01*
X847945Y253204D01*
X848195Y252996D01*
X848612Y252829D01*
X848987Y252787D01*
X849362Y252871D01*
X849612Y252996D01*
X849862Y253246D01*
X850029Y253537D01*
X850112Y253829D01*
Y254121D01*
X850029Y254412D01*
X849904Y254662D01*
X849737Y254871D01*
G01X847612Y256929D02*
X850112D01*
G01X847612Y255971D02*
Y257887D01*
G01X849070Y259237D02*
X848779Y259529D01*
X848612Y259779D01*
X848529Y260112D01*
X848612Y260404D01*
X848779Y260612D01*
X849029Y260779D01*
X849320Y260821D01*
X849570Y260779D01*
X849820Y260612D01*
X850029Y260362D01*
X850112Y260071D01*
X850029Y259737D01*
X849779Y259446D01*
X849404Y259279D01*
X848987Y259237D01*
X848445Y259321D01*
X848154Y259446D01*
X847862Y259654D01*
X847654Y259946D01*
X847612Y260237D01*
X847695Y260529D01*
X847904Y260737D01*
G01X840182Y249983D02*
Y243935D01*
X802782D01*
Y249983D01*
G01Y263083D02*
Y269131D01*
G01D02*
X840182D01*
Y263083D01*
G01X802782Y231083D02*
Y237131D01*
G01D02*
X840182D01*
Y231083D01*
G01Y281983D02*
Y275935D01*
X802782D01*
Y281983D01*
G01X843830Y319481D02*
Y321981D01*
X844871D01*
X845205Y321856D01*
X845413Y321689D01*
X845496Y321356D01*
X845413Y321023D01*
X845163Y320814D01*
X844871Y320689D01*
X843830D01*
G01X844871D02*
X845496Y319481D01*
G01X848263D02*
Y321981D01*
X846721Y320189D01*
X848805D01*
G01X849946Y319481D02*
Y321981D01*
X850780D01*
X851113Y321856D01*
X851363Y321689D01*
X851571Y321439D01*
X851738Y321148D01*
X851780Y320731D01*
X851738Y320314D01*
X851571Y320023D01*
X851363Y319773D01*
X851113Y319606D01*
X850780Y319481D01*
X849946D01*
G01X853880D02*
X853963Y320023D01*
X854088Y320481D01*
X854255Y320898D01*
X854463Y321356D01*
X854796Y321981D01*
X853130D01*
G01X857063Y319481D02*
Y321981D01*
X856563Y321481D01*
G01Y319481D02*
X857563D01*
G01X843930Y323181D02*
Y325681D01*
X844971D01*
X845305Y325556D01*
X845513Y325389D01*
X845596Y325056D01*
X845513Y324723D01*
X845263Y324514D01*
X844971Y324389D01*
X843930D01*
G01X844971D02*
X845596Y323181D01*
G01X847863Y325681D02*
Y323181D01*
G01X846905Y325681D02*
X848821D01*
G01X850171Y325264D02*
X850421Y325514D01*
X850713Y325639D01*
X851046Y325681D01*
X851463Y325598D01*
X851755Y325389D01*
X851838Y325139D01*
X851796Y324889D01*
X851630Y324681D01*
X850796Y324264D01*
X850421Y323973D01*
X850171Y323556D01*
X850088Y323181D01*
X851838D01*
G01X854063D02*
X854355Y323223D01*
X854688Y323348D01*
X854896Y323556D01*
X854980Y323848D01*
X854896Y324139D01*
X854646Y324389D01*
X854271Y324514D01*
X853855D01*
X853605Y324598D01*
X853396Y324806D01*
X853313Y325098D01*
X853438Y325389D01*
X853730Y325598D01*
X854063Y325681D01*
X854396Y325598D01*
X854688Y325389D01*
X854813Y325098D01*
X854730Y324806D01*
X854521Y324598D01*
X854271Y324514D01*
X853855D01*
X853480Y324389D01*
X853230Y324139D01*
X853146Y323848D01*
X853230Y323556D01*
X853438Y323348D01*
X853771Y323223D01*
X854063Y323181D01*
G01X844633Y291740D02*
Y294240D01*
X845674D01*
X846008Y294115D01*
X846216Y293948D01*
X846299Y293615D01*
X846216Y293282D01*
X845966Y293073D01*
X845674Y292948D01*
X844633D01*
G01X845674D02*
X846299Y291740D01*
G01X848566Y294240D02*
Y291740D01*
G01X847608Y294240D02*
X849524D01*
G01X850874Y293823D02*
X851124Y294073D01*
X851416Y294198D01*
X851749Y294240D01*
X852166Y294157D01*
X852458Y293948D01*
X852541Y293698D01*
X852499Y293448D01*
X852333Y293240D01*
X851499Y292823D01*
X851124Y292532D01*
X850874Y292115D01*
X850791Y291740D01*
X852541D01*
G01X853849Y292115D02*
X854099Y291907D01*
X854391Y291782D01*
X854766Y291740D01*
X855141Y291823D01*
X855433Y291990D01*
X855641Y292282D01*
X855683Y292615D01*
X855599Y292948D01*
X855391Y293157D01*
X855099Y293323D01*
X854808Y293365D01*
X854516Y293323D01*
X854141Y293157D01*
X854266Y294240D01*
X855391D01*
G01X802782Y295083D02*
Y301131D01*
G01D02*
X840182D01*
Y295083D01*
G01Y313983D02*
Y307935D01*
X802782D01*
Y313983D01*
G01Y327083D02*
Y333131D01*
G01D02*
X840182D01*
Y327083D01*
G01Y344983D02*
Y338935D01*
X802782D01*
Y344983D01*
G01X846185Y345942D02*
X843685D01*
Y346983D01*
X843810Y347317D01*
X843977Y347525D01*
X844310Y347608D01*
X844643Y347525D01*
X844852Y347275D01*
X844977Y346983D01*
Y345942D01*
G01Y346983D02*
X846185Y347608D01*
G01Y350375D02*
X843685D01*
X845477Y348833D01*
Y350917D01*
G01X846185Y352058D02*
X843685D01*
Y352892D01*
X843810Y353225D01*
X843977Y353475D01*
X844227Y353683D01*
X844518Y353850D01*
X844935Y353892D01*
X845352Y353850D01*
X845643Y353683D01*
X845893Y353475D01*
X846060Y353225D01*
X846185Y352892D01*
Y352058D01*
G01X845143Y355283D02*
X844852Y355575D01*
X844685Y355825D01*
X844602Y356158D01*
X844685Y356450D01*
X844852Y356658D01*
X845102Y356825D01*
X845393Y356867D01*
X845643Y356825D01*
X845893Y356658D01*
X846102Y356408D01*
X846185Y356117D01*
X846102Y355783D01*
X845852Y355492D01*
X845477Y355325D01*
X845060Y355283D01*
X844518Y355367D01*
X844227Y355492D01*
X843935Y355700D01*
X843727Y355992D01*
X843685Y356283D01*
X843768Y356575D01*
X843977Y356783D01*
G01X846185Y359175D02*
X846143Y359467D01*
X846018Y359800D01*
X845810Y360008D01*
X845518Y360092D01*
X845227Y360008D01*
X844977Y359758D01*
X844852Y359383D01*
Y358967D01*
X844768Y358717D01*
X844560Y358508D01*
X844268Y358425D01*
X843977Y358550D01*
X843768Y358842D01*
X843685Y359175D01*
X843768Y359508D01*
X843977Y359800D01*
X844268Y359925D01*
X844560Y359842D01*
X844768Y359633D01*
X844852Y359383D01*
Y358967D01*
X844977Y358592D01*
X845227Y358342D01*
X845518Y358258D01*
X845810Y358342D01*
X846018Y358550D01*
X846143Y358883D01*
X846185Y359175D01*
G01X803883Y400486D02*
X801383D01*
Y401527D01*
X801508Y401861D01*
X801675Y402069D01*
X802008Y402152D01*
X802341Y402069D01*
X802550Y401819D01*
X802675Y401527D01*
Y400486D01*
G01Y401527D02*
X803883Y402152D01*
G01Y404919D02*
X801383D01*
X803175Y403377D01*
Y405461D01*
G01X801591Y408436D02*
X801466Y408186D01*
X801383Y407894D01*
Y407561D01*
X801508Y407186D01*
X801716Y406894D01*
X801966Y406686D01*
X802383Y406519D01*
X802758Y406477D01*
X803133Y406561D01*
X803383Y406686D01*
X803633Y406936D01*
X803800Y407227D01*
X803883Y407519D01*
Y407811D01*
X803800Y408102D01*
X803675Y408352D01*
X803508Y408561D01*
G01X803383Y409702D02*
X803675Y409952D01*
X803841Y410286D01*
X803883Y410661D01*
X803841Y410994D01*
X803633Y411327D01*
X803383Y411536D01*
X803133Y411577D01*
X802841Y411494D01*
X802633Y411202D01*
X802550Y410911D01*
Y410536D01*
G01Y410911D02*
X802425Y411161D01*
X802216Y411369D01*
X801966Y411452D01*
X801716Y411369D01*
X801508Y411161D01*
X801383Y410786D01*
X801425Y410411D01*
X801591Y410036D01*
G01X819657Y398690D02*
Y401190D01*
X820698D01*
X821032Y401065D01*
X821240Y400898D01*
X821323Y400565D01*
X821240Y400232D01*
X820990Y400023D01*
X820698Y399898D01*
X819657D01*
G01X820698D02*
X821323Y398690D01*
G01X824090D02*
Y401190D01*
X822548Y399398D01*
X824632D01*
G01X827607Y400982D02*
X827357Y401107D01*
X827065Y401190D01*
X826732D01*
X826357Y401065D01*
X826065Y400857D01*
X825857Y400607D01*
X825690Y400190D01*
X825648Y399815D01*
X825732Y399440D01*
X825857Y399190D01*
X826107Y398940D01*
X826398Y398773D01*
X826690Y398690D01*
X826982D01*
X827273Y398773D01*
X827523Y398898D01*
X827732Y399065D01*
G01X830290Y398690D02*
Y401190D01*
X828748Y399398D01*
X830832D01*
G01X847146Y354958D02*
Y357458D01*
X848187D01*
X848521Y357333D01*
X848729Y357166D01*
X848812Y356833D01*
X848729Y356500D01*
X848479Y356291D01*
X848187Y356166D01*
X847146D01*
G01X848187D02*
X848812Y354958D01*
G01X851079Y357458D02*
Y354958D01*
G01X850121Y357458D02*
X852037D01*
G01X853387Y357041D02*
X853637Y357291D01*
X853929Y357416D01*
X854262Y357458D01*
X854679Y357375D01*
X854971Y357166D01*
X855054Y356916D01*
X855012Y356666D01*
X854846Y356458D01*
X854012Y356041D01*
X853637Y355750D01*
X853387Y355333D01*
X853304Y354958D01*
X855054D01*
G01X856362Y355458D02*
X856612Y355166D01*
X856946Y355000D01*
X857321Y354958D01*
X857654Y355000D01*
X857987Y355208D01*
X858196Y355458D01*
X858237Y355708D01*
X858154Y356000D01*
X857862Y356208D01*
X857571Y356291D01*
X857196D01*
G01X857571D02*
X857821Y356416D01*
X858029Y356625D01*
X858112Y356875D01*
X858029Y357125D01*
X857821Y357333D01*
X857446Y357458D01*
X857071Y357416D01*
X856696Y357250D01*
G01X802782Y358083D02*
Y364131D01*
G01D02*
X840182D01*
Y358083D01*
G01X843533Y382917D02*
X846033D01*
Y384583D01*
G01Y387350D02*
X843533D01*
X845325Y385808D01*
Y387892D01*
G01X843741Y390867D02*
X843616Y390617D01*
X843533Y390325D01*
Y389992D01*
X843658Y389617D01*
X843866Y389325D01*
X844116Y389117D01*
X844533Y388950D01*
X844908Y388908D01*
X845283Y388992D01*
X845533Y389117D01*
X845783Y389367D01*
X845950Y389658D01*
X846033Y389950D01*
Y390242D01*
X845950Y390533D01*
X845825Y390783D01*
X845658Y390992D01*
G01X843950Y392258D02*
X843700Y392508D01*
X843575Y392800D01*
X843533Y393133D01*
X843616Y393550D01*
X843825Y393842D01*
X844075Y393925D01*
X844325Y393883D01*
X844533Y393717D01*
X844950Y392883D01*
X845241Y392508D01*
X845658Y392258D01*
X846033Y392175D01*
Y393925D01*
G01X840137Y377131D02*
Y371083D01*
X802737D01*
Y377131D01*
G01Y390231D02*
Y396279D01*
G01D02*
X840137D01*
Y390231D01*
G01X815330Y463980D02*
Y456980D01*
G01X812263Y463980D02*
X818397D01*
G01X823930Y461647D02*
Y456980D01*
G01Y463513D02*
X823663Y463630D01*
Y463863D01*
X823930Y463980D01*
X824197Y463863D01*
Y463630D01*
X823930Y463513D01*
G01X832530Y456980D02*
X831730Y457097D01*
X830930Y457563D01*
X830397Y458380D01*
X830130Y459313D01*
X830397Y460247D01*
X830930Y461063D01*
X831730Y461530D01*
X832530Y461647D01*
X833330Y461530D01*
X834130Y461063D01*
X834663Y460247D01*
X834797Y459313D01*
X834663Y458380D01*
X834130Y457563D01*
X833330Y457097D01*
X832530Y456980D01*
G01X839263Y455230D02*
X840197Y454763D01*
X841263Y454647D01*
X842197Y454763D01*
X842997Y455347D01*
X843530Y456163D01*
Y461647D01*
G01Y460713D02*
X842997Y461180D01*
X842197Y461530D01*
X841263Y461647D01*
X840197Y461413D01*
X839530Y460947D01*
X838997Y460130D01*
X838730Y459313D01*
X838863Y458613D01*
X839397Y457796D01*
X840197Y457213D01*
X841263Y456980D01*
X842063Y457097D01*
X842997Y457563D01*
X843530Y458030D01*
G01X852130Y456980D02*
Y461647D01*
G01Y460830D02*
X851597Y461297D01*
X850797Y461530D01*
X849863Y461647D01*
X848930Y461413D01*
X848130Y460947D01*
X847597Y460247D01*
X847330Y459313D01*
X847597Y458380D01*
X848130Y457680D01*
X848930Y457213D01*
X849863Y456980D01*
X850797Y457097D01*
X851597Y457447D01*
X852130Y457913D01*
G01X864263Y456980D02*
Y463980D01*
X867463D01*
X868530Y463630D01*
X869330Y462813D01*
X869597Y461880D01*
X869330Y460947D01*
X868663Y460247D01*
X867463Y459896D01*
X864263D01*
G01X877930Y456980D02*
Y461647D01*
G01Y460830D02*
X877397Y461297D01*
X876597Y461530D01*
X875663Y461647D01*
X874730Y461413D01*
X873930Y460947D01*
X873397Y460247D01*
X873130Y459313D01*
X873397Y458380D01*
X873930Y457680D01*
X874730Y457213D01*
X875663Y456980D01*
X876597Y457097D01*
X877397Y457447D01*
X877930Y457913D01*
G01X882130Y457796D02*
X882797Y457330D01*
X883730Y456980D01*
X884530D01*
X885330Y457213D01*
X885863Y457563D01*
X886130Y458030D01*
X885997Y458730D01*
X885463Y459080D01*
X883063Y459780D01*
X882530Y460597D01*
X882797Y461180D01*
X883330Y461530D01*
X884130Y461647D01*
X884930Y461530D01*
X885730Y461180D01*
G01X890730Y457796D02*
X891397Y457330D01*
X892330Y456980D01*
X893130D01*
X893930Y457213D01*
X894463Y457563D01*
X894730Y458030D01*
X894597Y458730D01*
X894063Y459080D01*
X891663Y459780D01*
X891130Y460597D01*
X891397Y461180D01*
X891930Y461530D01*
X892730Y461647D01*
X893530Y461530D01*
X894330Y461180D01*
G01X906997Y456980D02*
Y463980D01*
X909663D01*
X910730Y463630D01*
X911530Y463163D01*
X912197Y462463D01*
X912730Y461647D01*
X912863Y460480D01*
X912730Y459313D01*
X912197Y458497D01*
X911530Y457796D01*
X910730Y457330D01*
X909663Y456980D01*
X906997D01*
G01X915197Y463980D02*
X918530Y456980D01*
X921863Y463980D01*
G01X927130D02*
Y456980D01*
G01X924063Y463980D02*
X930197D01*
G01X940863Y456980D02*
Y463980D01*
X944330Y458147D01*
X947797Y463980D01*
Y456980D01*
G01X953997Y460713D02*
X954530Y461063D01*
X954930Y461647D01*
X955197Y462463D01*
X954930Y463163D01*
X954397Y463630D01*
X953463Y463980D01*
X949863D01*
Y456980D01*
X954263D01*
X955197Y457447D01*
X955730Y458147D01*
X955997Y458963D01*
X955730Y459780D01*
X954930Y460480D01*
X953997Y460713D01*
X949863D01*
G01X829167Y440333D02*
X829700Y440683D01*
X830100Y441267D01*
X830367Y442083D01*
X830100Y442783D01*
X829567Y443250D01*
X828633Y443600D01*
X825033D01*
Y436600D01*
X829433D01*
X830367Y437067D01*
X830900Y437767D01*
X831167Y438583D01*
X830900Y439400D01*
X830100Y440100D01*
X829167Y440333D01*
X825033D01*
G01X838300Y436600D02*
Y443600D01*
X833367Y438583D01*
X840033D01*
G01X845300Y436600D02*
X846233Y436717D01*
X847300Y437067D01*
X847967Y437650D01*
X848233Y438467D01*
X847967Y439283D01*
X847167Y439983D01*
X845967Y440333D01*
X844633D01*
X843833Y440567D01*
X843167Y441150D01*
X842900Y441967D01*
X843300Y442783D01*
X844233Y443367D01*
X845300Y443600D01*
X846367Y443367D01*
X847300Y442783D01*
X847700Y441967D01*
X847433Y441150D01*
X846767Y440567D01*
X845967Y440333D01*
X844633D01*
X843433Y439983D01*
X842633Y439283D01*
X842367Y438467D01*
X842633Y437650D01*
X843300Y437067D01*
X844367Y436717D01*
X845300Y436600D01*
G01X853900Y436367D02*
X853633Y436483D01*
Y436717D01*
X853900Y436833D01*
X854167Y436717D01*
Y436483D01*
X853900Y436367D01*
G01X862500Y443600D02*
X861433Y443367D01*
X860633Y442783D01*
X860100Y442083D01*
X859700Y441150D01*
X859567Y440100D01*
X859700Y439050D01*
X860100Y438117D01*
X860633Y437416D01*
X861433Y436833D01*
X862500Y436600D01*
X863567Y436833D01*
X864367Y437416D01*
X864900Y438117D01*
X865300Y439050D01*
X865433Y440100D01*
X865300Y441150D01*
X864900Y442083D01*
X864367Y442783D01*
X863567Y443367D01*
X862500Y443600D01*
G01X871100D02*
X870033Y443367D01*
X869233Y442783D01*
X868700Y442083D01*
X868300Y441150D01*
X868167Y440100D01*
X868300Y439050D01*
X868700Y438117D01*
X869233Y437416D01*
X870033Y436833D01*
X871100Y436600D01*
X872167Y436833D01*
X872967Y437416D01*
X873500Y438117D01*
X873900Y439050D01*
X874033Y440100D01*
X873900Y441150D01*
X873500Y442083D01*
X872967Y442783D01*
X872167Y443367D01*
X871100Y443600D01*
G01X876900Y436600D02*
X882500Y443600D01*
G01X876900D02*
X882500Y436600D01*
G01X888300Y443600D02*
X887233Y443367D01*
X886433Y442783D01*
X885900Y442083D01*
X885500Y441150D01*
X885367Y440100D01*
X885500Y439050D01*
X885900Y438117D01*
X886433Y437416D01*
X887233Y436833D01*
X888300Y436600D01*
X889367Y436833D01*
X890167Y437416D01*
X890700Y438117D01*
X891100Y439050D01*
X891233Y440100D01*
X891100Y441150D01*
X890700Y442083D01*
X890167Y442783D01*
X889367Y443367D01*
X888300Y443600D01*
G01X893967Y437650D02*
X894767Y437067D01*
X895700Y436717D01*
X896900Y436600D01*
X898100Y436833D01*
X899033Y437300D01*
X899700Y438117D01*
X899833Y439050D01*
X899567Y439983D01*
X898900Y440567D01*
X897967Y441033D01*
X897033Y441150D01*
X896100Y441033D01*
X894900Y440567D01*
X895300Y443600D01*
X898900D01*
G01X905500Y436367D02*
X905233Y436483D01*
Y436717D01*
X905500Y436833D01*
X905767Y436717D01*
Y436483D01*
X905500Y436367D01*
G01X914100Y443600D02*
X913033Y443367D01*
X912233Y442783D01*
X911700Y442083D01*
X911300Y441150D01*
X911167Y440100D01*
X911300Y439050D01*
X911700Y438117D01*
X912233Y437416D01*
X913033Y436833D01*
X914100Y436600D01*
X915167Y436833D01*
X915967Y437416D01*
X916500Y438117D01*
X916900Y439050D01*
X917033Y440100D01*
X916900Y441150D01*
X916500Y442083D01*
X915967Y442783D01*
X915167Y443367D01*
X914100Y443600D01*
G01X922700D02*
X921633Y443367D01*
X920833Y442783D01*
X920300Y442083D01*
X919900Y441150D01*
X919767Y440100D01*
X919900Y439050D01*
X920300Y438117D01*
X920833Y437416D01*
X921633Y436833D01*
X922700Y436600D01*
X923767Y436833D01*
X924567Y437416D01*
X925100Y438117D01*
X925500Y439050D01*
X925633Y440100D01*
X925500Y441150D01*
X925100Y442083D01*
X924567Y442783D01*
X923767Y443367D01*
X922700Y443600D01*
G01X931300Y436600D02*
Y443600D01*
X929700Y442200D01*
G01Y436600D02*
X932900D01*
G01X940967Y440333D02*
X941500Y440683D01*
X941900Y441267D01*
X942167Y442083D01*
X941900Y442783D01*
X941367Y443250D01*
X940433Y443600D01*
X936833D01*
Y436600D01*
X941233D01*
X942167Y437067D01*
X942700Y437767D01*
X942967Y438583D01*
X942700Y439400D01*
X941900Y440100D01*
X940967Y440333D01*
X936833D01*
G01X851200Y446800D02*
Y453800D01*
X849600Y452400D01*
G01Y446800D02*
X852800D01*
G01X856867Y447850D02*
X857667Y447267D01*
X858600Y446917D01*
X859800Y446800D01*
X861000Y447033D01*
X861933Y447500D01*
X862600Y448317D01*
X862733Y449250D01*
X862467Y450183D01*
X861800Y450767D01*
X860867Y451233D01*
X859933Y451350D01*
X859000Y451233D01*
X857800Y450767D01*
X858200Y453800D01*
X861800D01*
G01X868400Y446800D02*
Y453800D01*
X866800Y452400D01*
G01Y446800D02*
X870000D01*
G01X874467Y452633D02*
X875267Y453333D01*
X876200Y453683D01*
X877267Y453800D01*
X878600Y453567D01*
X879533Y452983D01*
X879800Y452283D01*
X879667Y451583D01*
X879133Y451000D01*
X876467Y449833D01*
X875267Y449017D01*
X874467Y447850D01*
X874200Y446800D01*
X879800D01*
G01X883067Y449716D02*
X884000Y450533D01*
X884800Y451000D01*
X885867Y451233D01*
X886800Y451000D01*
X887467Y450533D01*
X888000Y449833D01*
X888133Y449017D01*
X888000Y448317D01*
X887467Y447616D01*
X886667Y447033D01*
X885733Y446800D01*
X884667Y447033D01*
X883733Y447733D01*
X883200Y448783D01*
X883067Y449950D01*
X883333Y451467D01*
X883733Y452283D01*
X884400Y453100D01*
X885333Y453683D01*
X886267Y453800D01*
X887200Y453567D01*
X887867Y452983D01*
G01X892467Y449133D02*
X895933D01*
G01X902800Y446800D02*
Y453800D01*
X901200Y452400D01*
G01Y446800D02*
X904400D01*
G01X912467Y450533D02*
X913000Y450883D01*
X913400Y451467D01*
X913667Y452283D01*
X913400Y452983D01*
X912867Y453450D01*
X911933Y453800D01*
X908333D01*
Y446800D01*
X912733D01*
X913667Y447267D01*
X914200Y447967D01*
X914467Y448783D01*
X914200Y449600D01*
X913400Y450300D01*
X912467Y450533D01*
X908333D01*
G01X825433Y425800D02*
Y432800D01*
X828900Y426967D01*
X832367Y432800D01*
Y425800D01*
G01X834167D02*
X837500Y432800D01*
X840833Y425800D01*
G01X839633Y428250D02*
X835367D01*
G01X843167Y425800D02*
Y432800D01*
X845833D01*
X846900Y432450D01*
X847700Y431983D01*
X848367Y431283D01*
X848900Y430467D01*
X849033Y429300D01*
X848900Y428133D01*
X848367Y427317D01*
X847700Y426616D01*
X846900Y426150D01*
X845833Y425800D01*
X843167D01*
G01X857367D02*
X852033D01*
Y432800D01*
X857367D01*
G01X855233Y429417D02*
X852033D01*
G01X870300Y432800D02*
X873500D01*
G01X871900D02*
Y425800D01*
G01X870300D02*
X873500D01*
G01X877433D02*
Y432800D01*
X883567Y425800D01*
Y432800D01*
G01X897700D02*
Y425800D01*
G01X894633Y432800D02*
X900767D01*
G01X902967Y425800D02*
X906300Y432800D01*
X909633Y425800D01*
G01X908433Y428250D02*
X904167D01*
G01X913300Y432800D02*
X916500D01*
G01X914900D02*
Y425800D01*
G01X913300D02*
X916500D01*
G01X919500Y432800D02*
X921367Y425800D01*
X923500Y432800D01*
X925633Y425800D01*
X927500Y432800D01*
G01X928767Y425800D02*
X932100Y432800D01*
X935433Y425800D01*
G01X934233Y428250D02*
X929967D01*
G01X937633Y425800D02*
Y432800D01*
X943767Y425800D01*
Y432800D01*
G01X795803Y429840D02*
Y432340D01*
X796844D01*
X797178Y432215D01*
X797386Y432048D01*
X797469Y431715D01*
X797386Y431382D01*
X797136Y431173D01*
X796844Y431048D01*
X795803D01*
G01X796844D02*
X797469Y429840D01*
G01X798944Y430882D02*
X799236Y431173D01*
X799486Y431340D01*
X799819Y431423D01*
X800111Y431340D01*
X800319Y431173D01*
X800486Y430923D01*
X800528Y430632D01*
X800486Y430382D01*
X800319Y430132D01*
X800069Y429923D01*
X799778Y429840D01*
X799444Y429923D01*
X799153Y430173D01*
X798986Y430548D01*
X798944Y430965D01*
X799028Y431507D01*
X799153Y431798D01*
X799361Y432090D01*
X799653Y432298D01*
X799944Y432340D01*
X800236Y432257D01*
X800444Y432048D01*
G01X801878Y429840D02*
Y432340D01*
X803794Y429840D01*
Y432340D01*
G01X805144Y431923D02*
X805394Y432173D01*
X805686Y432298D01*
X806019Y432340D01*
X806436Y432257D01*
X806728Y432048D01*
X806811Y431798D01*
X806769Y431548D01*
X806603Y431340D01*
X805769Y430923D01*
X805394Y430632D01*
X805144Y430215D01*
X805061Y429840D01*
X806811D01*
G01X795997Y425996D02*
Y428496D01*
X797038D01*
X797372Y428371D01*
X797580Y428204D01*
X797663Y427871D01*
X797580Y427538D01*
X797330Y427329D01*
X797038Y427204D01*
X795997D01*
G01X797038D02*
X797663Y425996D01*
G01X799138Y427038D02*
X799430Y427329D01*
X799680Y427496D01*
X800013Y427579D01*
X800305Y427496D01*
X800513Y427329D01*
X800680Y427079D01*
X800722Y426788D01*
X800680Y426538D01*
X800513Y426288D01*
X800263Y426079D01*
X799972Y425996D01*
X799638Y426079D01*
X799347Y426329D01*
X799180Y426704D01*
X799138Y427121D01*
X799222Y427663D01*
X799347Y427954D01*
X799555Y428246D01*
X799847Y428454D01*
X800138Y428496D01*
X800430Y428413D01*
X800638Y428204D01*
G01X802072Y425996D02*
Y428496D01*
X803988Y425996D01*
Y428496D01*
G01X806130Y425996D02*
Y428496D01*
X805630Y427996D01*
G01Y425996D02*
X806630D01*
G01X819626Y404458D02*
Y406958D01*
X820667D01*
X821001Y406833D01*
X821209Y406666D01*
X821292Y406333D01*
X821209Y406000D01*
X820959Y405791D01*
X820667Y405666D01*
X819626D01*
G01X820667D02*
X821292Y404458D01*
G01X824059D02*
Y406958D01*
X822517Y405166D01*
X824601D01*
G01X827576Y406750D02*
X827326Y406875D01*
X827034Y406958D01*
X826701D01*
X826326Y406833D01*
X826034Y406625D01*
X825826Y406375D01*
X825659Y405958D01*
X825617Y405583D01*
X825701Y405208D01*
X825826Y404958D01*
X826076Y404708D01*
X826367Y404541D01*
X826659Y404458D01*
X826951D01*
X827242Y404541D01*
X827492Y404666D01*
X827701Y404833D01*
G01X828967Y406541D02*
X829217Y406791D01*
X829509Y406916D01*
X829842Y406958D01*
X830259Y406875D01*
X830551Y406666D01*
X830634Y406416D01*
X830592Y406166D01*
X830426Y405958D01*
X829592Y405541D01*
X829217Y405250D01*
X828967Y404833D01*
X828884Y404458D01*
X830634D01*
G01X790234Y485500D02*
X800234D01*
X803234Y482000D01*
Y445000D01*
X788534D01*
G01Y489750D02*
X790234D01*
Y473250D01*
X788534D01*
G01X790489Y551206D02*
X790239Y551331D01*
X789947Y551414D01*
X789614D01*
X789239Y551289D01*
X788947Y551081D01*
X788739Y550831D01*
X788572Y550414D01*
X788530Y550039D01*
X788614Y549664D01*
X788739Y549414D01*
X788989Y549164D01*
X789280Y548997D01*
X789572Y548914D01*
X789864D01*
X790155Y548997D01*
X790405Y549122D01*
X790614Y549289D01*
G01X793172Y548914D02*
Y551414D01*
X791630Y549622D01*
X793714D01*
G01X794730Y548914D02*
X795772Y551414D01*
X796814Y548914D01*
G01X796439Y549789D02*
X795105D01*
G01X798872Y548914D02*
Y551414D01*
X798372Y550914D01*
G01Y548914D02*
X799372D01*
G01X801972D02*
X802264Y548956D01*
X802597Y549081D01*
X802805Y549289D01*
X802889Y549581D01*
X802805Y549872D01*
X802555Y550122D01*
X802180Y550247D01*
X801764D01*
X801514Y550331D01*
X801305Y550539D01*
X801222Y550831D01*
X801347Y551122D01*
X801639Y551331D01*
X801972Y551414D01*
X802305Y551331D01*
X802597Y551122D01*
X802722Y550831D01*
X802639Y550539D01*
X802430Y550331D01*
X802180Y550247D01*
X801764D01*
X801389Y550122D01*
X801139Y549872D01*
X801055Y549581D01*
X801139Y549289D01*
X801347Y549081D01*
X801680Y548956D01*
X801972Y548914D01*
G01X796460Y591380D02*
X796210Y591505D01*
X795918Y591588D01*
X795585D01*
X795210Y591463D01*
X794918Y591255D01*
X794710Y591005D01*
X794543Y590588D01*
X794501Y590213D01*
X794585Y589838D01*
X794710Y589588D01*
X794960Y589338D01*
X795251Y589171D01*
X795543Y589088D01*
X795835D01*
X796126Y589171D01*
X796376Y589296D01*
X796585Y589463D01*
G01X799143Y589088D02*
Y591588D01*
X797601Y589796D01*
X799685D01*
G01X800701Y589088D02*
X801743Y591588D01*
X802785Y589088D01*
G01X802410Y589963D02*
X801076D01*
G01X803926Y589463D02*
X804176Y589255D01*
X804468Y589130D01*
X804843Y589088D01*
X805218Y589171D01*
X805510Y589338D01*
X805718Y589630D01*
X805760Y589963D01*
X805676Y590296D01*
X805468Y590505D01*
X805176Y590671D01*
X804885Y590713D01*
X804593Y590671D01*
X804218Y590505D01*
X804343Y591588D01*
X805468D01*
G01X882984Y-38057D02*
X864984D01*
Y-56057D01*
X882984D01*
Y-38057D01*
G01X902984D02*
X884984D01*
Y-56057D01*
X902984D01*
Y-38057D01*
G01X909850Y14762D02*
X909600Y14887D01*
X909308Y14970D01*
X908975D01*
X908600Y14845D01*
X908308Y14637D01*
X908100Y14387D01*
X907933Y13970D01*
X907891Y13595D01*
X907975Y13220D01*
X908100Y12970D01*
X908350Y12720D01*
X908641Y12553D01*
X908933Y12470D01*
X909225D01*
X909516Y12553D01*
X909766Y12678D01*
X909975Y12845D01*
G01X911116D02*
X911366Y12637D01*
X911658Y12512D01*
X912033Y12470D01*
X912408Y12553D01*
X912700Y12720D01*
X912908Y13012D01*
X912950Y13345D01*
X912866Y13678D01*
X912658Y13887D01*
X912366Y14053D01*
X912075Y14095D01*
X911783Y14053D01*
X911408Y13887D01*
X911533Y14970D01*
X912658D01*
G01X915383Y13720D02*
X916216D01*
Y12970D01*
X915966Y12720D01*
X915675Y12553D01*
X915258Y12470D01*
X914841Y12553D01*
X914550Y12720D01*
X914300Y12970D01*
X914133Y13262D01*
X914050Y13595D01*
Y13887D01*
X914133Y14137D01*
X914300Y14428D01*
X914550Y14678D01*
X914800Y14845D01*
X915133Y14970D01*
X915425D01*
X915758Y14887D01*
X916008Y14720D01*
G01X918233Y12470D02*
Y14970D01*
X917733Y14470D01*
G01Y12470D02*
X918733D01*
G01X921833D02*
Y14970D01*
X920291Y13178D01*
X922375D01*
G01X892530Y15698D02*
X892280Y15823D01*
X891988Y15906D01*
X891655D01*
X891280Y15781D01*
X890988Y15573D01*
X890780Y15323D01*
X890613Y14906D01*
X890571Y14531D01*
X890655Y14156D01*
X890780Y13906D01*
X891030Y13656D01*
X891321Y13489D01*
X891613Y13406D01*
X891905D01*
X892196Y13489D01*
X892446Y13614D01*
X892655Y13781D01*
G01X893796D02*
X894046Y13573D01*
X894338Y13448D01*
X894713Y13406D01*
X895088Y13489D01*
X895380Y13656D01*
X895588Y13948D01*
X895630Y14281D01*
X895546Y14614D01*
X895338Y14823D01*
X895046Y14989D01*
X894755Y15031D01*
X894463Y14989D01*
X894088Y14823D01*
X894213Y15906D01*
X895338D01*
G01X898063Y14656D02*
X898896D01*
Y13906D01*
X898646Y13656D01*
X898355Y13489D01*
X897938Y13406D01*
X897521Y13489D01*
X897230Y13656D01*
X896980Y13906D01*
X896813Y14198D01*
X896730Y14531D01*
Y14823D01*
X896813Y15073D01*
X896980Y15364D01*
X897230Y15614D01*
X897480Y15781D01*
X897813Y15906D01*
X898105D01*
X898438Y15823D01*
X898688Y15656D01*
G01X900913Y13406D02*
Y15906D01*
X900413Y15406D01*
G01Y13406D02*
X901413D01*
G01X903096Y13906D02*
X903346Y13614D01*
X903680Y13448D01*
X904055Y13406D01*
X904388Y13448D01*
X904721Y13656D01*
X904930Y13906D01*
X904971Y14156D01*
X904888Y14448D01*
X904596Y14656D01*
X904305Y14739D01*
X903930D01*
G01X904305D02*
X904555Y14864D01*
X904763Y15073D01*
X904846Y15323D01*
X904763Y15573D01*
X904555Y15781D01*
X904180Y15906D01*
X903805Y15864D01*
X903430Y15698D01*
G01X876704Y14547D02*
X876454Y14672D01*
X876162Y14755D01*
X875829D01*
X875454Y14630D01*
X875162Y14422D01*
X874954Y14172D01*
X874787Y13755D01*
X874745Y13380D01*
X874829Y13005D01*
X874954Y12755D01*
X875204Y12505D01*
X875495Y12338D01*
X875787Y12255D01*
X876079D01*
X876370Y12338D01*
X876620Y12463D01*
X876829Y12630D01*
G01X877970D02*
X878220Y12422D01*
X878512Y12297D01*
X878887Y12255D01*
X879262Y12338D01*
X879554Y12505D01*
X879762Y12797D01*
X879804Y13130D01*
X879720Y13463D01*
X879512Y13672D01*
X879220Y13838D01*
X878929Y13880D01*
X878637Y13838D01*
X878262Y13672D01*
X878387Y14755D01*
X879512D01*
G01X882237Y13505D02*
X883070D01*
Y12755D01*
X882820Y12505D01*
X882529Y12338D01*
X882112Y12255D01*
X881695Y12338D01*
X881404Y12505D01*
X881154Y12755D01*
X880987Y13047D01*
X880904Y13380D01*
Y13672D01*
X880987Y13922D01*
X881154Y14213D01*
X881404Y14463D01*
X881654Y14630D01*
X881987Y14755D01*
X882279D01*
X882612Y14672D01*
X882862Y14505D01*
G01X885087Y12255D02*
Y14755D01*
X884587Y14255D01*
G01Y12255D02*
X885587D01*
G01X887395Y14338D02*
X887645Y14588D01*
X887937Y14713D01*
X888270Y14755D01*
X888687Y14672D01*
X888979Y14463D01*
X889062Y14213D01*
X889020Y13963D01*
X888854Y13755D01*
X888020Y13338D01*
X887645Y13047D01*
X887395Y12630D01*
X887312Y12255D01*
X889062D01*
G01X859819Y15604D02*
X859569Y15729D01*
X859277Y15812D01*
X858944D01*
X858569Y15687D01*
X858277Y15479D01*
X858069Y15229D01*
X857902Y14812D01*
X857860Y14437D01*
X857944Y14062D01*
X858069Y13812D01*
X858319Y13562D01*
X858610Y13395D01*
X858902Y13312D01*
X859194D01*
X859485Y13395D01*
X859735Y13520D01*
X859944Y13687D01*
G01X861085D02*
X861335Y13479D01*
X861627Y13354D01*
X862002Y13312D01*
X862377Y13395D01*
X862669Y13562D01*
X862877Y13854D01*
X862919Y14187D01*
X862835Y14520D01*
X862627Y14729D01*
X862335Y14895D01*
X862044Y14937D01*
X861752Y14895D01*
X861377Y14729D01*
X861502Y15812D01*
X862627D01*
G01X865352Y14562D02*
X866185D01*
Y13812D01*
X865935Y13562D01*
X865644Y13395D01*
X865227Y13312D01*
X864810Y13395D01*
X864519Y13562D01*
X864269Y13812D01*
X864102Y14104D01*
X864019Y14437D01*
Y14729D01*
X864102Y14979D01*
X864269Y15270D01*
X864519Y15520D01*
X864769Y15687D01*
X865102Y15812D01*
X865394D01*
X865727Y15729D01*
X865977Y15562D01*
G01X868202Y13312D02*
Y15812D01*
X867702Y15312D01*
G01Y13312D02*
X868702D01*
G01X871302D02*
Y15812D01*
X870802Y15312D01*
G01Y13312D02*
X871802D01*
G01X854300Y95400D02*
Y102400D01*
G01X859900D02*
Y95400D01*
G01Y98900D02*
X854300D01*
G01X882100Y119499D02*
X882101Y119500D01*
X900003D01*
Y103532D01*
X895383D01*
Y89136D01*
X866413D01*
G01X875000Y92167D02*
X872500D01*
Y93208D01*
X872625Y93542D01*
X872792Y93750D01*
X873125Y93833D01*
X873458Y93750D01*
X873667Y93500D01*
X873792Y93208D01*
Y92167D01*
G01Y93208D02*
X875000Y93833D01*
G01Y96600D02*
X872500D01*
X874292Y95058D01*
Y97142D01*
G01X873750Y99450D02*
Y100283D01*
X874500D01*
X874750Y100033D01*
X874917Y99742D01*
X875000Y99325D01*
X874917Y98908D01*
X874750Y98617D01*
X874500Y98367D01*
X874208Y98200D01*
X873875Y98117D01*
X873583D01*
X873333Y98200D01*
X873042Y98367D01*
X872792Y98617D01*
X872625Y98867D01*
X872500Y99200D01*
Y99492D01*
X872583Y99825D01*
X872750Y100075D01*
G01X875000Y102300D02*
X872500D01*
X873000Y101800D01*
G01X875000D02*
Y102800D01*
G01Y105400D02*
X874958Y105692D01*
X874833Y106025D01*
X874625Y106233D01*
X874333Y106317D01*
X874042Y106233D01*
X873792Y105983D01*
X873667Y105608D01*
Y105192D01*
X873583Y104942D01*
X873375Y104733D01*
X873083Y104650D01*
X872792Y104775D01*
X872583Y105067D01*
X872500Y105400D01*
X872583Y105733D01*
X872792Y106025D01*
X873083Y106150D01*
X873375Y106067D01*
X873583Y105858D01*
X873667Y105608D01*
Y105192D01*
X873792Y104817D01*
X874042Y104567D01*
X874333Y104483D01*
X874625Y104567D01*
X874833Y104775D01*
X874958Y105108D01*
X875000Y105400D01*
G01X869000Y90667D02*
X866500D01*
Y91708D01*
X866625Y92042D01*
X866792Y92250D01*
X867125Y92333D01*
X867458Y92250D01*
X867667Y92000D01*
X867792Y91708D01*
Y90667D01*
G01Y91708D02*
X869000Y92333D01*
G01Y95100D02*
X866500D01*
X868292Y93558D01*
Y95642D01*
G01X867750Y97950D02*
Y98783D01*
X868500D01*
X868750Y98533D01*
X868917Y98242D01*
X869000Y97825D01*
X868917Y97408D01*
X868750Y97117D01*
X868500Y96867D01*
X868208Y96700D01*
X867875Y96617D01*
X867583D01*
X867333Y96700D01*
X867042Y96867D01*
X866792Y97117D01*
X866625Y97367D01*
X866500Y97700D01*
Y97992D01*
X866583Y98325D01*
X866750Y98575D01*
G01X869000Y100800D02*
X866500D01*
X867000Y100300D01*
G01X869000D02*
Y101300D01*
G01X868708Y103192D02*
X868917Y103483D01*
X869000Y103817D01*
X868917Y104150D01*
X868667Y104442D01*
X868292Y104650D01*
X867917Y104733D01*
X867458D01*
X867083Y104650D01*
X866750Y104442D01*
X866583Y104192D01*
X866500Y103900D01*
X866583Y103567D01*
X866750Y103317D01*
X867000Y103150D01*
X867333Y103067D01*
X867625Y103150D01*
X867917Y103358D01*
X868083Y103608D01*
X868125Y103900D01*
X868042Y104233D01*
X867833Y104483D01*
X867458Y104733D01*
G01X892088Y93450D02*
X891963Y93200D01*
X891880Y92908D01*
Y92575D01*
X892005Y92200D01*
X892213Y91908D01*
X892463Y91700D01*
X892880Y91533D01*
X893255Y91491D01*
X893630Y91575D01*
X893880Y91700D01*
X894130Y91950D01*
X894297Y92241D01*
X894380Y92533D01*
Y92825D01*
X894297Y93116D01*
X894172Y93366D01*
X894005Y93575D01*
G01X894380Y96133D02*
X891880D01*
X893672Y94591D01*
Y96675D01*
G01X893130Y98983D02*
Y99816D01*
X893880D01*
X894130Y99566D01*
X894297Y99275D01*
X894380Y98858D01*
X894297Y98441D01*
X894130Y98150D01*
X893880Y97900D01*
X893588Y97733D01*
X893255Y97650D01*
X892963D01*
X892713Y97733D01*
X892422Y97900D01*
X892172Y98150D01*
X892005Y98400D01*
X891880Y98733D01*
Y99025D01*
X891963Y99358D01*
X892130Y99608D01*
G01X894380Y101833D02*
X891880D01*
X892380Y101333D01*
G01X894380D02*
Y102333D01*
G01X893338Y104141D02*
X893047Y104433D01*
X892880Y104683D01*
X892797Y105016D01*
X892880Y105308D01*
X893047Y105516D01*
X893297Y105683D01*
X893588Y105725D01*
X893838Y105683D01*
X894088Y105516D01*
X894297Y105266D01*
X894380Y104975D01*
X894297Y104641D01*
X894047Y104350D01*
X893672Y104183D01*
X893255Y104141D01*
X892713Y104225D01*
X892422Y104350D01*
X892130Y104558D01*
X891922Y104850D01*
X891880Y105141D01*
X891963Y105433D01*
X892172Y105641D01*
G01X885452Y93746D02*
X885327Y93496D01*
X885244Y93204D01*
Y92871D01*
X885369Y92496D01*
X885577Y92204D01*
X885827Y91996D01*
X886244Y91829D01*
X886619Y91787D01*
X886994Y91871D01*
X887244Y91996D01*
X887494Y92246D01*
X887661Y92537D01*
X887744Y92829D01*
Y93121D01*
X887661Y93412D01*
X887536Y93662D01*
X887369Y93871D01*
G01X887744Y96429D02*
X885244D01*
X887036Y94887D01*
Y96971D01*
G01X886494Y99279D02*
Y100112D01*
X887244D01*
X887494Y99862D01*
X887661Y99571D01*
X887744Y99154D01*
X887661Y98737D01*
X887494Y98446D01*
X887244Y98196D01*
X886952Y98029D01*
X886619Y97946D01*
X886327D01*
X886077Y98029D01*
X885786Y98196D01*
X885536Y98446D01*
X885369Y98696D01*
X885244Y99029D01*
Y99321D01*
X885327Y99654D01*
X885494Y99904D01*
G01X887744Y102129D02*
X885244D01*
X885744Y101629D01*
G01X887744D02*
Y102629D01*
G01X887369Y104312D02*
X887577Y104562D01*
X887702Y104854D01*
X887744Y105229D01*
X887661Y105604D01*
X887494Y105896D01*
X887202Y106104D01*
X886869Y106146D01*
X886536Y106062D01*
X886327Y105854D01*
X886161Y105562D01*
X886119Y105271D01*
X886161Y104979D01*
X886327Y104604D01*
X885244Y104729D01*
Y105854D01*
G01X878508Y94017D02*
X878383Y93767D01*
X878300Y93475D01*
Y93142D01*
X878425Y92767D01*
X878633Y92475D01*
X878883Y92267D01*
X879300Y92100D01*
X879675Y92058D01*
X880050Y92142D01*
X880300Y92267D01*
X880550Y92517D01*
X880717Y92808D01*
X880800Y93100D01*
Y93392D01*
X880717Y93683D01*
X880592Y93933D01*
X880425Y94142D01*
G01X880800Y96700D02*
X878300D01*
X880092Y95158D01*
Y97242D01*
G01X879550Y99550D02*
Y100383D01*
X880300D01*
X880550Y100133D01*
X880717Y99842D01*
X880800Y99425D01*
X880717Y99008D01*
X880550Y98717D01*
X880300Y98467D01*
X880008Y98300D01*
X879675Y98217D01*
X879383D01*
X879133Y98300D01*
X878842Y98467D01*
X878592Y98717D01*
X878425Y98967D01*
X878300Y99300D01*
Y99592D01*
X878383Y99925D01*
X878550Y100175D01*
G01X880800Y102400D02*
X878300D01*
X878800Y101900D01*
G01X880800D02*
Y102900D01*
G01Y106000D02*
X878300D01*
X880092Y104458D01*
Y106542D01*
G01X905000Y178500D02*
Y167901D01*
X905001Y167900D01*
X919099D01*
X919100Y167899D01*
Y115401D01*
X919099Y115400D01*
X900452D01*
G01X885767Y116959D02*
X885517Y117084D01*
X885225Y117167D01*
X884892D01*
X884517Y117042D01*
X884225Y116834D01*
X884017Y116584D01*
X883850Y116167D01*
X883808Y115792D01*
X883892Y115417D01*
X884017Y115167D01*
X884267Y114917D01*
X884558Y114750D01*
X884850Y114667D01*
X885142D01*
X885433Y114750D01*
X885683Y114875D01*
X885892Y115042D01*
G01X887158Y115709D02*
X887450Y116000D01*
X887700Y116167D01*
X888033Y116250D01*
X888325Y116167D01*
X888533Y116000D01*
X888700Y115750D01*
X888742Y115459D01*
X888700Y115209D01*
X888533Y114959D01*
X888283Y114750D01*
X887992Y114667D01*
X887658Y114750D01*
X887367Y115000D01*
X887200Y115375D01*
X887158Y115792D01*
X887242Y116334D01*
X887367Y116625D01*
X887575Y116917D01*
X887867Y117125D01*
X888158Y117167D01*
X888450Y117084D01*
X888658Y116875D01*
G01X890133Y117167D02*
Y115375D01*
X890300Y115000D01*
X890633Y114750D01*
X891050Y114667D01*
X891467Y114750D01*
X891800Y115000D01*
X891967Y115375D01*
Y117167D01*
G01X894150Y114667D02*
X894442Y114709D01*
X894775Y114834D01*
X894983Y115042D01*
X895067Y115334D01*
X894983Y115625D01*
X894733Y115875D01*
X894358Y116000D01*
X893942D01*
X893692Y116084D01*
X893483Y116292D01*
X893400Y116584D01*
X893525Y116875D01*
X893817Y117084D01*
X894150Y117167D01*
X894483Y117084D01*
X894775Y116875D01*
X894900Y116584D01*
X894817Y116292D01*
X894608Y116084D01*
X894358Y116000D01*
X893942D01*
X893567Y115875D01*
X893317Y115625D01*
X893233Y115334D01*
X893317Y115042D01*
X893525Y114834D01*
X893858Y114709D01*
X894150Y114667D01*
G01X879400Y126067D02*
X876900D01*
Y127108D01*
X877025Y127442D01*
X877192Y127650D01*
X877525Y127733D01*
X877858Y127650D01*
X878067Y127400D01*
X878192Y127108D01*
Y126067D01*
G01Y127108D02*
X879400Y127733D01*
G01X879025Y129083D02*
X879233Y129333D01*
X879358Y129625D01*
X879400Y130000D01*
X879317Y130375D01*
X879150Y130667D01*
X878858Y130875D01*
X878525Y130917D01*
X878192Y130833D01*
X877983Y130625D01*
X877817Y130333D01*
X877775Y130042D01*
X877817Y129750D01*
X877983Y129375D01*
X876900Y129500D01*
Y130625D01*
G01X879400Y132183D02*
X876900D01*
Y133017D01*
X877025Y133350D01*
X877192Y133600D01*
X877442Y133808D01*
X877733Y133975D01*
X878150Y134017D01*
X878567Y133975D01*
X878858Y133808D01*
X879108Y133600D01*
X879275Y133350D01*
X879400Y133017D01*
Y132183D01*
G01X878900Y135283D02*
X879192Y135533D01*
X879358Y135867D01*
X879400Y136242D01*
X879358Y136575D01*
X879150Y136908D01*
X878900Y137117D01*
X878650Y137158D01*
X878358Y137075D01*
X878150Y136783D01*
X878067Y136492D01*
Y136117D01*
G01Y136492D02*
X877942Y136742D01*
X877733Y136950D01*
X877483Y137033D01*
X877233Y136950D01*
X877025Y136742D01*
X876900Y136367D01*
X876942Y135992D01*
X877108Y135617D01*
G01X887800Y125867D02*
X885300D01*
Y126908D01*
X885425Y127242D01*
X885592Y127450D01*
X885925Y127533D01*
X886258Y127450D01*
X886467Y127200D01*
X886592Y126908D01*
Y125867D01*
G01Y126908D02*
X887800Y127533D01*
G01X886758Y129008D02*
X886467Y129300D01*
X886300Y129550D01*
X886217Y129883D01*
X886300Y130175D01*
X886467Y130383D01*
X886717Y130550D01*
X887008Y130592D01*
X887258Y130550D01*
X887508Y130383D01*
X887717Y130133D01*
X887800Y129842D01*
X887717Y129508D01*
X887467Y129217D01*
X887092Y129050D01*
X886675Y129008D01*
X886133Y129092D01*
X885842Y129217D01*
X885550Y129425D01*
X885342Y129717D01*
X885300Y130008D01*
X885383Y130300D01*
X885592Y130508D01*
G01X887800Y131983D02*
X885300D01*
Y132817D01*
X885425Y133150D01*
X885592Y133400D01*
X885842Y133608D01*
X886133Y133775D01*
X886550Y133817D01*
X886967Y133775D01*
X887258Y133608D01*
X887508Y133400D01*
X887675Y133150D01*
X887800Y132817D01*
Y131983D01*
G01Y136000D02*
X885300D01*
X885800Y135500D01*
G01X887800D02*
Y136500D01*
G01X887300Y138183D02*
X887592Y138433D01*
X887758Y138767D01*
X887800Y139142D01*
X887758Y139475D01*
X887550Y139808D01*
X887300Y140017D01*
X887050Y140058D01*
X886758Y139975D01*
X886550Y139683D01*
X886467Y139392D01*
Y139017D01*
G01Y139392D02*
X886342Y139642D01*
X886133Y139850D01*
X885883Y139933D01*
X885633Y139850D01*
X885425Y139642D01*
X885300Y139267D01*
X885342Y138892D01*
X885508Y138517D01*
G01X876000Y126067D02*
X873500D01*
Y127108D01*
X873625Y127442D01*
X873792Y127650D01*
X874125Y127733D01*
X874458Y127650D01*
X874667Y127400D01*
X874792Y127108D01*
Y126067D01*
G01Y127108D02*
X876000Y127733D01*
G01X875625Y129083D02*
X875833Y129333D01*
X875958Y129625D01*
X876000Y130000D01*
X875917Y130375D01*
X875750Y130667D01*
X875458Y130875D01*
X875125Y130917D01*
X874792Y130833D01*
X874583Y130625D01*
X874417Y130333D01*
X874375Y130042D01*
X874417Y129750D01*
X874583Y129375D01*
X873500Y129500D01*
Y130625D01*
G01X876000Y132183D02*
X873500D01*
Y133017D01*
X873625Y133350D01*
X873792Y133600D01*
X874042Y133808D01*
X874333Y133975D01*
X874750Y134017D01*
X875167Y133975D01*
X875458Y133808D01*
X875708Y133600D01*
X875875Y133350D01*
X876000Y133017D01*
Y132183D01*
G01X874958Y135408D02*
X874667Y135700D01*
X874500Y135950D01*
X874417Y136283D01*
X874500Y136575D01*
X874667Y136783D01*
X874917Y136950D01*
X875208Y136992D01*
X875458Y136950D01*
X875708Y136783D01*
X875917Y136533D01*
X876000Y136242D01*
X875917Y135908D01*
X875667Y135617D01*
X875292Y135450D01*
X874875Y135408D01*
X874333Y135492D01*
X874042Y135617D01*
X873750Y135825D01*
X873542Y136117D01*
X873500Y136408D01*
X873583Y136700D01*
X873792Y136908D01*
G01X900817Y147000D02*
Y149500D01*
X901858D01*
X902192Y149375D01*
X902400Y149208D01*
X902483Y148875D01*
X902400Y148542D01*
X902150Y148333D01*
X901858Y148208D01*
X900817D01*
G01X901858D02*
X902483Y147000D01*
G01X903958Y148042D02*
X904250Y148333D01*
X904500Y148500D01*
X904833Y148583D01*
X905125Y148500D01*
X905333Y148333D01*
X905500Y148083D01*
X905542Y147792D01*
X905500Y147542D01*
X905333Y147292D01*
X905083Y147083D01*
X904792Y147000D01*
X904458Y147083D01*
X904167Y147333D01*
X904000Y147708D01*
X903958Y148125D01*
X904042Y148667D01*
X904167Y148958D01*
X904375Y149250D01*
X904667Y149458D01*
X904958Y149500D01*
X905250Y149417D01*
X905458Y149208D01*
G01X906933Y147000D02*
Y149500D01*
X907767D01*
X908100Y149375D01*
X908350Y149208D01*
X908558Y148958D01*
X908725Y148667D01*
X908767Y148250D01*
X908725Y147833D01*
X908558Y147542D01*
X908350Y147292D01*
X908100Y147125D01*
X907767Y147000D01*
X906933D01*
G01X910950D02*
Y149500D01*
X910450Y149000D01*
G01Y147000D02*
X911450D01*
G01X914050Y149500D02*
X913717Y149417D01*
X913467Y149208D01*
X913300Y148958D01*
X913175Y148625D01*
X913133Y148250D01*
X913175Y147875D01*
X913300Y147542D01*
X913467Y147292D01*
X913717Y147083D01*
X914050Y147000D01*
X914383Y147083D01*
X914633Y147292D01*
X914800Y147542D01*
X914925Y147875D01*
X914967Y148250D01*
X914925Y148625D01*
X914800Y148958D01*
X914633Y149208D01*
X914383Y149417D01*
X914050Y149500D01*
G01X903767Y135400D02*
Y137900D01*
X904808D01*
X905142Y137775D01*
X905350Y137608D01*
X905433Y137275D01*
X905350Y136942D01*
X905100Y136733D01*
X904808Y136608D01*
X903767D01*
G01X904808D02*
X905433Y135400D01*
G01X906908Y136442D02*
X907200Y136733D01*
X907450Y136900D01*
X907783Y136983D01*
X908075Y136900D01*
X908283Y136733D01*
X908450Y136483D01*
X908492Y136192D01*
X908450Y135942D01*
X908283Y135692D01*
X908033Y135483D01*
X907742Y135400D01*
X907408Y135483D01*
X907117Y135733D01*
X906950Y136108D01*
X906908Y136525D01*
X906992Y137067D01*
X907117Y137358D01*
X907325Y137650D01*
X907617Y137858D01*
X907908Y137900D01*
X908200Y137817D01*
X908408Y137608D01*
G01X909883Y135400D02*
Y137900D01*
X910717D01*
X911050Y137775D01*
X911300Y137608D01*
X911508Y137358D01*
X911675Y137067D01*
X911717Y136650D01*
X911675Y136233D01*
X911508Y135942D01*
X911300Y135692D01*
X911050Y135525D01*
X910717Y135400D01*
X909883D01*
G01X913900D02*
Y137900D01*
X913400Y137400D01*
G01Y135400D02*
X914400D01*
G01X916208Y137483D02*
X916458Y137733D01*
X916750Y137858D01*
X917083Y137900D01*
X917500Y137817D01*
X917792Y137608D01*
X917875Y137358D01*
X917833Y137108D01*
X917667Y136900D01*
X916833Y136483D01*
X916458Y136192D01*
X916208Y135775D01*
X916125Y135400D01*
X917875D01*
G01X900817Y150400D02*
Y152900D01*
X901858D01*
X902192Y152775D01*
X902400Y152608D01*
X902483Y152275D01*
X902400Y151942D01*
X902150Y151733D01*
X901858Y151608D01*
X900817D01*
G01X901858D02*
X902483Y150400D01*
G01X903958Y151442D02*
X904250Y151733D01*
X904500Y151900D01*
X904833Y151983D01*
X905125Y151900D01*
X905333Y151733D01*
X905500Y151483D01*
X905542Y151192D01*
X905500Y150942D01*
X905333Y150692D01*
X905083Y150483D01*
X904792Y150400D01*
X904458Y150483D01*
X904167Y150733D01*
X904000Y151108D01*
X903958Y151525D01*
X904042Y152067D01*
X904167Y152358D01*
X904375Y152650D01*
X904667Y152858D01*
X904958Y152900D01*
X905250Y152817D01*
X905458Y152608D01*
G01X906933Y150400D02*
Y152900D01*
X907767D01*
X908100Y152775D01*
X908350Y152608D01*
X908558Y152358D01*
X908725Y152067D01*
X908767Y151650D01*
X908725Y151233D01*
X908558Y150942D01*
X908350Y150692D01*
X908100Y150525D01*
X907767Y150400D01*
X906933D01*
G01X910242Y150692D02*
X910533Y150483D01*
X910867Y150400D01*
X911200Y150483D01*
X911492Y150733D01*
X911700Y151108D01*
X911783Y151483D01*
Y151942D01*
X911700Y152317D01*
X911492Y152650D01*
X911242Y152817D01*
X910950Y152900D01*
X910617Y152817D01*
X910367Y152650D01*
X910200Y152400D01*
X910117Y152067D01*
X910200Y151775D01*
X910408Y151483D01*
X910658Y151317D01*
X910950Y151275D01*
X911283Y151358D01*
X911533Y151567D01*
X911783Y151942D01*
G01X900817Y153800D02*
Y156300D01*
X901858D01*
X902192Y156175D01*
X902400Y156008D01*
X902483Y155675D01*
X902400Y155342D01*
X902150Y155133D01*
X901858Y155008D01*
X900817D01*
G01X901858D02*
X902483Y153800D01*
G01X903958Y154842D02*
X904250Y155133D01*
X904500Y155300D01*
X904833Y155383D01*
X905125Y155300D01*
X905333Y155133D01*
X905500Y154883D01*
X905542Y154592D01*
X905500Y154342D01*
X905333Y154092D01*
X905083Y153883D01*
X904792Y153800D01*
X904458Y153883D01*
X904167Y154133D01*
X904000Y154508D01*
X903958Y154925D01*
X904042Y155467D01*
X904167Y155758D01*
X904375Y156050D01*
X904667Y156258D01*
X904958Y156300D01*
X905250Y156217D01*
X905458Y156008D01*
G01X906933Y153800D02*
Y156300D01*
X907767D01*
X908100Y156175D01*
X908350Y156008D01*
X908558Y155758D01*
X908725Y155467D01*
X908767Y155050D01*
X908725Y154633D01*
X908558Y154342D01*
X908350Y154092D01*
X908100Y153925D01*
X907767Y153800D01*
X906933D01*
G01X910950D02*
X911242Y153842D01*
X911575Y153967D01*
X911783Y154175D01*
X911867Y154467D01*
X911783Y154758D01*
X911533Y155008D01*
X911158Y155133D01*
X910742D01*
X910492Y155217D01*
X910283Y155425D01*
X910200Y155717D01*
X910325Y156008D01*
X910617Y156217D01*
X910950Y156300D01*
X911283Y156217D01*
X911575Y156008D01*
X911700Y155717D01*
X911617Y155425D01*
X911408Y155217D01*
X911158Y155133D01*
X910742D01*
X910367Y155008D01*
X910117Y154758D01*
X910033Y154467D01*
X910117Y154175D01*
X910325Y153967D01*
X910658Y153842D01*
X910950Y153800D01*
G01X900817Y143600D02*
Y146100D01*
X901858D01*
X902192Y145975D01*
X902400Y145808D01*
X902483Y145475D01*
X902400Y145142D01*
X902150Y144933D01*
X901858Y144808D01*
X900817D01*
G01X901858D02*
X902483Y143600D01*
G01X903958Y144642D02*
X904250Y144933D01*
X904500Y145100D01*
X904833Y145183D01*
X905125Y145100D01*
X905333Y144933D01*
X905500Y144683D01*
X905542Y144392D01*
X905500Y144142D01*
X905333Y143892D01*
X905083Y143683D01*
X904792Y143600D01*
X904458Y143683D01*
X904167Y143933D01*
X904000Y144308D01*
X903958Y144725D01*
X904042Y145267D01*
X904167Y145558D01*
X904375Y145850D01*
X904667Y146058D01*
X904958Y146100D01*
X905250Y146017D01*
X905458Y145808D01*
G01X906933Y143600D02*
Y146100D01*
X907767D01*
X908100Y145975D01*
X908350Y145808D01*
X908558Y145558D01*
X908725Y145267D01*
X908767Y144850D01*
X908725Y144433D01*
X908558Y144142D01*
X908350Y143892D01*
X908100Y143725D01*
X907767Y143600D01*
X906933D01*
G01X910950D02*
Y146100D01*
X910450Y145600D01*
G01Y143600D02*
X911450D01*
G01X914050D02*
Y146100D01*
X913550Y145600D01*
G01Y143600D02*
X914550D01*
G01X893200Y125867D02*
X890700D01*
Y126908D01*
X890825Y127242D01*
X890992Y127450D01*
X891325Y127533D01*
X891658Y127450D01*
X891867Y127200D01*
X891992Y126908D01*
Y125867D01*
G01Y126908D02*
X893200Y127533D01*
G01X892158Y129008D02*
X891867Y129300D01*
X891700Y129550D01*
X891617Y129883D01*
X891700Y130175D01*
X891867Y130383D01*
X892117Y130550D01*
X892408Y130592D01*
X892658Y130550D01*
X892908Y130383D01*
X893117Y130133D01*
X893200Y129842D01*
X893117Y129508D01*
X892867Y129217D01*
X892492Y129050D01*
X892075Y129008D01*
X891533Y129092D01*
X891242Y129217D01*
X890950Y129425D01*
X890742Y129717D01*
X890700Y130008D01*
X890783Y130300D01*
X890992Y130508D01*
G01X893200Y131983D02*
X890700D01*
Y132817D01*
X890825Y133150D01*
X890992Y133400D01*
X891242Y133608D01*
X891533Y133775D01*
X891950Y133817D01*
X892367Y133775D01*
X892658Y133608D01*
X892908Y133400D01*
X893075Y133150D01*
X893200Y132817D01*
Y131983D01*
G01Y136000D02*
X890700D01*
X891200Y135500D01*
G01X893200D02*
Y136500D01*
G01X892825Y138183D02*
X893033Y138433D01*
X893158Y138725D01*
X893200Y139100D01*
X893117Y139475D01*
X892950Y139767D01*
X892658Y139975D01*
X892325Y140017D01*
X891992Y139933D01*
X891783Y139725D01*
X891617Y139433D01*
X891575Y139142D01*
X891617Y138850D01*
X891783Y138475D01*
X890700Y138600D01*
Y139725D01*
G01X897000Y127467D02*
X894500D01*
Y128508D01*
X894625Y128842D01*
X894792Y129050D01*
X895125Y129133D01*
X895458Y129050D01*
X895667Y128800D01*
X895792Y128508D01*
Y127467D01*
G01Y128508D02*
X897000Y129133D01*
G01X895958Y130608D02*
X895667Y130900D01*
X895500Y131150D01*
X895417Y131483D01*
X895500Y131775D01*
X895667Y131983D01*
X895917Y132150D01*
X896208Y132192D01*
X896458Y132150D01*
X896708Y131983D01*
X896917Y131733D01*
X897000Y131442D01*
X896917Y131108D01*
X896667Y130817D01*
X896292Y130650D01*
X895875Y130608D01*
X895333Y130692D01*
X895042Y130817D01*
X894750Y131025D01*
X894542Y131317D01*
X894500Y131608D01*
X894583Y131900D01*
X894792Y132108D01*
G01X897000Y133583D02*
X894500D01*
Y134417D01*
X894625Y134750D01*
X894792Y135000D01*
X895042Y135208D01*
X895333Y135375D01*
X895750Y135417D01*
X896167Y135375D01*
X896458Y135208D01*
X896708Y135000D01*
X896875Y134750D01*
X897000Y134417D01*
Y133583D01*
G01Y137600D02*
X894500D01*
X895000Y137100D01*
G01X897000D02*
Y138100D01*
G01Y141200D02*
X894500D01*
X896292Y139658D01*
Y141742D01*
G01X882417Y121500D02*
Y124000D01*
X883458D01*
X883792Y123875D01*
X884000Y123708D01*
X884083Y123375D01*
X884000Y123042D01*
X883750Y122833D01*
X883458Y122708D01*
X882417D01*
G01X883458D02*
X884083Y121500D01*
G01X885433Y121875D02*
X885683Y121667D01*
X885975Y121542D01*
X886350Y121500D01*
X886725Y121583D01*
X887017Y121750D01*
X887225Y122042D01*
X887267Y122375D01*
X887183Y122708D01*
X886975Y122917D01*
X886683Y123083D01*
X886392Y123125D01*
X886100Y123083D01*
X885725Y122917D01*
X885850Y124000D01*
X886975D01*
G01X888533Y121500D02*
Y124000D01*
X889367D01*
X889700Y123875D01*
X889950Y123708D01*
X890158Y123458D01*
X890325Y123167D01*
X890367Y122750D01*
X890325Y122333D01*
X890158Y122042D01*
X889950Y121792D01*
X889700Y121625D01*
X889367Y121500D01*
X888533D01*
G01X891633Y121875D02*
X891883Y121667D01*
X892175Y121542D01*
X892550Y121500D01*
X892925Y121583D01*
X893217Y121750D01*
X893425Y122042D01*
X893467Y122375D01*
X893383Y122708D01*
X893175Y122917D01*
X892883Y123083D01*
X892592Y123125D01*
X892300Y123083D01*
X891925Y122917D01*
X892050Y124000D01*
X893175D01*
G01X882800Y126067D02*
X880300D01*
Y127108D01*
X880425Y127442D01*
X880592Y127650D01*
X880925Y127733D01*
X881258Y127650D01*
X881467Y127400D01*
X881592Y127108D01*
Y126067D01*
G01Y127108D02*
X882800Y127733D01*
G01X882425Y129083D02*
X882633Y129333D01*
X882758Y129625D01*
X882800Y130000D01*
X882717Y130375D01*
X882550Y130667D01*
X882258Y130875D01*
X881925Y130917D01*
X881592Y130833D01*
X881383Y130625D01*
X881217Y130333D01*
X881175Y130042D01*
X881217Y129750D01*
X881383Y129375D01*
X880300Y129500D01*
Y130625D01*
G01X882800Y132183D02*
X880300D01*
Y133017D01*
X880425Y133350D01*
X880592Y133600D01*
X880842Y133808D01*
X881133Y133975D01*
X881550Y134017D01*
X881967Y133975D01*
X882258Y133808D01*
X882508Y133600D01*
X882675Y133350D01*
X882800Y133017D01*
Y132183D01*
G01Y136700D02*
X880300D01*
X882092Y135158D01*
Y137242D01*
G01X876729Y108496D02*
X874229D01*
Y109537D01*
X874354Y109871D01*
X874521Y110079D01*
X874854Y110162D01*
X875187Y110079D01*
X875396Y109829D01*
X875521Y109537D01*
Y108496D01*
G01Y109537D02*
X876729Y110162D01*
G01Y112929D02*
X874229D01*
X876021Y111387D01*
Y113471D01*
G01X875479Y115779D02*
Y116612D01*
X876229D01*
X876479Y116362D01*
X876646Y116071D01*
X876729Y115654D01*
X876646Y115237D01*
X876479Y114946D01*
X876229Y114696D01*
X875937Y114529D01*
X875604Y114446D01*
X875312D01*
X875062Y114529D01*
X874771Y114696D01*
X874521Y114946D01*
X874354Y115196D01*
X874229Y115529D01*
Y115821D01*
X874312Y116154D01*
X874479Y116404D01*
G01X876729Y118629D02*
X874229D01*
X874729Y118129D01*
G01X876729D02*
Y119129D01*
G01X874646Y120937D02*
X874396Y121187D01*
X874271Y121479D01*
X874229Y121812D01*
X874312Y122229D01*
X874521Y122521D01*
X874771Y122604D01*
X875021Y122562D01*
X875229Y122396D01*
X875646Y121562D01*
X875937Y121187D01*
X876354Y120937D01*
X876729Y120854D01*
Y122604D01*
G01X873329Y108496D02*
X870829D01*
Y109537D01*
X870954Y109871D01*
X871121Y110079D01*
X871454Y110162D01*
X871787Y110079D01*
X871996Y109829D01*
X872121Y109537D01*
Y108496D01*
G01Y109537D02*
X873329Y110162D01*
G01Y112929D02*
X870829D01*
X872621Y111387D01*
Y113471D01*
G01X872079Y115779D02*
Y116612D01*
X872829D01*
X873079Y116362D01*
X873246Y116071D01*
X873329Y115654D01*
X873246Y115237D01*
X873079Y114946D01*
X872829Y114696D01*
X872537Y114529D01*
X872204Y114446D01*
X871912D01*
X871662Y114529D01*
X871371Y114696D01*
X871121Y114946D01*
X870954Y115196D01*
X870829Y115529D01*
Y115821D01*
X870912Y116154D01*
X871079Y116404D01*
G01X873329Y118629D02*
X870829D01*
X871329Y118129D01*
G01X873329D02*
Y119129D01*
G01Y122229D02*
X870829D01*
X872621Y120687D01*
Y122771D01*
G01X863928Y109295D02*
X861428D01*
Y110336D01*
X861553Y110670D01*
X861720Y110878D01*
X862053Y110961D01*
X862386Y110878D01*
X862595Y110628D01*
X862720Y110336D01*
Y109295D01*
G01Y110336D02*
X863928Y110961D01*
G01Y113728D02*
X861428D01*
X863220Y112186D01*
Y114270D01*
G01X862678Y116578D02*
Y117411D01*
X863428D01*
X863678Y117161D01*
X863845Y116870D01*
X863928Y116453D01*
X863845Y116036D01*
X863678Y115745D01*
X863428Y115495D01*
X863136Y115328D01*
X862803Y115245D01*
X862511D01*
X862261Y115328D01*
X861970Y115495D01*
X861720Y115745D01*
X861553Y115995D01*
X861428Y116328D01*
Y116620D01*
X861511Y116953D01*
X861678Y117203D01*
G01X863928Y119428D02*
X861428D01*
X861928Y118928D01*
G01X863928D02*
Y119928D01*
G01Y122528D02*
X861428D01*
X861928Y122028D01*
G01X863928D02*
Y123028D01*
G01X896508Y144817D02*
X896383Y144567D01*
X896300Y144275D01*
Y143942D01*
X896425Y143567D01*
X896633Y143275D01*
X896883Y143067D01*
X897300Y142900D01*
X897675Y142858D01*
X898050Y142942D01*
X898300Y143067D01*
X898550Y143317D01*
X898717Y143608D01*
X898800Y143900D01*
Y144192D01*
X898717Y144483D01*
X898592Y144733D01*
X898425Y144942D01*
G01X897758Y146208D02*
X897467Y146500D01*
X897300Y146750D01*
X897217Y147083D01*
X897300Y147375D01*
X897467Y147583D01*
X897717Y147750D01*
X898008Y147792D01*
X898258Y147750D01*
X898508Y147583D01*
X898717Y147333D01*
X898800Y147042D01*
X898717Y146708D01*
X898467Y146417D01*
X898092Y146250D01*
X897675Y146208D01*
X897133Y146292D01*
X896842Y146417D01*
X896550Y146625D01*
X896342Y146917D01*
X896300Y147208D01*
X896383Y147500D01*
X896592Y147708D01*
G01X898800Y149183D02*
X896300D01*
Y150017D01*
X896425Y150350D01*
X896592Y150600D01*
X896842Y150808D01*
X897133Y150975D01*
X897550Y151017D01*
X897967Y150975D01*
X898258Y150808D01*
X898508Y150600D01*
X898675Y150350D01*
X898800Y150017D01*
Y149183D01*
G01Y153200D02*
X896300D01*
X896800Y152700D01*
G01X898800D02*
Y153700D01*
G01X896300Y156300D02*
X896383Y155967D01*
X896592Y155717D01*
X896842Y155550D01*
X897175Y155425D01*
X897550Y155383D01*
X897925Y155425D01*
X898258Y155550D01*
X898508Y155717D01*
X898717Y155967D01*
X898800Y156300D01*
X898717Y156633D01*
X898508Y156883D01*
X898258Y157050D01*
X897925Y157175D01*
X897550Y157217D01*
X897175Y157175D01*
X896842Y157050D01*
X896592Y156883D01*
X896383Y156633D01*
X896300Y156300D01*
G01X893108Y144817D02*
X892983Y144567D01*
X892900Y144275D01*
Y143942D01*
X893025Y143567D01*
X893233Y143275D01*
X893483Y143067D01*
X893900Y142900D01*
X894275Y142858D01*
X894650Y142942D01*
X894900Y143067D01*
X895150Y143317D01*
X895317Y143608D01*
X895400Y143900D01*
Y144192D01*
X895317Y144483D01*
X895192Y144733D01*
X895025Y144942D01*
G01X894358Y146208D02*
X894067Y146500D01*
X893900Y146750D01*
X893817Y147083D01*
X893900Y147375D01*
X894067Y147583D01*
X894317Y147750D01*
X894608Y147792D01*
X894858Y147750D01*
X895108Y147583D01*
X895317Y147333D01*
X895400Y147042D01*
X895317Y146708D01*
X895067Y146417D01*
X894692Y146250D01*
X894275Y146208D01*
X893733Y146292D01*
X893442Y146417D01*
X893150Y146625D01*
X892942Y146917D01*
X892900Y147208D01*
X892983Y147500D01*
X893192Y147708D01*
G01X895400Y149183D02*
X892900D01*
Y150017D01*
X893025Y150350D01*
X893192Y150600D01*
X893442Y150808D01*
X893733Y150975D01*
X894150Y151017D01*
X894567Y150975D01*
X894858Y150808D01*
X895108Y150600D01*
X895275Y150350D01*
X895400Y150017D01*
Y149183D01*
G01X895108Y152492D02*
X895317Y152783D01*
X895400Y153117D01*
X895317Y153450D01*
X895067Y153742D01*
X894692Y153950D01*
X894317Y154033D01*
X893858D01*
X893483Y153950D01*
X893150Y153742D01*
X892983Y153492D01*
X892900Y153200D01*
X892983Y152867D01*
X893150Y152617D01*
X893400Y152450D01*
X893733Y152367D01*
X894025Y152450D01*
X894317Y152658D01*
X894483Y152908D01*
X894525Y153200D01*
X894442Y153533D01*
X894233Y153783D01*
X893858Y154033D01*
G01X888908Y143817D02*
X888783Y143567D01*
X888700Y143275D01*
Y142942D01*
X888825Y142567D01*
X889033Y142275D01*
X889283Y142067D01*
X889700Y141900D01*
X890075Y141858D01*
X890450Y141942D01*
X890700Y142067D01*
X890950Y142317D01*
X891117Y142608D01*
X891200Y142900D01*
Y143192D01*
X891117Y143483D01*
X890992Y143733D01*
X890825Y143942D01*
G01X890158Y145208D02*
X889867Y145500D01*
X889700Y145750D01*
X889617Y146083D01*
X889700Y146375D01*
X889867Y146583D01*
X890117Y146750D01*
X890408Y146792D01*
X890658Y146750D01*
X890908Y146583D01*
X891117Y146333D01*
X891200Y146042D01*
X891117Y145708D01*
X890867Y145417D01*
X890492Y145250D01*
X890075Y145208D01*
X889533Y145292D01*
X889242Y145417D01*
X888950Y145625D01*
X888742Y145917D01*
X888700Y146208D01*
X888783Y146500D01*
X888992Y146708D01*
G01X891200Y148183D02*
X888700D01*
Y149017D01*
X888825Y149350D01*
X888992Y149600D01*
X889242Y149808D01*
X889533Y149975D01*
X889950Y150017D01*
X890367Y149975D01*
X890658Y149808D01*
X890908Y149600D01*
X891075Y149350D01*
X891200Y149017D01*
Y148183D01*
G01Y152200D02*
X891158Y152492D01*
X891033Y152825D01*
X890825Y153033D01*
X890533Y153117D01*
X890242Y153033D01*
X889992Y152783D01*
X889867Y152408D01*
Y151992D01*
X889783Y151742D01*
X889575Y151533D01*
X889283Y151450D01*
X888992Y151575D01*
X888783Y151867D01*
X888700Y152200D01*
X888783Y152533D01*
X888992Y152825D01*
X889283Y152950D01*
X889575Y152867D01*
X889783Y152658D01*
X889867Y152408D01*
Y151992D01*
X889992Y151617D01*
X890242Y151367D01*
X890533Y151283D01*
X890825Y151367D01*
X891033Y151575D01*
X891158Y151908D01*
X891200Y152200D01*
G01X885508Y143817D02*
X885383Y143567D01*
X885300Y143275D01*
Y142942D01*
X885425Y142567D01*
X885633Y142275D01*
X885883Y142067D01*
X886300Y141900D01*
X886675Y141858D01*
X887050Y141942D01*
X887300Y142067D01*
X887550Y142317D01*
X887717Y142608D01*
X887800Y142900D01*
Y143192D01*
X887717Y143483D01*
X887592Y143733D01*
X887425Y143942D01*
G01Y145083D02*
X887633Y145333D01*
X887758Y145625D01*
X887800Y146000D01*
X887717Y146375D01*
X887550Y146667D01*
X887258Y146875D01*
X886925Y146917D01*
X886592Y146833D01*
X886383Y146625D01*
X886217Y146333D01*
X886175Y146042D01*
X886217Y145750D01*
X886383Y145375D01*
X885300Y145500D01*
Y146625D01*
G01X887800Y148183D02*
X885300D01*
Y149017D01*
X885425Y149350D01*
X885592Y149600D01*
X885842Y149808D01*
X886133Y149975D01*
X886550Y150017D01*
X886967Y149975D01*
X887258Y149808D01*
X887508Y149600D01*
X887675Y149350D01*
X887800Y149017D01*
Y148183D01*
G01X887425Y151283D02*
X887633Y151533D01*
X887758Y151825D01*
X887800Y152200D01*
X887717Y152575D01*
X887550Y152867D01*
X887258Y153075D01*
X886925Y153117D01*
X886592Y153033D01*
X886383Y152825D01*
X886217Y152533D01*
X886175Y152242D01*
X886217Y151950D01*
X886383Y151575D01*
X885300Y151700D01*
Y152825D01*
G01Y155300D02*
X885383Y154967D01*
X885592Y154717D01*
X885842Y154550D01*
X886175Y154425D01*
X886550Y154383D01*
X886925Y154425D01*
X887258Y154550D01*
X887508Y154717D01*
X887717Y154967D01*
X887800Y155300D01*
X887717Y155633D01*
X887508Y155883D01*
X887258Y156050D01*
X886925Y156175D01*
X886550Y156217D01*
X886175Y156175D01*
X885842Y156050D01*
X885592Y155883D01*
X885383Y155633D01*
X885300Y155300D01*
G01X882108Y143817D02*
X881983Y143567D01*
X881900Y143275D01*
Y142942D01*
X882025Y142567D01*
X882233Y142275D01*
X882483Y142067D01*
X882900Y141900D01*
X883275Y141858D01*
X883650Y141942D01*
X883900Y142067D01*
X884150Y142317D01*
X884317Y142608D01*
X884400Y142900D01*
Y143192D01*
X884317Y143483D01*
X884192Y143733D01*
X884025Y143942D01*
G01Y145083D02*
X884233Y145333D01*
X884358Y145625D01*
X884400Y146000D01*
X884317Y146375D01*
X884150Y146667D01*
X883858Y146875D01*
X883525Y146917D01*
X883192Y146833D01*
X882983Y146625D01*
X882817Y146333D01*
X882775Y146042D01*
X882817Y145750D01*
X882983Y145375D01*
X881900Y145500D01*
Y146625D01*
G01X884400Y148183D02*
X881900D01*
Y149017D01*
X882025Y149350D01*
X882192Y149600D01*
X882442Y149808D01*
X882733Y149975D01*
X883150Y150017D01*
X883567Y149975D01*
X883858Y149808D01*
X884108Y149600D01*
X884275Y149350D01*
X884400Y149017D01*
Y148183D01*
G01Y152700D02*
X881900D01*
X883692Y151158D01*
Y153242D01*
G01X884108Y154592D02*
X884317Y154883D01*
X884400Y155217D01*
X884317Y155550D01*
X884067Y155842D01*
X883692Y156050D01*
X883317Y156133D01*
X882858D01*
X882483Y156050D01*
X882150Y155842D01*
X881983Y155592D01*
X881900Y155300D01*
X881983Y154967D01*
X882150Y154717D01*
X882400Y154550D01*
X882733Y154467D01*
X883025Y154550D01*
X883317Y154758D01*
X883483Y155008D01*
X883525Y155300D01*
X883442Y155633D01*
X883233Y155883D01*
X882858Y156133D01*
G01X876308Y143617D02*
X876183Y143367D01*
X876100Y143075D01*
Y142742D01*
X876225Y142367D01*
X876433Y142075D01*
X876683Y141867D01*
X877100Y141700D01*
X877475Y141658D01*
X877850Y141742D01*
X878100Y141867D01*
X878350Y142117D01*
X878517Y142408D01*
X878600Y142700D01*
Y142992D01*
X878517Y143283D01*
X878392Y143533D01*
X878225Y143742D01*
G01Y144883D02*
X878433Y145133D01*
X878558Y145425D01*
X878600Y145800D01*
X878517Y146175D01*
X878350Y146467D01*
X878058Y146675D01*
X877725Y146717D01*
X877392Y146633D01*
X877183Y146425D01*
X877017Y146133D01*
X876975Y145842D01*
X877017Y145550D01*
X877183Y145175D01*
X876100Y145300D01*
Y146425D01*
G01X878600Y147983D02*
X876100D01*
Y148817D01*
X876225Y149150D01*
X876392Y149400D01*
X876642Y149608D01*
X876933Y149775D01*
X877350Y149817D01*
X877767Y149775D01*
X878058Y149608D01*
X878308Y149400D01*
X878475Y149150D01*
X878600Y148817D01*
Y147983D01*
G01Y152500D02*
X876100D01*
X877892Y150958D01*
Y153042D01*
G01X878600Y155100D02*
X878558Y155392D01*
X878433Y155725D01*
X878225Y155933D01*
X877933Y156017D01*
X877642Y155933D01*
X877392Y155683D01*
X877267Y155308D01*
Y154892D01*
X877183Y154642D01*
X876975Y154433D01*
X876683Y154350D01*
X876392Y154475D01*
X876183Y154767D01*
X876100Y155100D01*
X876183Y155433D01*
X876392Y155725D01*
X876683Y155850D01*
X876975Y155767D01*
X877183Y155558D01*
X877267Y155308D01*
Y154892D01*
X877392Y154517D01*
X877642Y154267D01*
X877933Y154183D01*
X878225Y154267D01*
X878433Y154475D01*
X878558Y154808D01*
X878600Y155100D01*
G01X872908Y143617D02*
X872783Y143367D01*
X872700Y143075D01*
Y142742D01*
X872825Y142367D01*
X873033Y142075D01*
X873283Y141867D01*
X873700Y141700D01*
X874075Y141658D01*
X874450Y141742D01*
X874700Y141867D01*
X874950Y142117D01*
X875117Y142408D01*
X875200Y142700D01*
Y142992D01*
X875117Y143283D01*
X874992Y143533D01*
X874825Y143742D01*
G01Y144883D02*
X875033Y145133D01*
X875158Y145425D01*
X875200Y145800D01*
X875117Y146175D01*
X874950Y146467D01*
X874658Y146675D01*
X874325Y146717D01*
X873992Y146633D01*
X873783Y146425D01*
X873617Y146133D01*
X873575Y145842D01*
X873617Y145550D01*
X873783Y145175D01*
X872700Y145300D01*
Y146425D01*
G01X875200Y147983D02*
X872700D01*
Y148817D01*
X872825Y149150D01*
X872992Y149400D01*
X873242Y149608D01*
X873533Y149775D01*
X873950Y149817D01*
X874367Y149775D01*
X874658Y149608D01*
X874908Y149400D01*
X875075Y149150D01*
X875200Y148817D01*
Y147983D01*
G01X874825Y151083D02*
X875033Y151333D01*
X875158Y151625D01*
X875200Y152000D01*
X875117Y152375D01*
X874950Y152667D01*
X874658Y152875D01*
X874325Y152917D01*
X873992Y152833D01*
X873783Y152625D01*
X873617Y152333D01*
X873575Y152042D01*
X873617Y151750D01*
X873783Y151375D01*
X872700Y151500D01*
Y152625D01*
G01X874700Y154183D02*
X874992Y154433D01*
X875158Y154767D01*
X875200Y155142D01*
X875158Y155475D01*
X874950Y155808D01*
X874700Y156017D01*
X874450Y156058D01*
X874158Y155975D01*
X873950Y155683D01*
X873867Y155392D01*
Y155017D01*
G01Y155392D02*
X873742Y155642D01*
X873533Y155850D01*
X873283Y155933D01*
X873033Y155850D01*
X872825Y155642D01*
X872700Y155267D01*
X872742Y154892D01*
X872908Y154517D01*
G01X869508Y143617D02*
X869383Y143367D01*
X869300Y143075D01*
Y142742D01*
X869425Y142367D01*
X869633Y142075D01*
X869883Y141867D01*
X870300Y141700D01*
X870675Y141658D01*
X871050Y141742D01*
X871300Y141867D01*
X871550Y142117D01*
X871717Y142408D01*
X871800Y142700D01*
Y142992D01*
X871717Y143283D01*
X871592Y143533D01*
X871425Y143742D01*
G01Y144883D02*
X871633Y145133D01*
X871758Y145425D01*
X871800Y145800D01*
X871717Y146175D01*
X871550Y146467D01*
X871258Y146675D01*
X870925Y146717D01*
X870592Y146633D01*
X870383Y146425D01*
X870217Y146133D01*
X870175Y145842D01*
X870217Y145550D01*
X870383Y145175D01*
X869300Y145300D01*
Y146425D01*
G01X871800Y147983D02*
X869300D01*
Y148817D01*
X869425Y149150D01*
X869592Y149400D01*
X869842Y149608D01*
X870133Y149775D01*
X870550Y149817D01*
X870967Y149775D01*
X871258Y149608D01*
X871508Y149400D01*
X871675Y149150D01*
X871800Y148817D01*
Y147983D01*
G01X871425Y151083D02*
X871633Y151333D01*
X871758Y151625D01*
X871800Y152000D01*
X871717Y152375D01*
X871550Y152667D01*
X871258Y152875D01*
X870925Y152917D01*
X870592Y152833D01*
X870383Y152625D01*
X870217Y152333D01*
X870175Y152042D01*
X870217Y151750D01*
X870383Y151375D01*
X869300Y151500D01*
Y152625D01*
G01X869717Y154308D02*
X869467Y154558D01*
X869342Y154850D01*
X869300Y155183D01*
X869383Y155600D01*
X869592Y155892D01*
X869842Y155975D01*
X870092Y155933D01*
X870300Y155767D01*
X870717Y154933D01*
X871008Y154558D01*
X871425Y154308D01*
X871800Y154225D01*
Y155975D01*
G01X863508Y127817D02*
X863383Y127567D01*
X863300Y127275D01*
Y126942D01*
X863425Y126567D01*
X863633Y126275D01*
X863883Y126067D01*
X864300Y125900D01*
X864675Y125858D01*
X865050Y125942D01*
X865300Y126067D01*
X865550Y126317D01*
X865717Y126608D01*
X865800Y126900D01*
Y127192D01*
X865717Y127483D01*
X865592Y127733D01*
X865425Y127942D01*
G01Y129083D02*
X865633Y129333D01*
X865758Y129625D01*
X865800Y130000D01*
X865717Y130375D01*
X865550Y130667D01*
X865258Y130875D01*
X864925Y130917D01*
X864592Y130833D01*
X864383Y130625D01*
X864217Y130333D01*
X864175Y130042D01*
X864217Y129750D01*
X864383Y129375D01*
X863300Y129500D01*
Y130625D01*
G01X865800Y132183D02*
X863300D01*
Y133017D01*
X863425Y133350D01*
X863592Y133600D01*
X863842Y133808D01*
X864133Y133975D01*
X864550Y134017D01*
X864967Y133975D01*
X865258Y133808D01*
X865508Y133600D01*
X865675Y133350D01*
X865800Y133017D01*
Y132183D01*
G01X865425Y135283D02*
X865633Y135533D01*
X865758Y135825D01*
X865800Y136200D01*
X865717Y136575D01*
X865550Y136867D01*
X865258Y137075D01*
X864925Y137117D01*
X864592Y137033D01*
X864383Y136825D01*
X864217Y136533D01*
X864175Y136242D01*
X864217Y135950D01*
X864383Y135575D01*
X863300Y135700D01*
Y136825D01*
G01X865508Y138592D02*
X865717Y138883D01*
X865800Y139217D01*
X865717Y139550D01*
X865467Y139842D01*
X865092Y140050D01*
X864717Y140133D01*
X864258D01*
X863883Y140050D01*
X863550Y139842D01*
X863383Y139592D01*
X863300Y139300D01*
X863383Y138967D01*
X863550Y138717D01*
X863800Y138550D01*
X864133Y138467D01*
X864425Y138550D01*
X864717Y138758D01*
X864883Y139008D01*
X864925Y139300D01*
X864842Y139633D01*
X864633Y139883D01*
X864258Y140133D01*
G01X870308Y127817D02*
X870183Y127567D01*
X870100Y127275D01*
Y126942D01*
X870225Y126567D01*
X870433Y126275D01*
X870683Y126067D01*
X871100Y125900D01*
X871475Y125858D01*
X871850Y125942D01*
X872100Y126067D01*
X872350Y126317D01*
X872517Y126608D01*
X872600Y126900D01*
Y127192D01*
X872517Y127483D01*
X872392Y127733D01*
X872225Y127942D01*
G01Y129083D02*
X872433Y129333D01*
X872558Y129625D01*
X872600Y130000D01*
X872517Y130375D01*
X872350Y130667D01*
X872058Y130875D01*
X871725Y130917D01*
X871392Y130833D01*
X871183Y130625D01*
X871017Y130333D01*
X870975Y130042D01*
X871017Y129750D01*
X871183Y129375D01*
X870100Y129500D01*
Y130625D01*
G01X872600Y132183D02*
X870100D01*
Y133017D01*
X870225Y133350D01*
X870392Y133600D01*
X870642Y133808D01*
X870933Y133975D01*
X871350Y134017D01*
X871767Y133975D01*
X872058Y133808D01*
X872308Y133600D01*
X872475Y133350D01*
X872600Y133017D01*
Y132183D01*
G01X871558Y135408D02*
X871267Y135700D01*
X871100Y135950D01*
X871017Y136283D01*
X871100Y136575D01*
X871267Y136783D01*
X871517Y136950D01*
X871808Y136992D01*
X872058Y136950D01*
X872308Y136783D01*
X872517Y136533D01*
X872600Y136242D01*
X872517Y135908D01*
X872267Y135617D01*
X871892Y135450D01*
X871475Y135408D01*
X870933Y135492D01*
X870642Y135617D01*
X870350Y135825D01*
X870142Y136117D01*
X870100Y136408D01*
X870183Y136700D01*
X870392Y136908D01*
G01X872600Y139300D02*
X870100D01*
X870600Y138800D01*
G01X872600D02*
Y139800D01*
G01X866908Y127817D02*
X866783Y127567D01*
X866700Y127275D01*
Y126942D01*
X866825Y126567D01*
X867033Y126275D01*
X867283Y126067D01*
X867700Y125900D01*
X868075Y125858D01*
X868450Y125942D01*
X868700Y126067D01*
X868950Y126317D01*
X869117Y126608D01*
X869200Y126900D01*
Y127192D01*
X869117Y127483D01*
X868992Y127733D01*
X868825Y127942D01*
G01Y129083D02*
X869033Y129333D01*
X869158Y129625D01*
X869200Y130000D01*
X869117Y130375D01*
X868950Y130667D01*
X868658Y130875D01*
X868325Y130917D01*
X867992Y130833D01*
X867783Y130625D01*
X867617Y130333D01*
X867575Y130042D01*
X867617Y129750D01*
X867783Y129375D01*
X866700Y129500D01*
Y130625D01*
G01X869200Y132183D02*
X866700D01*
Y133017D01*
X866825Y133350D01*
X866992Y133600D01*
X867242Y133808D01*
X867533Y133975D01*
X867950Y134017D01*
X868367Y133975D01*
X868658Y133808D01*
X868908Y133600D01*
X869075Y133350D01*
X869200Y133017D01*
Y132183D01*
G01X868158Y135408D02*
X867867Y135700D01*
X867700Y135950D01*
X867617Y136283D01*
X867700Y136575D01*
X867867Y136783D01*
X868117Y136950D01*
X868408Y136992D01*
X868658Y136950D01*
X868908Y136783D01*
X869117Y136533D01*
X869200Y136242D01*
X869117Y135908D01*
X868867Y135617D01*
X868492Y135450D01*
X868075Y135408D01*
X867533Y135492D01*
X867242Y135617D01*
X866950Y135825D01*
X866742Y136117D01*
X866700Y136408D01*
X866783Y136700D01*
X866992Y136908D01*
G01X866700Y139300D02*
X866783Y138967D01*
X866992Y138717D01*
X867242Y138550D01*
X867575Y138425D01*
X867950Y138383D01*
X868325Y138425D01*
X868658Y138550D01*
X868908Y138717D01*
X869117Y138967D01*
X869200Y139300D01*
X869117Y139633D01*
X868908Y139883D01*
X868658Y140050D01*
X868325Y140175D01*
X867950Y140217D01*
X867575Y140175D01*
X867242Y140050D01*
X866992Y139883D01*
X866783Y139633D01*
X866700Y139300D01*
G01X854408Y143617D02*
X854283Y143367D01*
X854200Y143075D01*
Y142742D01*
X854325Y142367D01*
X854533Y142075D01*
X854783Y141867D01*
X855200Y141700D01*
X855575Y141658D01*
X855950Y141742D01*
X856200Y141867D01*
X856450Y142117D01*
X856617Y142408D01*
X856700Y142700D01*
Y142992D01*
X856617Y143283D01*
X856492Y143533D01*
X856325Y143742D01*
G01Y144883D02*
X856533Y145133D01*
X856658Y145425D01*
X856700Y145800D01*
X856617Y146175D01*
X856450Y146467D01*
X856158Y146675D01*
X855825Y146717D01*
X855492Y146633D01*
X855283Y146425D01*
X855117Y146133D01*
X855075Y145842D01*
X855117Y145550D01*
X855283Y145175D01*
X854200Y145300D01*
Y146425D01*
G01X856700Y147983D02*
X854200D01*
Y148817D01*
X854325Y149150D01*
X854492Y149400D01*
X854742Y149608D01*
X855033Y149775D01*
X855450Y149817D01*
X855867Y149775D01*
X856158Y149608D01*
X856408Y149400D01*
X856575Y149150D01*
X856700Y148817D01*
Y147983D01*
G01Y152500D02*
X854200D01*
X855992Y150958D01*
Y153042D01*
G01X856325Y154183D02*
X856533Y154433D01*
X856658Y154725D01*
X856700Y155100D01*
X856617Y155475D01*
X856450Y155767D01*
X856158Y155975D01*
X855825Y156017D01*
X855492Y155933D01*
X855283Y155725D01*
X855117Y155433D01*
X855075Y155142D01*
X855117Y154850D01*
X855283Y154475D01*
X854200Y154600D01*
Y155725D01*
G01X851008Y143617D02*
X850883Y143367D01*
X850800Y143075D01*
Y142742D01*
X850925Y142367D01*
X851133Y142075D01*
X851383Y141867D01*
X851800Y141700D01*
X852175Y141658D01*
X852550Y141742D01*
X852800Y141867D01*
X853050Y142117D01*
X853217Y142408D01*
X853300Y142700D01*
Y142992D01*
X853217Y143283D01*
X853092Y143533D01*
X852925Y143742D01*
G01Y144883D02*
X853133Y145133D01*
X853258Y145425D01*
X853300Y145800D01*
X853217Y146175D01*
X853050Y146467D01*
X852758Y146675D01*
X852425Y146717D01*
X852092Y146633D01*
X851883Y146425D01*
X851717Y146133D01*
X851675Y145842D01*
X851717Y145550D01*
X851883Y145175D01*
X850800Y145300D01*
Y146425D01*
G01X853300Y147983D02*
X850800D01*
Y148817D01*
X850925Y149150D01*
X851092Y149400D01*
X851342Y149608D01*
X851633Y149775D01*
X852050Y149817D01*
X852467Y149775D01*
X852758Y149608D01*
X853008Y149400D01*
X853175Y149150D01*
X853300Y148817D01*
Y147983D01*
G01Y152500D02*
X850800D01*
X852592Y150958D01*
Y153042D01*
G01X853300Y155600D02*
X850800D01*
X852592Y154058D01*
Y156142D01*
G01X859608Y126617D02*
X859483Y126367D01*
X859400Y126075D01*
Y125742D01*
X859525Y125367D01*
X859733Y125075D01*
X859983Y124867D01*
X860400Y124700D01*
X860775Y124658D01*
X861150Y124742D01*
X861400Y124867D01*
X861650Y125117D01*
X861817Y125408D01*
X861900Y125700D01*
Y125992D01*
X861817Y126283D01*
X861692Y126533D01*
X861525Y126742D01*
G01Y127883D02*
X861733Y128133D01*
X861858Y128425D01*
X861900Y128800D01*
X861817Y129175D01*
X861650Y129467D01*
X861358Y129675D01*
X861025Y129717D01*
X860692Y129633D01*
X860483Y129425D01*
X860317Y129133D01*
X860275Y128842D01*
X860317Y128550D01*
X860483Y128175D01*
X859400Y128300D01*
Y129425D01*
G01X861900Y130983D02*
X859400D01*
Y131817D01*
X859525Y132150D01*
X859692Y132400D01*
X859942Y132608D01*
X860233Y132775D01*
X860650Y132817D01*
X861067Y132775D01*
X861358Y132608D01*
X861608Y132400D01*
X861775Y132150D01*
X861900Y131817D01*
Y130983D01*
G01X861525Y134083D02*
X861733Y134333D01*
X861858Y134625D01*
X861900Y135000D01*
X861817Y135375D01*
X861650Y135667D01*
X861358Y135875D01*
X861025Y135917D01*
X860692Y135833D01*
X860483Y135625D01*
X860317Y135333D01*
X860275Y135042D01*
X860317Y134750D01*
X860483Y134375D01*
X859400Y134500D01*
Y135625D01*
G01X861900Y138100D02*
X861858Y138392D01*
X861733Y138725D01*
X861525Y138933D01*
X861233Y139017D01*
X860942Y138933D01*
X860692Y138683D01*
X860567Y138308D01*
Y137892D01*
X860483Y137642D01*
X860275Y137433D01*
X859983Y137350D01*
X859692Y137475D01*
X859483Y137767D01*
X859400Y138100D01*
X859483Y138433D01*
X859692Y138725D01*
X859983Y138850D01*
X860275Y138767D01*
X860483Y138558D01*
X860567Y138308D01*
Y137892D01*
X860692Y137517D01*
X860942Y137267D01*
X861233Y137183D01*
X861525Y137267D01*
X861733Y137475D01*
X861858Y137808D01*
X861900Y138100D01*
G01X854908Y127517D02*
X854783Y127267D01*
X854700Y126975D01*
Y126642D01*
X854825Y126267D01*
X855033Y125975D01*
X855283Y125767D01*
X855700Y125600D01*
X856075Y125558D01*
X856450Y125642D01*
X856700Y125767D01*
X856950Y126017D01*
X857117Y126308D01*
X857200Y126600D01*
Y126892D01*
X857117Y127183D01*
X856992Y127433D01*
X856825Y127642D01*
G01Y128783D02*
X857033Y129033D01*
X857158Y129325D01*
X857200Y129700D01*
X857117Y130075D01*
X856950Y130367D01*
X856658Y130575D01*
X856325Y130617D01*
X855992Y130533D01*
X855783Y130325D01*
X855617Y130033D01*
X855575Y129742D01*
X855617Y129450D01*
X855783Y129075D01*
X854700Y129200D01*
Y130325D01*
G01X857200Y131883D02*
X854700D01*
Y132717D01*
X854825Y133050D01*
X854992Y133300D01*
X855242Y133508D01*
X855533Y133675D01*
X855950Y133717D01*
X856367Y133675D01*
X856658Y133508D01*
X856908Y133300D01*
X857075Y133050D01*
X857200Y132717D01*
Y131883D01*
G01X856825Y134983D02*
X857033Y135233D01*
X857158Y135525D01*
X857200Y135900D01*
X857117Y136275D01*
X856950Y136567D01*
X856658Y136775D01*
X856325Y136817D01*
X855992Y136733D01*
X855783Y136525D01*
X855617Y136233D01*
X855575Y135942D01*
X855617Y135650D01*
X855783Y135275D01*
X854700Y135400D01*
Y136525D01*
G01X857200Y138917D02*
X856658Y139000D01*
X856200Y139125D01*
X855783Y139292D01*
X855325Y139500D01*
X854700Y139833D01*
Y138167D01*
G01X866108Y143617D02*
X865983Y143367D01*
X865900Y143075D01*
Y142742D01*
X866025Y142367D01*
X866233Y142075D01*
X866483Y141867D01*
X866900Y141700D01*
X867275Y141658D01*
X867650Y141742D01*
X867900Y141867D01*
X868150Y142117D01*
X868317Y142408D01*
X868400Y142700D01*
Y142992D01*
X868317Y143283D01*
X868192Y143533D01*
X868025Y143742D01*
G01Y144883D02*
X868233Y145133D01*
X868358Y145425D01*
X868400Y145800D01*
X868317Y146175D01*
X868150Y146467D01*
X867858Y146675D01*
X867525Y146717D01*
X867192Y146633D01*
X866983Y146425D01*
X866817Y146133D01*
X866775Y145842D01*
X866817Y145550D01*
X866983Y145175D01*
X865900Y145300D01*
Y146425D01*
G01X868400Y147983D02*
X865900D01*
Y148817D01*
X866025Y149150D01*
X866192Y149400D01*
X866442Y149608D01*
X866733Y149775D01*
X867150Y149817D01*
X867567Y149775D01*
X867858Y149608D01*
X868108Y149400D01*
X868275Y149150D01*
X868400Y148817D01*
Y147983D01*
G01X868025Y151083D02*
X868233Y151333D01*
X868358Y151625D01*
X868400Y152000D01*
X868317Y152375D01*
X868150Y152667D01*
X867858Y152875D01*
X867525Y152917D01*
X867192Y152833D01*
X866983Y152625D01*
X866817Y152333D01*
X866775Y152042D01*
X866817Y151750D01*
X866983Y151375D01*
X865900Y151500D01*
Y152625D01*
G01X868400Y155100D02*
X865900D01*
X866400Y154600D01*
G01X868400D02*
Y155600D01*
G01X862708Y143617D02*
X862583Y143367D01*
X862500Y143075D01*
Y142742D01*
X862625Y142367D01*
X862833Y142075D01*
X863083Y141867D01*
X863500Y141700D01*
X863875Y141658D01*
X864250Y141742D01*
X864500Y141867D01*
X864750Y142117D01*
X864917Y142408D01*
X865000Y142700D01*
Y142992D01*
X864917Y143283D01*
X864792Y143533D01*
X864625Y143742D01*
G01Y144883D02*
X864833Y145133D01*
X864958Y145425D01*
X865000Y145800D01*
X864917Y146175D01*
X864750Y146467D01*
X864458Y146675D01*
X864125Y146717D01*
X863792Y146633D01*
X863583Y146425D01*
X863417Y146133D01*
X863375Y145842D01*
X863417Y145550D01*
X863583Y145175D01*
X862500Y145300D01*
Y146425D01*
G01X865000Y147983D02*
X862500D01*
Y148817D01*
X862625Y149150D01*
X862792Y149400D01*
X863042Y149608D01*
X863333Y149775D01*
X863750Y149817D01*
X864167Y149775D01*
X864458Y149608D01*
X864708Y149400D01*
X864875Y149150D01*
X865000Y148817D01*
Y147983D01*
G01Y152500D02*
X862500D01*
X864292Y150958D01*
Y153042D01*
G01X865000Y155017D02*
X864458Y155100D01*
X864000Y155225D01*
X863583Y155392D01*
X863125Y155600D01*
X862500Y155933D01*
Y154267D01*
G01X857808Y143617D02*
X857683Y143367D01*
X857600Y143075D01*
Y142742D01*
X857725Y142367D01*
X857933Y142075D01*
X858183Y141867D01*
X858600Y141700D01*
X858975Y141658D01*
X859350Y141742D01*
X859600Y141867D01*
X859850Y142117D01*
X860017Y142408D01*
X860100Y142700D01*
Y142992D01*
X860017Y143283D01*
X859892Y143533D01*
X859725Y143742D01*
G01Y144883D02*
X859933Y145133D01*
X860058Y145425D01*
X860100Y145800D01*
X860017Y146175D01*
X859850Y146467D01*
X859558Y146675D01*
X859225Y146717D01*
X858892Y146633D01*
X858683Y146425D01*
X858517Y146133D01*
X858475Y145842D01*
X858517Y145550D01*
X858683Y145175D01*
X857600Y145300D01*
Y146425D01*
G01X860100Y147983D02*
X857600D01*
Y148817D01*
X857725Y149150D01*
X857892Y149400D01*
X858142Y149608D01*
X858433Y149775D01*
X858850Y149817D01*
X859267Y149775D01*
X859558Y149608D01*
X859808Y149400D01*
X859975Y149150D01*
X860100Y148817D01*
Y147983D01*
G01Y152500D02*
X857600D01*
X859392Y150958D01*
Y153042D01*
G01X859058Y154308D02*
X858767Y154600D01*
X858600Y154850D01*
X858517Y155183D01*
X858600Y155475D01*
X858767Y155683D01*
X859017Y155850D01*
X859308Y155892D01*
X859558Y155850D01*
X859808Y155683D01*
X860017Y155433D01*
X860100Y155142D01*
X860017Y154808D01*
X859767Y154517D01*
X859392Y154350D01*
X858975Y154308D01*
X858433Y154392D01*
X858142Y154517D01*
X857850Y154725D01*
X857642Y155017D01*
X857600Y155308D01*
X857683Y155600D01*
X857892Y155808D01*
G01X851508Y127517D02*
X851383Y127267D01*
X851300Y126975D01*
Y126642D01*
X851425Y126267D01*
X851633Y125975D01*
X851883Y125767D01*
X852300Y125600D01*
X852675Y125558D01*
X853050Y125642D01*
X853300Y125767D01*
X853550Y126017D01*
X853717Y126308D01*
X853800Y126600D01*
Y126892D01*
X853717Y127183D01*
X853592Y127433D01*
X853425Y127642D01*
G01Y128783D02*
X853633Y129033D01*
X853758Y129325D01*
X853800Y129700D01*
X853717Y130075D01*
X853550Y130367D01*
X853258Y130575D01*
X852925Y130617D01*
X852592Y130533D01*
X852383Y130325D01*
X852217Y130033D01*
X852175Y129742D01*
X852217Y129450D01*
X852383Y129075D01*
X851300Y129200D01*
Y130325D01*
G01X853800Y131883D02*
X851300D01*
Y132717D01*
X851425Y133050D01*
X851592Y133300D01*
X851842Y133508D01*
X852133Y133675D01*
X852550Y133717D01*
X852967Y133675D01*
X853258Y133508D01*
X853508Y133300D01*
X853675Y133050D01*
X853800Y132717D01*
Y131883D01*
G01X853425Y134983D02*
X853633Y135233D01*
X853758Y135525D01*
X853800Y135900D01*
X853717Y136275D01*
X853550Y136567D01*
X853258Y136775D01*
X852925Y136817D01*
X852592Y136733D01*
X852383Y136525D01*
X852217Y136233D01*
X852175Y135942D01*
X852217Y135650D01*
X852383Y135275D01*
X851300Y135400D01*
Y136525D01*
G01X852758Y138208D02*
X852467Y138500D01*
X852300Y138750D01*
X852217Y139083D01*
X852300Y139375D01*
X852467Y139583D01*
X852717Y139750D01*
X853008Y139792D01*
X853258Y139750D01*
X853508Y139583D01*
X853717Y139333D01*
X853800Y139042D01*
X853717Y138708D01*
X853467Y138417D01*
X853092Y138250D01*
X852675Y138208D01*
X852133Y138292D01*
X851842Y138417D01*
X851550Y138625D01*
X851342Y138917D01*
X851300Y139208D01*
X851383Y139500D01*
X851592Y139708D01*
G01X850967Y109592D02*
X850717Y109717D01*
X850425Y109800D01*
X850092D01*
X849717Y109675D01*
X849425Y109467D01*
X849217Y109217D01*
X849050Y108800D01*
X849008Y108425D01*
X849092Y108050D01*
X849217Y107800D01*
X849467Y107550D01*
X849758Y107383D01*
X850050Y107300D01*
X850342D01*
X850633Y107383D01*
X850883Y107508D01*
X851092Y107675D01*
G01X853650Y107300D02*
Y109800D01*
X852108Y108008D01*
X854192D01*
G01X856500Y108550D02*
X857333D01*
Y107800D01*
X857083Y107550D01*
X856792Y107383D01*
X856375Y107300D01*
X855958Y107383D01*
X855667Y107550D01*
X855417Y107800D01*
X855250Y108092D01*
X855167Y108425D01*
Y108717D01*
X855250Y108967D01*
X855417Y109258D01*
X855667Y109508D01*
X855917Y109675D01*
X856250Y109800D01*
X856542D01*
X856875Y109717D01*
X857125Y109550D01*
G01X858558Y108342D02*
X858850Y108633D01*
X859100Y108800D01*
X859433Y108883D01*
X859725Y108800D01*
X859933Y108633D01*
X860100Y108383D01*
X860142Y108092D01*
X860100Y107842D01*
X859933Y107592D01*
X859683Y107383D01*
X859392Y107300D01*
X859058Y107383D01*
X858767Y107633D01*
X858600Y108008D01*
X858558Y108425D01*
X858642Y108967D01*
X858767Y109258D01*
X858975Y109550D01*
X859267Y109758D01*
X859558Y109800D01*
X859850Y109717D01*
X860058Y109508D01*
G01X850967Y106192D02*
X850717Y106317D01*
X850425Y106400D01*
X850092D01*
X849717Y106275D01*
X849425Y106067D01*
X849217Y105817D01*
X849050Y105400D01*
X849008Y105025D01*
X849092Y104650D01*
X849217Y104400D01*
X849467Y104150D01*
X849758Y103983D01*
X850050Y103900D01*
X850342D01*
X850633Y103983D01*
X850883Y104108D01*
X851092Y104275D01*
G01X853650Y103900D02*
Y106400D01*
X852108Y104608D01*
X854192D01*
G01X856500Y105150D02*
X857333D01*
Y104400D01*
X857083Y104150D01*
X856792Y103983D01*
X856375Y103900D01*
X855958Y103983D01*
X855667Y104150D01*
X855417Y104400D01*
X855250Y104692D01*
X855167Y105025D01*
Y105317D01*
X855250Y105567D01*
X855417Y105858D01*
X855667Y106108D01*
X855917Y106275D01*
X856250Y106400D01*
X856542D01*
X856875Y106317D01*
X857125Y106150D01*
G01X859350Y103900D02*
Y106400D01*
X858850Y105900D01*
G01Y103900D02*
X859850D01*
G01X862450Y106400D02*
X862117Y106317D01*
X861867Y106108D01*
X861700Y105858D01*
X861575Y105525D01*
X861533Y105150D01*
X861575Y104775D01*
X861700Y104442D01*
X861867Y104192D01*
X862117Y103983D01*
X862450Y103900D01*
X862783Y103983D01*
X863033Y104192D01*
X863200Y104442D01*
X863325Y104775D01*
X863367Y105150D01*
X863325Y105525D01*
X863200Y105858D01*
X863033Y106108D01*
X862783Y106317D01*
X862450Y106400D01*
G01X866215Y110302D02*
X866090Y110052D01*
X866007Y109760D01*
Y109427D01*
X866132Y109052D01*
X866340Y108760D01*
X866590Y108552D01*
X867007Y108385D01*
X867382Y108343D01*
X867757Y108427D01*
X868007Y108552D01*
X868257Y108802D01*
X868424Y109093D01*
X868507Y109385D01*
Y109677D01*
X868424Y109968D01*
X868299Y110218D01*
X868132Y110427D01*
G01X868507Y112985D02*
X866007D01*
X867799Y111443D01*
Y113527D01*
G01X867257Y115835D02*
Y116668D01*
X868007D01*
X868257Y116418D01*
X868424Y116127D01*
X868507Y115710D01*
X868424Y115293D01*
X868257Y115002D01*
X868007Y114752D01*
X867715Y114585D01*
X867382Y114502D01*
X867090D01*
X866840Y114585D01*
X866549Y114752D01*
X866299Y115002D01*
X866132Y115252D01*
X866007Y115585D01*
Y115877D01*
X866090Y116210D01*
X866257Y116460D01*
G01X868215Y117977D02*
X868424Y118268D01*
X868507Y118602D01*
X868424Y118935D01*
X868174Y119227D01*
X867799Y119435D01*
X867424Y119518D01*
X866965D01*
X866590Y119435D01*
X866257Y119227D01*
X866090Y118977D01*
X866007Y118685D01*
X866090Y118352D01*
X866257Y118102D01*
X866507Y117935D01*
X866840Y117852D01*
X867132Y117935D01*
X867424Y118143D01*
X867590Y118393D01*
X867632Y118685D01*
X867549Y119018D01*
X867340Y119268D01*
X866965Y119518D01*
G01X885267Y110959D02*
X885017Y111084D01*
X884725Y111167D01*
X884392D01*
X884017Y111042D01*
X883725Y110834D01*
X883517Y110584D01*
X883350Y110167D01*
X883308Y109792D01*
X883392Y109417D01*
X883517Y109167D01*
X883767Y108917D01*
X884058Y108750D01*
X884350Y108667D01*
X884642D01*
X884933Y108750D01*
X885183Y108875D01*
X885392Y109042D01*
G01X887950Y108667D02*
Y111167D01*
X886408Y109375D01*
X888492D01*
G01X890800Y109917D02*
X891633D01*
Y109167D01*
X891383Y108917D01*
X891092Y108750D01*
X890675Y108667D01*
X890258Y108750D01*
X889967Y108917D01*
X889717Y109167D01*
X889550Y109459D01*
X889467Y109792D01*
Y110084D01*
X889550Y110334D01*
X889717Y110625D01*
X889967Y110875D01*
X890217Y111042D01*
X890550Y111167D01*
X890842D01*
X891175Y111084D01*
X891425Y110917D01*
G01X892733Y109042D02*
X892983Y108834D01*
X893275Y108709D01*
X893650Y108667D01*
X894025Y108750D01*
X894317Y108917D01*
X894525Y109209D01*
X894567Y109542D01*
X894483Y109875D01*
X894275Y110084D01*
X893983Y110250D01*
X893692Y110292D01*
X893400Y110250D01*
X893025Y110084D01*
X893150Y111167D01*
X894275D01*
G01X861742Y218268D02*
X866808D01*
X861742Y211268D01*
X866808D01*
G01X905000Y178500D02*
X906500Y177000D01*
X903500D01*
X905000Y178500D01*
G01X900199Y206900D02*
X900600D01*
G01X871400Y254300D02*
X900200D01*
Y206900D01*
X853601D01*
X853600Y206901D01*
G01X900200D02*
X900199Y206900D01*
G01X905000Y167901D02*
X900600D01*
Y206900D01*
X900200D01*
G01X900817Y164000D02*
Y166500D01*
X901858D01*
X902192Y166375D01*
X902400Y166208D01*
X902483Y165875D01*
X902400Y165542D01*
X902150Y165333D01*
X901858Y165208D01*
X900817D01*
G01X901858D02*
X902483Y164000D01*
G01X903958Y165042D02*
X904250Y165333D01*
X904500Y165500D01*
X904833Y165583D01*
X905125Y165500D01*
X905333Y165333D01*
X905500Y165083D01*
X905542Y164792D01*
X905500Y164542D01*
X905333Y164292D01*
X905083Y164083D01*
X904792Y164000D01*
X904458Y164083D01*
X904167Y164333D01*
X904000Y164708D01*
X903958Y165125D01*
X904042Y165667D01*
X904167Y165958D01*
X904375Y166250D01*
X904667Y166458D01*
X904958Y166500D01*
X905250Y166417D01*
X905458Y166208D01*
G01X906933Y164000D02*
Y166500D01*
X907767D01*
X908100Y166375D01*
X908350Y166208D01*
X908558Y165958D01*
X908725Y165667D01*
X908767Y165250D01*
X908725Y164833D01*
X908558Y164542D01*
X908350Y164292D01*
X908100Y164125D01*
X907767Y164000D01*
X906933D01*
G01X910033Y164375D02*
X910283Y164167D01*
X910575Y164042D01*
X910950Y164000D01*
X911325Y164083D01*
X911617Y164250D01*
X911825Y164542D01*
X911867Y164875D01*
X911783Y165208D01*
X911575Y165417D01*
X911283Y165583D01*
X910992Y165625D01*
X910700Y165583D01*
X910325Y165417D01*
X910450Y166500D01*
X911575D01*
G01X900817Y157200D02*
Y159700D01*
X901858D01*
X902192Y159575D01*
X902400Y159408D01*
X902483Y159075D01*
X902400Y158742D01*
X902150Y158533D01*
X901858Y158408D01*
X900817D01*
G01X901858D02*
X902483Y157200D01*
G01X903958Y158242D02*
X904250Y158533D01*
X904500Y158700D01*
X904833Y158783D01*
X905125Y158700D01*
X905333Y158533D01*
X905500Y158283D01*
X905542Y157992D01*
X905500Y157742D01*
X905333Y157492D01*
X905083Y157283D01*
X904792Y157200D01*
X904458Y157283D01*
X904167Y157533D01*
X904000Y157908D01*
X903958Y158325D01*
X904042Y158867D01*
X904167Y159158D01*
X904375Y159450D01*
X904667Y159658D01*
X904958Y159700D01*
X905250Y159617D01*
X905458Y159408D01*
G01X906933Y157200D02*
Y159700D01*
X907767D01*
X908100Y159575D01*
X908350Y159408D01*
X908558Y159158D01*
X908725Y158867D01*
X908767Y158450D01*
X908725Y158033D01*
X908558Y157742D01*
X908350Y157492D01*
X908100Y157325D01*
X907767Y157200D01*
X906933D01*
G01X910867D02*
X910950Y157742D01*
X911075Y158200D01*
X911242Y158617D01*
X911450Y159075D01*
X911783Y159700D01*
X910117D01*
G01X900817Y160600D02*
Y163100D01*
X901858D01*
X902192Y162975D01*
X902400Y162808D01*
X902483Y162475D01*
X902400Y162142D01*
X902150Y161933D01*
X901858Y161808D01*
X900817D01*
G01X901858D02*
X902483Y160600D01*
G01X903958Y161642D02*
X904250Y161933D01*
X904500Y162100D01*
X904833Y162183D01*
X905125Y162100D01*
X905333Y161933D01*
X905500Y161683D01*
X905542Y161392D01*
X905500Y161142D01*
X905333Y160892D01*
X905083Y160683D01*
X904792Y160600D01*
X904458Y160683D01*
X904167Y160933D01*
X904000Y161308D01*
X903958Y161725D01*
X904042Y162267D01*
X904167Y162558D01*
X904375Y162850D01*
X904667Y163058D01*
X904958Y163100D01*
X905250Y163017D01*
X905458Y162808D01*
G01X906933Y160600D02*
Y163100D01*
X907767D01*
X908100Y162975D01*
X908350Y162808D01*
X908558Y162558D01*
X908725Y162267D01*
X908767Y161850D01*
X908725Y161433D01*
X908558Y161142D01*
X908350Y160892D01*
X908100Y160725D01*
X907767Y160600D01*
X906933D01*
G01X910158Y161642D02*
X910450Y161933D01*
X910700Y162100D01*
X911033Y162183D01*
X911325Y162100D01*
X911533Y161933D01*
X911700Y161683D01*
X911742Y161392D01*
X911700Y161142D01*
X911533Y160892D01*
X911283Y160683D01*
X910992Y160600D01*
X910658Y160683D01*
X910367Y160933D01*
X910200Y161308D01*
X910158Y161725D01*
X910242Y162267D01*
X910367Y162558D01*
X910575Y162850D01*
X910867Y163058D01*
X911158Y163100D01*
X911450Y163017D01*
X911658Y162808D01*
G01X884713Y192630D02*
X882213D01*
Y193671D01*
X882338Y194005D01*
X882505Y194213D01*
X882838Y194296D01*
X883171Y194213D01*
X883380Y193963D01*
X883505Y193671D01*
Y192630D01*
G01Y193671D02*
X884713Y194296D01*
G01X884338Y195646D02*
X884546Y195896D01*
X884671Y196188D01*
X884713Y196563D01*
X884630Y196938D01*
X884463Y197230D01*
X884171Y197438D01*
X883838Y197480D01*
X883505Y197396D01*
X883296Y197188D01*
X883130Y196896D01*
X883088Y196605D01*
X883130Y196313D01*
X883296Y195938D01*
X882213Y196063D01*
Y197188D01*
G01X884713Y198746D02*
X882213D01*
Y199580D01*
X882338Y199913D01*
X882505Y200163D01*
X882755Y200371D01*
X883046Y200538D01*
X883463Y200580D01*
X883880Y200538D01*
X884171Y200371D01*
X884421Y200163D01*
X884588Y199913D01*
X884713Y199580D01*
Y198746D01*
G01Y202763D02*
X882213D01*
X882713Y202263D01*
G01X884713D02*
Y203263D01*
G01X888113Y192630D02*
X885613D01*
Y193671D01*
X885738Y194005D01*
X885905Y194213D01*
X886238Y194296D01*
X886571Y194213D01*
X886780Y193963D01*
X886905Y193671D01*
Y192630D01*
G01Y193671D02*
X888113Y194296D01*
G01X887738Y195646D02*
X887946Y195896D01*
X888071Y196188D01*
X888113Y196563D01*
X888030Y196938D01*
X887863Y197230D01*
X887571Y197438D01*
X887238Y197480D01*
X886905Y197396D01*
X886696Y197188D01*
X886530Y196896D01*
X886488Y196605D01*
X886530Y196313D01*
X886696Y195938D01*
X885613Y196063D01*
Y197188D01*
G01X888113Y198746D02*
X885613D01*
Y199580D01*
X885738Y199913D01*
X885905Y200163D01*
X886155Y200371D01*
X886446Y200538D01*
X886863Y200580D01*
X887280Y200538D01*
X887571Y200371D01*
X887821Y200163D01*
X887988Y199913D01*
X888113Y199580D01*
Y198746D01*
G01X886030Y201971D02*
X885780Y202221D01*
X885655Y202513D01*
X885613Y202846D01*
X885696Y203263D01*
X885905Y203555D01*
X886155Y203638D01*
X886405Y203596D01*
X886613Y203430D01*
X887030Y202596D01*
X887321Y202221D01*
X887738Y201971D01*
X888113Y201888D01*
Y203638D01*
G01X895567Y192120D02*
X893067D01*
Y193161D01*
X893192Y193495D01*
X893359Y193703D01*
X893692Y193786D01*
X894025Y193703D01*
X894234Y193453D01*
X894359Y193161D01*
Y192120D01*
G01Y193161D02*
X895567Y193786D01*
G01X894525Y195261D02*
X894234Y195553D01*
X894067Y195803D01*
X893984Y196136D01*
X894067Y196428D01*
X894234Y196636D01*
X894484Y196803D01*
X894775Y196845D01*
X895025Y196803D01*
X895275Y196636D01*
X895484Y196386D01*
X895567Y196095D01*
X895484Y195761D01*
X895234Y195470D01*
X894859Y195303D01*
X894442Y195261D01*
X893900Y195345D01*
X893609Y195470D01*
X893317Y195678D01*
X893109Y195970D01*
X893067Y196261D01*
X893150Y196553D01*
X893359Y196761D01*
G01X895567Y198236D02*
X893067D01*
Y199070D01*
X893192Y199403D01*
X893359Y199653D01*
X893609Y199861D01*
X893900Y200028D01*
X894317Y200070D01*
X894734Y200028D01*
X895025Y199861D01*
X895275Y199653D01*
X895442Y199403D01*
X895567Y199070D01*
Y198236D01*
G01X893484Y201461D02*
X893234Y201711D01*
X893109Y202003D01*
X893067Y202336D01*
X893150Y202753D01*
X893359Y203045D01*
X893609Y203128D01*
X893859Y203086D01*
X894067Y202920D01*
X894484Y202086D01*
X894775Y201711D01*
X895192Y201461D01*
X895567Y201378D01*
Y203128D01*
G01X891513Y192630D02*
X889013D01*
Y193671D01*
X889138Y194005D01*
X889305Y194213D01*
X889638Y194296D01*
X889971Y194213D01*
X890180Y193963D01*
X890305Y193671D01*
Y192630D01*
G01Y193671D02*
X891513Y194296D01*
G01X890471Y195771D02*
X890180Y196063D01*
X890013Y196313D01*
X889930Y196646D01*
X890013Y196938D01*
X890180Y197146D01*
X890430Y197313D01*
X890721Y197355D01*
X890971Y197313D01*
X891221Y197146D01*
X891430Y196896D01*
X891513Y196605D01*
X891430Y196271D01*
X891180Y195980D01*
X890805Y195813D01*
X890388Y195771D01*
X889846Y195855D01*
X889555Y195980D01*
X889263Y196188D01*
X889055Y196480D01*
X889013Y196771D01*
X889096Y197063D01*
X889305Y197271D01*
G01X891513Y198746D02*
X889013D01*
Y199580D01*
X889138Y199913D01*
X889305Y200163D01*
X889555Y200371D01*
X889846Y200538D01*
X890263Y200580D01*
X890680Y200538D01*
X890971Y200371D01*
X891221Y200163D01*
X891388Y199913D01*
X891513Y199580D01*
Y198746D01*
G01Y202763D02*
X889013D01*
X889513Y202263D01*
G01X891513D02*
Y203263D01*
G01X885767Y188500D02*
Y191000D01*
X886808D01*
X887142Y190875D01*
X887350Y190708D01*
X887433Y190375D01*
X887350Y190042D01*
X887100Y189833D01*
X886808Y189708D01*
X885767D01*
G01X886808D02*
X887433Y188500D01*
G01X888908Y189542D02*
X889200Y189833D01*
X889450Y190000D01*
X889783Y190083D01*
X890075Y190000D01*
X890283Y189833D01*
X890450Y189583D01*
X890492Y189292D01*
X890450Y189042D01*
X890283Y188792D01*
X890033Y188583D01*
X889742Y188500D01*
X889408Y188583D01*
X889117Y188833D01*
X888950Y189208D01*
X888908Y189625D01*
X888992Y190167D01*
X889117Y190458D01*
X889325Y190750D01*
X889617Y190958D01*
X889908Y191000D01*
X890200Y190917D01*
X890408Y190708D01*
G01X891883Y188500D02*
Y191000D01*
X892717D01*
X893050Y190875D01*
X893300Y190708D01*
X893508Y190458D01*
X893675Y190167D01*
X893717Y189750D01*
X893675Y189333D01*
X893508Y189042D01*
X893300Y188792D01*
X893050Y188625D01*
X892717Y188500D01*
X891883D01*
G01X895900D02*
Y191000D01*
X895400Y190500D01*
G01Y188500D02*
X896400D01*
G01X898208Y189542D02*
X898500Y189833D01*
X898750Y190000D01*
X899083Y190083D01*
X899375Y190000D01*
X899583Y189833D01*
X899750Y189583D01*
X899792Y189292D01*
X899750Y189042D01*
X899583Y188792D01*
X899333Y188583D01*
X899042Y188500D01*
X898708Y188583D01*
X898417Y188833D01*
X898250Y189208D01*
X898208Y189625D01*
X898292Y190167D01*
X898417Y190458D01*
X898625Y190750D01*
X898917Y190958D01*
X899208Y191000D01*
X899500Y190917D01*
X899708Y190708D01*
G01X877669Y191109D02*
X875169D01*
Y192150D01*
X875294Y192484D01*
X875461Y192692D01*
X875794Y192775D01*
X876127Y192692D01*
X876336Y192442D01*
X876461Y192150D01*
Y191109D01*
G01Y192150D02*
X877669Y192775D01*
G01X877169Y194125D02*
X877461Y194375D01*
X877627Y194709D01*
X877669Y195084D01*
X877627Y195417D01*
X877419Y195750D01*
X877169Y195959D01*
X876919Y196000D01*
X876627Y195917D01*
X876419Y195625D01*
X876336Y195334D01*
Y194959D01*
G01Y195334D02*
X876211Y195584D01*
X876002Y195792D01*
X875752Y195875D01*
X875502Y195792D01*
X875294Y195584D01*
X875169Y195209D01*
X875211Y194834D01*
X875377Y194459D01*
G01X877669Y197309D02*
X875169D01*
Y198309D01*
X875294Y198642D01*
X875586Y198892D01*
X875919Y198975D01*
X876252Y198892D01*
X876502Y198684D01*
X876627Y198309D01*
Y197309D01*
G01X875586Y200450D02*
X875336Y200700D01*
X875211Y200992D01*
X875169Y201325D01*
X875252Y201742D01*
X875461Y202034D01*
X875711Y202117D01*
X875961Y202075D01*
X876169Y201909D01*
X876586Y201075D01*
X876877Y200700D01*
X877294Y200450D01*
X877669Y200367D01*
Y202117D01*
G01X877377Y203634D02*
X877586Y203925D01*
X877669Y204259D01*
X877586Y204592D01*
X877336Y204884D01*
X876961Y205092D01*
X876586Y205175D01*
X876127D01*
X875752Y205092D01*
X875419Y204884D01*
X875252Y204634D01*
X875169Y204342D01*
X875252Y204009D01*
X875419Y203759D01*
X875669Y203592D01*
X876002Y203509D01*
X876294Y203592D01*
X876586Y203800D01*
X876752Y204050D01*
X876794Y204342D01*
X876711Y204675D01*
X876502Y204925D01*
X876127Y205175D01*
G01X898185Y208845D02*
X895685D01*
Y209886D01*
X895810Y210220D01*
X895977Y210428D01*
X896310Y210511D01*
X896643Y210428D01*
X896852Y210178D01*
X896977Y209886D01*
Y208845D01*
G01Y209886D02*
X898185Y210511D01*
G01Y212695D02*
X897643Y212778D01*
X897185Y212903D01*
X896768Y213070D01*
X896310Y213278D01*
X895685Y213611D01*
Y211945D01*
G01X896935Y216128D02*
Y216961D01*
X897685D01*
X897935Y216711D01*
X898102Y216420D01*
X898185Y216003D01*
X898102Y215586D01*
X897935Y215295D01*
X897685Y215045D01*
X897393Y214878D01*
X897060Y214795D01*
X896768D01*
X896518Y214878D01*
X896227Y215045D01*
X895977Y215295D01*
X895810Y215545D01*
X895685Y215878D01*
Y216170D01*
X895768Y216503D01*
X895935Y216753D01*
G01X897685Y218061D02*
X897977Y218311D01*
X898143Y218645D01*
X898185Y219020D01*
X898143Y219353D01*
X897935Y219686D01*
X897685Y219895D01*
X897435Y219936D01*
X897143Y219853D01*
X896935Y219561D01*
X896852Y219270D01*
Y218895D01*
G01Y219270D02*
X896727Y219520D01*
X896518Y219728D01*
X896268Y219811D01*
X896018Y219728D01*
X895810Y219520D01*
X895685Y219145D01*
X895727Y218770D01*
X895893Y218395D01*
G01X895685Y222078D02*
X895768Y221745D01*
X895977Y221495D01*
X896227Y221328D01*
X896560Y221203D01*
X896935Y221161D01*
X897310Y221203D01*
X897643Y221328D01*
X897893Y221495D01*
X898102Y221745D01*
X898185Y222078D01*
X898102Y222411D01*
X897893Y222661D01*
X897643Y222828D01*
X897310Y222953D01*
X896935Y222995D01*
X896560Y222953D01*
X896227Y222828D01*
X895977Y222661D01*
X895768Y222411D01*
X895685Y222078D01*
G01X893008Y159817D02*
X892883Y159567D01*
X892800Y159275D01*
Y158942D01*
X892925Y158567D01*
X893133Y158275D01*
X893383Y158067D01*
X893800Y157900D01*
X894175Y157858D01*
X894550Y157942D01*
X894800Y158067D01*
X895050Y158317D01*
X895217Y158608D01*
X895300Y158900D01*
Y159192D01*
X895217Y159483D01*
X895092Y159733D01*
X894925Y159942D01*
G01X894258Y161208D02*
X893967Y161500D01*
X893800Y161750D01*
X893717Y162083D01*
X893800Y162375D01*
X893967Y162583D01*
X894217Y162750D01*
X894508Y162792D01*
X894758Y162750D01*
X895008Y162583D01*
X895217Y162333D01*
X895300Y162042D01*
X895217Y161708D01*
X894967Y161417D01*
X894592Y161250D01*
X894175Y161208D01*
X893633Y161292D01*
X893342Y161417D01*
X893050Y161625D01*
X892842Y161917D01*
X892800Y162208D01*
X892883Y162500D01*
X893092Y162708D01*
G01X895300Y164183D02*
X892800D01*
Y165017D01*
X892925Y165350D01*
X893092Y165600D01*
X893342Y165808D01*
X893633Y165975D01*
X894050Y166017D01*
X894467Y165975D01*
X894758Y165808D01*
X895008Y165600D01*
X895175Y165350D01*
X895300Y165017D01*
Y164183D01*
G01Y168117D02*
X894758Y168200D01*
X894300Y168325D01*
X893883Y168492D01*
X893425Y168700D01*
X892800Y169033D01*
Y167367D01*
G01X886208Y159817D02*
X886083Y159567D01*
X886000Y159275D01*
Y158942D01*
X886125Y158567D01*
X886333Y158275D01*
X886583Y158067D01*
X887000Y157900D01*
X887375Y157858D01*
X887750Y157942D01*
X888000Y158067D01*
X888250Y158317D01*
X888417Y158608D01*
X888500Y158900D01*
Y159192D01*
X888417Y159483D01*
X888292Y159733D01*
X888125Y159942D01*
G01X887458Y161208D02*
X887167Y161500D01*
X887000Y161750D01*
X886917Y162083D01*
X887000Y162375D01*
X887167Y162583D01*
X887417Y162750D01*
X887708Y162792D01*
X887958Y162750D01*
X888208Y162583D01*
X888417Y162333D01*
X888500Y162042D01*
X888417Y161708D01*
X888167Y161417D01*
X887792Y161250D01*
X887375Y161208D01*
X886833Y161292D01*
X886542Y161417D01*
X886250Y161625D01*
X886042Y161917D01*
X886000Y162208D01*
X886083Y162500D01*
X886292Y162708D01*
G01X888500Y164183D02*
X886000D01*
Y165017D01*
X886125Y165350D01*
X886292Y165600D01*
X886542Y165808D01*
X886833Y165975D01*
X887250Y166017D01*
X887667Y165975D01*
X887958Y165808D01*
X888208Y165600D01*
X888375Y165350D01*
X888500Y165017D01*
Y164183D01*
G01X888125Y167283D02*
X888333Y167533D01*
X888458Y167825D01*
X888500Y168200D01*
X888417Y168575D01*
X888250Y168867D01*
X887958Y169075D01*
X887625Y169117D01*
X887292Y169033D01*
X887083Y168825D01*
X886917Y168533D01*
X886875Y168242D01*
X886917Y167950D01*
X887083Y167575D01*
X886000Y167700D01*
Y168825D01*
G01X889608Y159817D02*
X889483Y159567D01*
X889400Y159275D01*
Y158942D01*
X889525Y158567D01*
X889733Y158275D01*
X889983Y158067D01*
X890400Y157900D01*
X890775Y157858D01*
X891150Y157942D01*
X891400Y158067D01*
X891650Y158317D01*
X891817Y158608D01*
X891900Y158900D01*
Y159192D01*
X891817Y159483D01*
X891692Y159733D01*
X891525Y159942D01*
G01X890858Y161208D02*
X890567Y161500D01*
X890400Y161750D01*
X890317Y162083D01*
X890400Y162375D01*
X890567Y162583D01*
X890817Y162750D01*
X891108Y162792D01*
X891358Y162750D01*
X891608Y162583D01*
X891817Y162333D01*
X891900Y162042D01*
X891817Y161708D01*
X891567Y161417D01*
X891192Y161250D01*
X890775Y161208D01*
X890233Y161292D01*
X889942Y161417D01*
X889650Y161625D01*
X889442Y161917D01*
X889400Y162208D01*
X889483Y162500D01*
X889692Y162708D01*
G01X891900Y164183D02*
X889400D01*
Y165017D01*
X889525Y165350D01*
X889692Y165600D01*
X889942Y165808D01*
X890233Y165975D01*
X890650Y166017D01*
X891067Y165975D01*
X891358Y165808D01*
X891608Y165600D01*
X891775Y165350D01*
X891900Y165017D01*
Y164183D01*
G01X890858Y167408D02*
X890567Y167700D01*
X890400Y167950D01*
X890317Y168283D01*
X890400Y168575D01*
X890567Y168783D01*
X890817Y168950D01*
X891108Y168992D01*
X891358Y168950D01*
X891608Y168783D01*
X891817Y168533D01*
X891900Y168242D01*
X891817Y167908D01*
X891567Y167617D01*
X891192Y167450D01*
X890775Y167408D01*
X890233Y167492D01*
X889942Y167617D01*
X889650Y167825D01*
X889442Y168117D01*
X889400Y168408D01*
X889483Y168700D01*
X889692Y168908D01*
G01X879408Y159817D02*
X879283Y159567D01*
X879200Y159275D01*
Y158942D01*
X879325Y158567D01*
X879533Y158275D01*
X879783Y158067D01*
X880200Y157900D01*
X880575Y157858D01*
X880950Y157942D01*
X881200Y158067D01*
X881450Y158317D01*
X881617Y158608D01*
X881700Y158900D01*
Y159192D01*
X881617Y159483D01*
X881492Y159733D01*
X881325Y159942D01*
G01Y161083D02*
X881533Y161333D01*
X881658Y161625D01*
X881700Y162000D01*
X881617Y162375D01*
X881450Y162667D01*
X881158Y162875D01*
X880825Y162917D01*
X880492Y162833D01*
X880283Y162625D01*
X880117Y162333D01*
X880075Y162042D01*
X880117Y161750D01*
X880283Y161375D01*
X879200Y161500D01*
Y162625D01*
G01X881700Y164183D02*
X879200D01*
Y165017D01*
X879325Y165350D01*
X879492Y165600D01*
X879742Y165808D01*
X880033Y165975D01*
X880450Y166017D01*
X880867Y165975D01*
X881158Y165808D01*
X881408Y165600D01*
X881575Y165350D01*
X881700Y165017D01*
Y164183D01*
G01X881200Y167283D02*
X881492Y167533D01*
X881658Y167867D01*
X881700Y168242D01*
X881658Y168575D01*
X881450Y168908D01*
X881200Y169117D01*
X880950Y169158D01*
X880658Y169075D01*
X880450Y168783D01*
X880367Y168492D01*
Y168117D01*
G01Y168492D02*
X880242Y168742D01*
X880033Y168950D01*
X879783Y169033D01*
X879533Y168950D01*
X879325Y168742D01*
X879200Y168367D01*
X879242Y167992D01*
X879408Y167617D01*
G01X881700Y171217D02*
X881158Y171300D01*
X880700Y171425D01*
X880283Y171592D01*
X879825Y171800D01*
X879200Y172133D01*
Y170467D01*
G01X882808Y159817D02*
X882683Y159567D01*
X882600Y159275D01*
Y158942D01*
X882725Y158567D01*
X882933Y158275D01*
X883183Y158067D01*
X883600Y157900D01*
X883975Y157858D01*
X884350Y157942D01*
X884600Y158067D01*
X884850Y158317D01*
X885017Y158608D01*
X885100Y158900D01*
Y159192D01*
X885017Y159483D01*
X884892Y159733D01*
X884725Y159942D01*
G01Y161083D02*
X884933Y161333D01*
X885058Y161625D01*
X885100Y162000D01*
X885017Y162375D01*
X884850Y162667D01*
X884558Y162875D01*
X884225Y162917D01*
X883892Y162833D01*
X883683Y162625D01*
X883517Y162333D01*
X883475Y162042D01*
X883517Y161750D01*
X883683Y161375D01*
X882600Y161500D01*
Y162625D01*
G01X885100Y164183D02*
X882600D01*
Y165017D01*
X882725Y165350D01*
X882892Y165600D01*
X883142Y165808D01*
X883433Y165975D01*
X883850Y166017D01*
X884267Y165975D01*
X884558Y165808D01*
X884808Y165600D01*
X884975Y165350D01*
X885100Y165017D01*
Y164183D01*
G01X884600Y167283D02*
X884892Y167533D01*
X885058Y167867D01*
X885100Y168242D01*
X885058Y168575D01*
X884850Y168908D01*
X884600Y169117D01*
X884350Y169158D01*
X884058Y169075D01*
X883850Y168783D01*
X883767Y168492D01*
Y168117D01*
G01Y168492D02*
X883642Y168742D01*
X883433Y168950D01*
X883183Y169033D01*
X882933Y168950D01*
X882725Y168742D01*
X882600Y168367D01*
X882642Y167992D01*
X882808Y167617D01*
G01X885100Y171300D02*
X885058Y171592D01*
X884933Y171925D01*
X884725Y172133D01*
X884433Y172217D01*
X884142Y172133D01*
X883892Y171883D01*
X883767Y171508D01*
Y171092D01*
X883683Y170842D01*
X883475Y170633D01*
X883183Y170550D01*
X882892Y170675D01*
X882683Y170967D01*
X882600Y171300D01*
X882683Y171633D01*
X882892Y171925D01*
X883183Y172050D01*
X883475Y171967D01*
X883683Y171758D01*
X883767Y171508D01*
Y171092D01*
X883892Y170717D01*
X884142Y170467D01*
X884433Y170383D01*
X884725Y170467D01*
X884933Y170675D01*
X885058Y171008D01*
X885100Y171300D01*
G01X876008Y159817D02*
X875883Y159567D01*
X875800Y159275D01*
Y158942D01*
X875925Y158567D01*
X876133Y158275D01*
X876383Y158067D01*
X876800Y157900D01*
X877175Y157858D01*
X877550Y157942D01*
X877800Y158067D01*
X878050Y158317D01*
X878217Y158608D01*
X878300Y158900D01*
Y159192D01*
X878217Y159483D01*
X878092Y159733D01*
X877925Y159942D01*
G01Y161083D02*
X878133Y161333D01*
X878258Y161625D01*
X878300Y162000D01*
X878217Y162375D01*
X878050Y162667D01*
X877758Y162875D01*
X877425Y162917D01*
X877092Y162833D01*
X876883Y162625D01*
X876717Y162333D01*
X876675Y162042D01*
X876717Y161750D01*
X876883Y161375D01*
X875800Y161500D01*
Y162625D01*
G01X878300Y164183D02*
X875800D01*
Y165017D01*
X875925Y165350D01*
X876092Y165600D01*
X876342Y165808D01*
X876633Y165975D01*
X877050Y166017D01*
X877467Y165975D01*
X877758Y165808D01*
X878008Y165600D01*
X878175Y165350D01*
X878300Y165017D01*
Y164183D01*
G01X877800Y167283D02*
X878092Y167533D01*
X878258Y167867D01*
X878300Y168242D01*
X878258Y168575D01*
X878050Y168908D01*
X877800Y169117D01*
X877550Y169158D01*
X877258Y169075D01*
X877050Y168783D01*
X876967Y168492D01*
Y168117D01*
G01Y168492D02*
X876842Y168742D01*
X876633Y168950D01*
X876383Y169033D01*
X876133Y168950D01*
X875925Y168742D01*
X875800Y168367D01*
X875842Y167992D01*
X876008Y167617D01*
G01X877258Y170508D02*
X876967Y170800D01*
X876800Y171050D01*
X876717Y171383D01*
X876800Y171675D01*
X876967Y171883D01*
X877217Y172050D01*
X877508Y172092D01*
X877758Y172050D01*
X878008Y171883D01*
X878217Y171633D01*
X878300Y171342D01*
X878217Y171008D01*
X877967Y170717D01*
X877592Y170550D01*
X877175Y170508D01*
X876633Y170592D01*
X876342Y170717D01*
X876050Y170925D01*
X875842Y171217D01*
X875800Y171508D01*
X875883Y171800D01*
X876092Y172008D01*
G01X875608Y177517D02*
X875483Y177267D01*
X875400Y176975D01*
Y176642D01*
X875525Y176267D01*
X875733Y175975D01*
X875983Y175767D01*
X876400Y175600D01*
X876775Y175558D01*
X877150Y175642D01*
X877400Y175767D01*
X877650Y176017D01*
X877817Y176308D01*
X877900Y176600D01*
Y176892D01*
X877817Y177183D01*
X877692Y177433D01*
X877525Y177642D01*
G01Y178783D02*
X877733Y179033D01*
X877858Y179325D01*
X877900Y179700D01*
X877817Y180075D01*
X877650Y180367D01*
X877358Y180575D01*
X877025Y180617D01*
X876692Y180533D01*
X876483Y180325D01*
X876317Y180033D01*
X876275Y179742D01*
X876317Y179450D01*
X876483Y179075D01*
X875400Y179200D01*
Y180325D01*
G01X877900Y181883D02*
X875400D01*
Y182717D01*
X875525Y183050D01*
X875692Y183300D01*
X875942Y183508D01*
X876233Y183675D01*
X876650Y183717D01*
X877067Y183675D01*
X877358Y183508D01*
X877608Y183300D01*
X877775Y183050D01*
X877900Y182717D01*
Y181883D01*
G01X875817Y185108D02*
X875567Y185358D01*
X875442Y185650D01*
X875400Y185983D01*
X875483Y186400D01*
X875692Y186692D01*
X875942Y186775D01*
X876192Y186733D01*
X876400Y186567D01*
X876817Y185733D01*
X877108Y185358D01*
X877525Y185108D01*
X877900Y185025D01*
Y186775D01*
G01Y189000D02*
X875400D01*
X875900Y188500D01*
G01X877900D02*
Y189500D01*
G01X879008Y176917D02*
X878883Y176667D01*
X878800Y176375D01*
Y176042D01*
X878925Y175667D01*
X879133Y175375D01*
X879383Y175167D01*
X879800Y175000D01*
X880175Y174958D01*
X880550Y175042D01*
X880800Y175167D01*
X881050Y175417D01*
X881217Y175708D01*
X881300Y176000D01*
Y176292D01*
X881217Y176583D01*
X881092Y176833D01*
X880925Y177042D01*
G01Y178183D02*
X881133Y178433D01*
X881258Y178725D01*
X881300Y179100D01*
X881217Y179475D01*
X881050Y179767D01*
X880758Y179975D01*
X880425Y180017D01*
X880092Y179933D01*
X879883Y179725D01*
X879717Y179433D01*
X879675Y179142D01*
X879717Y178850D01*
X879883Y178475D01*
X878800Y178600D01*
Y179725D01*
G01X881300Y181283D02*
X878800D01*
Y182117D01*
X878925Y182450D01*
X879092Y182700D01*
X879342Y182908D01*
X879633Y183075D01*
X880050Y183117D01*
X880467Y183075D01*
X880758Y182908D01*
X881008Y182700D01*
X881175Y182450D01*
X881300Y182117D01*
Y181283D01*
G01X879217Y184508D02*
X878967Y184758D01*
X878842Y185050D01*
X878800Y185383D01*
X878883Y185800D01*
X879092Y186092D01*
X879342Y186175D01*
X879592Y186133D01*
X879800Y185967D01*
X880217Y185133D01*
X880508Y184758D01*
X880925Y184508D01*
X881300Y184425D01*
Y186175D01*
G01X879217Y187608D02*
X878967Y187858D01*
X878842Y188150D01*
X878800Y188483D01*
X878883Y188900D01*
X879092Y189192D01*
X879342Y189275D01*
X879592Y189233D01*
X879800Y189067D01*
X880217Y188233D01*
X880508Y187858D01*
X880925Y187608D01*
X881300Y187525D01*
Y189275D01*
G01X882508Y177017D02*
X882383Y176767D01*
X882300Y176475D01*
Y176142D01*
X882425Y175767D01*
X882633Y175475D01*
X882883Y175267D01*
X883300Y175100D01*
X883675Y175058D01*
X884050Y175142D01*
X884300Y175267D01*
X884550Y175517D01*
X884717Y175808D01*
X884800Y176100D01*
Y176392D01*
X884717Y176683D01*
X884592Y176933D01*
X884425Y177142D01*
G01Y178283D02*
X884633Y178533D01*
X884758Y178825D01*
X884800Y179200D01*
X884717Y179575D01*
X884550Y179867D01*
X884258Y180075D01*
X883925Y180117D01*
X883592Y180033D01*
X883383Y179825D01*
X883217Y179533D01*
X883175Y179242D01*
X883217Y178950D01*
X883383Y178575D01*
X882300Y178700D01*
Y179825D01*
G01X884800Y181383D02*
X882300D01*
Y182217D01*
X882425Y182550D01*
X882592Y182800D01*
X882842Y183008D01*
X883133Y183175D01*
X883550Y183217D01*
X883967Y183175D01*
X884258Y183008D01*
X884508Y182800D01*
X884675Y182550D01*
X884800Y182217D01*
Y181383D01*
G01X882717Y184608D02*
X882467Y184858D01*
X882342Y185150D01*
X882300Y185483D01*
X882383Y185900D01*
X882592Y186192D01*
X882842Y186275D01*
X883092Y186233D01*
X883300Y186067D01*
X883717Y185233D01*
X884008Y184858D01*
X884425Y184608D01*
X884800Y184525D01*
Y186275D01*
G01X884300Y187583D02*
X884592Y187833D01*
X884758Y188167D01*
X884800Y188542D01*
X884758Y188875D01*
X884550Y189208D01*
X884300Y189417D01*
X884050Y189458D01*
X883758Y189375D01*
X883550Y189083D01*
X883467Y188792D01*
Y188417D01*
G01Y188792D02*
X883342Y189042D01*
X883133Y189250D01*
X882883Y189333D01*
X882633Y189250D01*
X882425Y189042D01*
X882300Y188667D01*
X882342Y188292D01*
X882508Y187917D01*
G01X893208Y177667D02*
X893083Y177417D01*
X893000Y177125D01*
Y176792D01*
X893125Y176417D01*
X893333Y176125D01*
X893583Y175917D01*
X894000Y175750D01*
X894375Y175708D01*
X894750Y175792D01*
X895000Y175917D01*
X895250Y176167D01*
X895417Y176458D01*
X895500Y176750D01*
Y177042D01*
X895417Y177333D01*
X895292Y177583D01*
X895125Y177792D01*
G01X894458Y179058D02*
X894167Y179350D01*
X894000Y179600D01*
X893917Y179933D01*
X894000Y180225D01*
X894167Y180433D01*
X894417Y180600D01*
X894708Y180642D01*
X894958Y180600D01*
X895208Y180433D01*
X895417Y180183D01*
X895500Y179892D01*
X895417Y179558D01*
X895167Y179267D01*
X894792Y179100D01*
X894375Y179058D01*
X893833Y179142D01*
X893542Y179267D01*
X893250Y179475D01*
X893042Y179767D01*
X893000Y180058D01*
X893083Y180350D01*
X893292Y180558D01*
G01X895500Y182033D02*
X893000D01*
Y182867D01*
X893125Y183200D01*
X893292Y183450D01*
X893542Y183658D01*
X893833Y183825D01*
X894250Y183867D01*
X894667Y183825D01*
X894958Y183658D01*
X895208Y183450D01*
X895375Y183200D01*
X895500Y182867D01*
Y182033D01*
G01Y186550D02*
X893000D01*
X894792Y185008D01*
Y187092D01*
G01X897108Y177767D02*
X896983Y177517D01*
X896900Y177225D01*
Y176892D01*
X897025Y176517D01*
X897233Y176225D01*
X897483Y176017D01*
X897900Y175850D01*
X898275Y175808D01*
X898650Y175892D01*
X898900Y176017D01*
X899150Y176267D01*
X899317Y176558D01*
X899400Y176850D01*
Y177142D01*
X899317Y177433D01*
X899192Y177683D01*
X899025Y177892D01*
G01X898358Y179158D02*
X898067Y179450D01*
X897900Y179700D01*
X897817Y180033D01*
X897900Y180325D01*
X898067Y180533D01*
X898317Y180700D01*
X898608Y180742D01*
X898858Y180700D01*
X899108Y180533D01*
X899317Y180283D01*
X899400Y179992D01*
X899317Y179658D01*
X899067Y179367D01*
X898692Y179200D01*
X898275Y179158D01*
X897733Y179242D01*
X897442Y179367D01*
X897150Y179575D01*
X896942Y179867D01*
X896900Y180158D01*
X896983Y180450D01*
X897192Y180658D01*
G01X899400Y182133D02*
X896900D01*
Y182967D01*
X897025Y183300D01*
X897192Y183550D01*
X897442Y183758D01*
X897733Y183925D01*
X898150Y183967D01*
X898567Y183925D01*
X898858Y183758D01*
X899108Y183550D01*
X899275Y183300D01*
X899400Y182967D01*
Y182133D01*
G01Y186150D02*
X896900D01*
X897400Y185650D01*
G01X899400D02*
Y186650D01*
G01X889808Y177767D02*
X889683Y177517D01*
X889600Y177225D01*
Y176892D01*
X889725Y176517D01*
X889933Y176225D01*
X890183Y176017D01*
X890600Y175850D01*
X890975Y175808D01*
X891350Y175892D01*
X891600Y176017D01*
X891850Y176267D01*
X892017Y176558D01*
X892100Y176850D01*
Y177142D01*
X892017Y177433D01*
X891892Y177683D01*
X891725Y177892D01*
G01X891058Y179158D02*
X890767Y179450D01*
X890600Y179700D01*
X890517Y180033D01*
X890600Y180325D01*
X890767Y180533D01*
X891017Y180700D01*
X891308Y180742D01*
X891558Y180700D01*
X891808Y180533D01*
X892017Y180283D01*
X892100Y179992D01*
X892017Y179658D01*
X891767Y179367D01*
X891392Y179200D01*
X890975Y179158D01*
X890433Y179242D01*
X890142Y179367D01*
X889850Y179575D01*
X889642Y179867D01*
X889600Y180158D01*
X889683Y180450D01*
X889892Y180658D01*
G01X892100Y182133D02*
X889600D01*
Y182967D01*
X889725Y183300D01*
X889892Y183550D01*
X890142Y183758D01*
X890433Y183925D01*
X890850Y183967D01*
X891267Y183925D01*
X891558Y183758D01*
X891808Y183550D01*
X891975Y183300D01*
X892100Y182967D01*
Y182133D01*
G01X891600Y185233D02*
X891892Y185483D01*
X892058Y185817D01*
X892100Y186192D01*
X892058Y186525D01*
X891850Y186858D01*
X891600Y187067D01*
X891350Y187108D01*
X891058Y187025D01*
X890850Y186733D01*
X890767Y186442D01*
Y186067D01*
G01Y186442D02*
X890642Y186692D01*
X890433Y186900D01*
X890183Y186983D01*
X889933Y186900D01*
X889725Y186692D01*
X889600Y186317D01*
X889642Y185942D01*
X889808Y185567D01*
G01X886308Y177767D02*
X886183Y177517D01*
X886100Y177225D01*
Y176892D01*
X886225Y176517D01*
X886433Y176225D01*
X886683Y176017D01*
X887100Y175850D01*
X887475Y175808D01*
X887850Y175892D01*
X888100Y176017D01*
X888350Y176267D01*
X888517Y176558D01*
X888600Y176850D01*
Y177142D01*
X888517Y177433D01*
X888392Y177683D01*
X888225Y177892D01*
G01X887558Y179158D02*
X887267Y179450D01*
X887100Y179700D01*
X887017Y180033D01*
X887100Y180325D01*
X887267Y180533D01*
X887517Y180700D01*
X887808Y180742D01*
X888058Y180700D01*
X888308Y180533D01*
X888517Y180283D01*
X888600Y179992D01*
X888517Y179658D01*
X888267Y179367D01*
X887892Y179200D01*
X887475Y179158D01*
X886933Y179242D01*
X886642Y179367D01*
X886350Y179575D01*
X886142Y179867D01*
X886100Y180158D01*
X886183Y180450D01*
X886392Y180658D01*
G01X888600Y182133D02*
X886100D01*
Y182967D01*
X886225Y183300D01*
X886392Y183550D01*
X886642Y183758D01*
X886933Y183925D01*
X887350Y183967D01*
X887767Y183925D01*
X888058Y183758D01*
X888308Y183550D01*
X888475Y183300D01*
X888600Y182967D01*
Y182133D01*
G01X886517Y185358D02*
X886267Y185608D01*
X886142Y185900D01*
X886100Y186233D01*
X886183Y186650D01*
X886392Y186942D01*
X886642Y187025D01*
X886892Y186983D01*
X887100Y186817D01*
X887517Y185983D01*
X887808Y185608D01*
X888225Y185358D01*
X888600Y185275D01*
Y187025D01*
G01X878931Y194172D02*
X878806Y193922D01*
X878723Y193630D01*
Y193297D01*
X878848Y192922D01*
X879056Y192630D01*
X879306Y192422D01*
X879723Y192255D01*
X880098Y192213D01*
X880473Y192297D01*
X880723Y192422D01*
X880973Y192672D01*
X881140Y192963D01*
X881223Y193255D01*
Y193547D01*
X881140Y193838D01*
X881015Y194088D01*
X880848Y194297D01*
G01Y195438D02*
X881056Y195688D01*
X881181Y195980D01*
X881223Y196355D01*
X881140Y196730D01*
X880973Y197022D01*
X880681Y197230D01*
X880348Y197272D01*
X880015Y197188D01*
X879806Y196980D01*
X879640Y196688D01*
X879598Y196397D01*
X879640Y196105D01*
X879806Y195730D01*
X878723Y195855D01*
Y196980D01*
G01X881223Y198538D02*
X878723D01*
Y199372D01*
X878848Y199705D01*
X879015Y199955D01*
X879265Y200163D01*
X879556Y200330D01*
X879973Y200372D01*
X880390Y200330D01*
X880681Y200163D01*
X880931Y199955D01*
X881098Y199705D01*
X881223Y199372D01*
Y198538D01*
G01X880848Y201638D02*
X881056Y201888D01*
X881181Y202180D01*
X881223Y202555D01*
X881140Y202930D01*
X880973Y203222D01*
X880681Y203430D01*
X880348Y203472D01*
X880015Y203388D01*
X879806Y203180D01*
X879640Y202888D01*
X879598Y202597D01*
X879640Y202305D01*
X879806Y201930D01*
X878723Y202055D01*
Y203180D01*
G01X868708Y177217D02*
X868583Y176967D01*
X868500Y176675D01*
Y176342D01*
X868625Y175967D01*
X868833Y175675D01*
X869083Y175467D01*
X869500Y175300D01*
X869875Y175258D01*
X870250Y175342D01*
X870500Y175467D01*
X870750Y175717D01*
X870917Y176008D01*
X871000Y176300D01*
Y176592D01*
X870917Y176883D01*
X870792Y177133D01*
X870625Y177342D01*
G01Y178483D02*
X870833Y178733D01*
X870958Y179025D01*
X871000Y179400D01*
X870917Y179775D01*
X870750Y180067D01*
X870458Y180275D01*
X870125Y180317D01*
X869792Y180233D01*
X869583Y180025D01*
X869417Y179733D01*
X869375Y179442D01*
X869417Y179150D01*
X869583Y178775D01*
X868500Y178900D01*
Y180025D01*
G01X871000Y181583D02*
X868500D01*
Y182417D01*
X868625Y182750D01*
X868792Y183000D01*
X869042Y183208D01*
X869333Y183375D01*
X869750Y183417D01*
X870167Y183375D01*
X870458Y183208D01*
X870708Y183000D01*
X870875Y182750D01*
X871000Y182417D01*
Y181583D01*
G01X868917Y184808D02*
X868667Y185058D01*
X868542Y185350D01*
X868500Y185683D01*
X868583Y186100D01*
X868792Y186392D01*
X869042Y186475D01*
X869292Y186433D01*
X869500Y186267D01*
X869917Y185433D01*
X870208Y185058D01*
X870625Y184808D01*
X871000Y184725D01*
Y186475D01*
G01X868500Y188700D02*
X868583Y188367D01*
X868792Y188117D01*
X869042Y187950D01*
X869375Y187825D01*
X869750Y187783D01*
X870125Y187825D01*
X870458Y187950D01*
X870708Y188117D01*
X870917Y188367D01*
X871000Y188700D01*
X870917Y189033D01*
X870708Y189283D01*
X870458Y189450D01*
X870125Y189575D01*
X869750Y189617D01*
X869375Y189575D01*
X869042Y189450D01*
X868792Y189283D01*
X868583Y189033D01*
X868500Y188700D01*
G01X855008Y177217D02*
X854883Y176967D01*
X854800Y176675D01*
Y176342D01*
X854925Y175967D01*
X855133Y175675D01*
X855383Y175467D01*
X855800Y175300D01*
X856175Y175258D01*
X856550Y175342D01*
X856800Y175467D01*
X857050Y175717D01*
X857217Y176008D01*
X857300Y176300D01*
Y176592D01*
X857217Y176883D01*
X857092Y177133D01*
X856925Y177342D01*
G01Y178483D02*
X857133Y178733D01*
X857258Y179025D01*
X857300Y179400D01*
X857217Y179775D01*
X857050Y180067D01*
X856758Y180275D01*
X856425Y180317D01*
X856092Y180233D01*
X855883Y180025D01*
X855717Y179733D01*
X855675Y179442D01*
X855717Y179150D01*
X855883Y178775D01*
X854800Y178900D01*
Y180025D01*
G01X857300Y181583D02*
X854800D01*
Y182417D01*
X854925Y182750D01*
X855092Y183000D01*
X855342Y183208D01*
X855633Y183375D01*
X856050Y183417D01*
X856467Y183375D01*
X856758Y183208D01*
X857008Y183000D01*
X857175Y182750D01*
X857300Y182417D01*
Y181583D01*
G01Y185600D02*
X854800D01*
X855300Y185100D01*
G01X857300D02*
Y186100D01*
G01Y188617D02*
X856758Y188700D01*
X856300Y188825D01*
X855883Y188992D01*
X855425Y189200D01*
X854800Y189533D01*
Y187867D01*
G01X851508Y177217D02*
X851383Y176967D01*
X851300Y176675D01*
Y176342D01*
X851425Y175967D01*
X851633Y175675D01*
X851883Y175467D01*
X852300Y175300D01*
X852675Y175258D01*
X853050Y175342D01*
X853300Y175467D01*
X853550Y175717D01*
X853717Y176008D01*
X853800Y176300D01*
Y176592D01*
X853717Y176883D01*
X853592Y177133D01*
X853425Y177342D01*
G01Y178483D02*
X853633Y178733D01*
X853758Y179025D01*
X853800Y179400D01*
X853717Y179775D01*
X853550Y180067D01*
X853258Y180275D01*
X852925Y180317D01*
X852592Y180233D01*
X852383Y180025D01*
X852217Y179733D01*
X852175Y179442D01*
X852217Y179150D01*
X852383Y178775D01*
X851300Y178900D01*
Y180025D01*
G01X853800Y181583D02*
X851300D01*
Y182417D01*
X851425Y182750D01*
X851592Y183000D01*
X851842Y183208D01*
X852133Y183375D01*
X852550Y183417D01*
X852967Y183375D01*
X853258Y183208D01*
X853508Y183000D01*
X853675Y182750D01*
X853800Y182417D01*
Y181583D01*
G01Y185600D02*
X851300D01*
X851800Y185100D01*
G01X853800D02*
Y186100D01*
G01X852758Y187908D02*
X852467Y188200D01*
X852300Y188450D01*
X852217Y188783D01*
X852300Y189075D01*
X852467Y189283D01*
X852717Y189450D01*
X853008Y189492D01*
X853258Y189450D01*
X853508Y189283D01*
X853717Y189033D01*
X853800Y188742D01*
X853717Y188408D01*
X853467Y188117D01*
X853092Y187950D01*
X852675Y187908D01*
X852133Y187992D01*
X851842Y188117D01*
X851550Y188325D01*
X851342Y188617D01*
X851300Y188908D01*
X851383Y189200D01*
X851592Y189408D01*
G01X861808Y177217D02*
X861683Y176967D01*
X861600Y176675D01*
Y176342D01*
X861725Y175967D01*
X861933Y175675D01*
X862183Y175467D01*
X862600Y175300D01*
X862975Y175258D01*
X863350Y175342D01*
X863600Y175467D01*
X863850Y175717D01*
X864017Y176008D01*
X864100Y176300D01*
Y176592D01*
X864017Y176883D01*
X863892Y177133D01*
X863725Y177342D01*
G01Y178483D02*
X863933Y178733D01*
X864058Y179025D01*
X864100Y179400D01*
X864017Y179775D01*
X863850Y180067D01*
X863558Y180275D01*
X863225Y180317D01*
X862892Y180233D01*
X862683Y180025D01*
X862517Y179733D01*
X862475Y179442D01*
X862517Y179150D01*
X862683Y178775D01*
X861600Y178900D01*
Y180025D01*
G01X864100Y181583D02*
X861600D01*
Y182417D01*
X861725Y182750D01*
X861892Y183000D01*
X862142Y183208D01*
X862433Y183375D01*
X862850Y183417D01*
X863267Y183375D01*
X863558Y183208D01*
X863808Y183000D01*
X863975Y182750D01*
X864100Y182417D01*
Y181583D01*
G01Y185600D02*
X861600D01*
X862100Y185100D01*
G01X864100D02*
Y186100D01*
G01X863808Y187992D02*
X864017Y188283D01*
X864100Y188617D01*
X864017Y188950D01*
X863767Y189242D01*
X863392Y189450D01*
X863017Y189533D01*
X862558D01*
X862183Y189450D01*
X861850Y189242D01*
X861683Y188992D01*
X861600Y188700D01*
X861683Y188367D01*
X861850Y188117D01*
X862100Y187950D01*
X862433Y187867D01*
X862725Y187950D01*
X863017Y188158D01*
X863183Y188408D01*
X863225Y188700D01*
X863142Y189033D01*
X862933Y189283D01*
X862558Y189533D01*
G01X858408Y177017D02*
X858283Y176767D01*
X858200Y176475D01*
Y176142D01*
X858325Y175767D01*
X858533Y175475D01*
X858783Y175267D01*
X859200Y175100D01*
X859575Y175058D01*
X859950Y175142D01*
X860200Y175267D01*
X860450Y175517D01*
X860617Y175808D01*
X860700Y176100D01*
Y176392D01*
X860617Y176683D01*
X860492Y176933D01*
X860325Y177142D01*
G01Y178283D02*
X860533Y178533D01*
X860658Y178825D01*
X860700Y179200D01*
X860617Y179575D01*
X860450Y179867D01*
X860158Y180075D01*
X859825Y180117D01*
X859492Y180033D01*
X859283Y179825D01*
X859117Y179533D01*
X859075Y179242D01*
X859117Y178950D01*
X859283Y178575D01*
X858200Y178700D01*
Y179825D01*
G01X860700Y181383D02*
X858200D01*
Y182217D01*
X858325Y182550D01*
X858492Y182800D01*
X858742Y183008D01*
X859033Y183175D01*
X859450Y183217D01*
X859867Y183175D01*
X860158Y183008D01*
X860408Y182800D01*
X860575Y182550D01*
X860700Y182217D01*
Y181383D01*
G01Y185400D02*
X858200D01*
X858700Y184900D01*
G01X860700D02*
Y185900D01*
G01Y188500D02*
X860658Y188792D01*
X860533Y189125D01*
X860325Y189333D01*
X860033Y189417D01*
X859742Y189333D01*
X859492Y189083D01*
X859367Y188708D01*
Y188292D01*
X859283Y188042D01*
X859075Y187833D01*
X858783Y187750D01*
X858492Y187875D01*
X858283Y188167D01*
X858200Y188500D01*
X858283Y188833D01*
X858492Y189125D01*
X858783Y189250D01*
X859075Y189167D01*
X859283Y188958D01*
X859367Y188708D01*
Y188292D01*
X859492Y187917D01*
X859742Y187667D01*
X860033Y187583D01*
X860325Y187667D01*
X860533Y187875D01*
X860658Y188208D01*
X860700Y188500D01*
G01X865008Y193017D02*
X864883Y192767D01*
X864800Y192475D01*
Y192142D01*
X864925Y191767D01*
X865133Y191475D01*
X865383Y191267D01*
X865800Y191100D01*
X866175Y191058D01*
X866550Y191142D01*
X866800Y191267D01*
X867050Y191517D01*
X867217Y191808D01*
X867300Y192100D01*
Y192392D01*
X867217Y192683D01*
X867092Y192933D01*
X866925Y193142D01*
G01Y194283D02*
X867133Y194533D01*
X867258Y194825D01*
X867300Y195200D01*
X867217Y195575D01*
X867050Y195867D01*
X866758Y196075D01*
X866425Y196117D01*
X866092Y196033D01*
X865883Y195825D01*
X865717Y195533D01*
X865675Y195242D01*
X865717Y194950D01*
X865883Y194575D01*
X864800Y194700D01*
Y195825D01*
G01X867300Y197383D02*
X864800D01*
Y198217D01*
X864925Y198550D01*
X865092Y198800D01*
X865342Y199008D01*
X865633Y199175D01*
X866050Y199217D01*
X866467Y199175D01*
X866758Y199008D01*
X867008Y198800D01*
X867175Y198550D01*
X867300Y198217D01*
Y197383D01*
G01X865217Y200608D02*
X864967Y200858D01*
X864842Y201150D01*
X864800Y201483D01*
X864883Y201900D01*
X865092Y202192D01*
X865342Y202275D01*
X865592Y202233D01*
X865800Y202067D01*
X866217Y201233D01*
X866508Y200858D01*
X866925Y200608D01*
X867300Y200525D01*
Y202275D01*
G01X868408Y193017D02*
X868283Y192767D01*
X868200Y192475D01*
Y192142D01*
X868325Y191767D01*
X868533Y191475D01*
X868783Y191267D01*
X869200Y191100D01*
X869575Y191058D01*
X869950Y191142D01*
X870200Y191267D01*
X870450Y191517D01*
X870617Y191808D01*
X870700Y192100D01*
Y192392D01*
X870617Y192683D01*
X870492Y192933D01*
X870325Y193142D01*
G01Y194283D02*
X870533Y194533D01*
X870658Y194825D01*
X870700Y195200D01*
X870617Y195575D01*
X870450Y195867D01*
X870158Y196075D01*
X869825Y196117D01*
X869492Y196033D01*
X869283Y195825D01*
X869117Y195533D01*
X869075Y195242D01*
X869117Y194950D01*
X869283Y194575D01*
X868200Y194700D01*
Y195825D01*
G01X870700Y197383D02*
X868200D01*
Y198217D01*
X868325Y198550D01*
X868492Y198800D01*
X868742Y199008D01*
X869033Y199175D01*
X869450Y199217D01*
X869867Y199175D01*
X870158Y199008D01*
X870408Y198800D01*
X870575Y198550D01*
X870700Y198217D01*
Y197383D01*
G01X870200Y200483D02*
X870492Y200733D01*
X870658Y201067D01*
X870700Y201442D01*
X870658Y201775D01*
X870450Y202108D01*
X870200Y202317D01*
X869950Y202358D01*
X869658Y202275D01*
X869450Y201983D01*
X869367Y201692D01*
Y201317D01*
G01Y201692D02*
X869242Y201942D01*
X869033Y202150D01*
X868783Y202233D01*
X868533Y202150D01*
X868325Y201942D01*
X868200Y201567D01*
X868242Y201192D01*
X868408Y200817D01*
G01X871808Y193017D02*
X871683Y192767D01*
X871600Y192475D01*
Y192142D01*
X871725Y191767D01*
X871933Y191475D01*
X872183Y191267D01*
X872600Y191100D01*
X872975Y191058D01*
X873350Y191142D01*
X873600Y191267D01*
X873850Y191517D01*
X874017Y191808D01*
X874100Y192100D01*
Y192392D01*
X874017Y192683D01*
X873892Y192933D01*
X873725Y193142D01*
G01Y194283D02*
X873933Y194533D01*
X874058Y194825D01*
X874100Y195200D01*
X874017Y195575D01*
X873850Y195867D01*
X873558Y196075D01*
X873225Y196117D01*
X872892Y196033D01*
X872683Y195825D01*
X872517Y195533D01*
X872475Y195242D01*
X872517Y194950D01*
X872683Y194575D01*
X871600Y194700D01*
Y195825D01*
G01X874100Y197383D02*
X871600D01*
Y198217D01*
X871725Y198550D01*
X871892Y198800D01*
X872142Y199008D01*
X872433Y199175D01*
X872850Y199217D01*
X873267Y199175D01*
X873558Y199008D01*
X873808Y198800D01*
X873975Y198550D01*
X874100Y198217D01*
Y197383D01*
G01Y201900D02*
X871600D01*
X873392Y200358D01*
Y202442D01*
G01X858208Y193017D02*
X858083Y192767D01*
X858000Y192475D01*
Y192142D01*
X858125Y191767D01*
X858333Y191475D01*
X858583Y191267D01*
X859000Y191100D01*
X859375Y191058D01*
X859750Y191142D01*
X860000Y191267D01*
X860250Y191517D01*
X860417Y191808D01*
X860500Y192100D01*
Y192392D01*
X860417Y192683D01*
X860292Y192933D01*
X860125Y193142D01*
G01Y194283D02*
X860333Y194533D01*
X860458Y194825D01*
X860500Y195200D01*
X860417Y195575D01*
X860250Y195867D01*
X859958Y196075D01*
X859625Y196117D01*
X859292Y196033D01*
X859083Y195825D01*
X858917Y195533D01*
X858875Y195242D01*
X858917Y194950D01*
X859083Y194575D01*
X858000Y194700D01*
Y195825D01*
G01X860500Y197383D02*
X858000D01*
Y198217D01*
X858125Y198550D01*
X858292Y198800D01*
X858542Y199008D01*
X858833Y199175D01*
X859250Y199217D01*
X859667Y199175D01*
X859958Y199008D01*
X860208Y198800D01*
X860375Y198550D01*
X860500Y198217D01*
Y197383D01*
G01Y201400D02*
X860458Y201692D01*
X860333Y202025D01*
X860125Y202233D01*
X859833Y202317D01*
X859542Y202233D01*
X859292Y201983D01*
X859167Y201608D01*
Y201192D01*
X859083Y200942D01*
X858875Y200733D01*
X858583Y200650D01*
X858292Y200775D01*
X858083Y201067D01*
X858000Y201400D01*
X858083Y201733D01*
X858292Y202025D01*
X858583Y202150D01*
X858875Y202067D01*
X859083Y201858D01*
X859167Y201608D01*
Y201192D01*
X859292Y200817D01*
X859542Y200567D01*
X859833Y200483D01*
X860125Y200567D01*
X860333Y200775D01*
X860458Y201108D01*
X860500Y201400D01*
G01X861608Y193017D02*
X861483Y192767D01*
X861400Y192475D01*
Y192142D01*
X861525Y191767D01*
X861733Y191475D01*
X861983Y191267D01*
X862400Y191100D01*
X862775Y191058D01*
X863150Y191142D01*
X863400Y191267D01*
X863650Y191517D01*
X863817Y191808D01*
X863900Y192100D01*
Y192392D01*
X863817Y192683D01*
X863692Y192933D01*
X863525Y193142D01*
G01Y194283D02*
X863733Y194533D01*
X863858Y194825D01*
X863900Y195200D01*
X863817Y195575D01*
X863650Y195867D01*
X863358Y196075D01*
X863025Y196117D01*
X862692Y196033D01*
X862483Y195825D01*
X862317Y195533D01*
X862275Y195242D01*
X862317Y194950D01*
X862483Y194575D01*
X861400Y194700D01*
Y195825D01*
G01X863900Y197383D02*
X861400D01*
Y198217D01*
X861525Y198550D01*
X861692Y198800D01*
X861942Y199008D01*
X862233Y199175D01*
X862650Y199217D01*
X863067Y199175D01*
X863358Y199008D01*
X863608Y198800D01*
X863775Y198550D01*
X863900Y198217D01*
Y197383D01*
G01Y201400D02*
X861400D01*
X861900Y200900D01*
G01X863900D02*
Y201900D01*
G01X854808Y193017D02*
X854683Y192767D01*
X854600Y192475D01*
Y192142D01*
X854725Y191767D01*
X854933Y191475D01*
X855183Y191267D01*
X855600Y191100D01*
X855975Y191058D01*
X856350Y191142D01*
X856600Y191267D01*
X856850Y191517D01*
X857017Y191808D01*
X857100Y192100D01*
Y192392D01*
X857017Y192683D01*
X856892Y192933D01*
X856725Y193142D01*
G01Y194283D02*
X856933Y194533D01*
X857058Y194825D01*
X857100Y195200D01*
X857017Y195575D01*
X856850Y195867D01*
X856558Y196075D01*
X856225Y196117D01*
X855892Y196033D01*
X855683Y195825D01*
X855517Y195533D01*
X855475Y195242D01*
X855517Y194950D01*
X855683Y194575D01*
X854600Y194700D01*
Y195825D01*
G01X857100Y197383D02*
X854600D01*
Y198217D01*
X854725Y198550D01*
X854892Y198800D01*
X855142Y199008D01*
X855433Y199175D01*
X855850Y199217D01*
X856267Y199175D01*
X856558Y199008D01*
X856808Y198800D01*
X856975Y198550D01*
X857100Y198217D01*
Y197383D01*
G01Y201317D02*
X856558Y201400D01*
X856100Y201525D01*
X855683Y201692D01*
X855225Y201900D01*
X854600Y202233D01*
Y200567D01*
G01X851408Y193017D02*
X851283Y192767D01*
X851200Y192475D01*
Y192142D01*
X851325Y191767D01*
X851533Y191475D01*
X851783Y191267D01*
X852200Y191100D01*
X852575Y191058D01*
X852950Y191142D01*
X853200Y191267D01*
X853450Y191517D01*
X853617Y191808D01*
X853700Y192100D01*
Y192392D01*
X853617Y192683D01*
X853492Y192933D01*
X853325Y193142D01*
G01Y194283D02*
X853533Y194533D01*
X853658Y194825D01*
X853700Y195200D01*
X853617Y195575D01*
X853450Y195867D01*
X853158Y196075D01*
X852825Y196117D01*
X852492Y196033D01*
X852283Y195825D01*
X852117Y195533D01*
X852075Y195242D01*
X852117Y194950D01*
X852283Y194575D01*
X851200Y194700D01*
Y195825D01*
G01X853700Y197383D02*
X851200D01*
Y198217D01*
X851325Y198550D01*
X851492Y198800D01*
X851742Y199008D01*
X852033Y199175D01*
X852450Y199217D01*
X852867Y199175D01*
X853158Y199008D01*
X853408Y198800D01*
X853575Y198550D01*
X853700Y198217D01*
Y197383D01*
G01X852658Y200608D02*
X852367Y200900D01*
X852200Y201150D01*
X852117Y201483D01*
X852200Y201775D01*
X852367Y201983D01*
X852617Y202150D01*
X852908Y202192D01*
X853158Y202150D01*
X853408Y201983D01*
X853617Y201733D01*
X853700Y201442D01*
X853617Y201108D01*
X853367Y200817D01*
X852992Y200650D01*
X852575Y200608D01*
X852033Y200692D01*
X851742Y200817D01*
X851450Y201025D01*
X851242Y201317D01*
X851200Y201608D01*
X851283Y201900D01*
X851492Y202108D01*
G01X869208Y159817D02*
X869083Y159567D01*
X869000Y159275D01*
Y158942D01*
X869125Y158567D01*
X869333Y158275D01*
X869583Y158067D01*
X870000Y157900D01*
X870375Y157858D01*
X870750Y157942D01*
X871000Y158067D01*
X871250Y158317D01*
X871417Y158608D01*
X871500Y158900D01*
Y159192D01*
X871417Y159483D01*
X871292Y159733D01*
X871125Y159942D01*
G01Y161083D02*
X871333Y161333D01*
X871458Y161625D01*
X871500Y162000D01*
X871417Y162375D01*
X871250Y162667D01*
X870958Y162875D01*
X870625Y162917D01*
X870292Y162833D01*
X870083Y162625D01*
X869917Y162333D01*
X869875Y162042D01*
X869917Y161750D01*
X870083Y161375D01*
X869000Y161500D01*
Y162625D01*
G01X871500Y164183D02*
X869000D01*
Y165017D01*
X869125Y165350D01*
X869292Y165600D01*
X869542Y165808D01*
X869833Y165975D01*
X870250Y166017D01*
X870667Y165975D01*
X870958Y165808D01*
X871208Y165600D01*
X871375Y165350D01*
X871500Y165017D01*
Y164183D01*
G01X871000Y167283D02*
X871292Y167533D01*
X871458Y167867D01*
X871500Y168242D01*
X871458Y168575D01*
X871250Y168908D01*
X871000Y169117D01*
X870750Y169158D01*
X870458Y169075D01*
X870250Y168783D01*
X870167Y168492D01*
Y168117D01*
G01Y168492D02*
X870042Y168742D01*
X869833Y168950D01*
X869583Y169033D01*
X869333Y168950D01*
X869125Y168742D01*
X869000Y168367D01*
X869042Y167992D01*
X869208Y167617D01*
G01X871500Y171800D02*
X869000D01*
X870792Y170258D01*
Y172342D01*
G01X872608Y159817D02*
X872483Y159567D01*
X872400Y159275D01*
Y158942D01*
X872525Y158567D01*
X872733Y158275D01*
X872983Y158067D01*
X873400Y157900D01*
X873775Y157858D01*
X874150Y157942D01*
X874400Y158067D01*
X874650Y158317D01*
X874817Y158608D01*
X874900Y158900D01*
Y159192D01*
X874817Y159483D01*
X874692Y159733D01*
X874525Y159942D01*
G01Y161083D02*
X874733Y161333D01*
X874858Y161625D01*
X874900Y162000D01*
X874817Y162375D01*
X874650Y162667D01*
X874358Y162875D01*
X874025Y162917D01*
X873692Y162833D01*
X873483Y162625D01*
X873317Y162333D01*
X873275Y162042D01*
X873317Y161750D01*
X873483Y161375D01*
X872400Y161500D01*
Y162625D01*
G01X874900Y164183D02*
X872400D01*
Y165017D01*
X872525Y165350D01*
X872692Y165600D01*
X872942Y165808D01*
X873233Y165975D01*
X873650Y166017D01*
X874067Y165975D01*
X874358Y165808D01*
X874608Y165600D01*
X874775Y165350D01*
X874900Y165017D01*
Y164183D01*
G01X874400Y167283D02*
X874692Y167533D01*
X874858Y167867D01*
X874900Y168242D01*
X874858Y168575D01*
X874650Y168908D01*
X874400Y169117D01*
X874150Y169158D01*
X873858Y169075D01*
X873650Y168783D01*
X873567Y168492D01*
Y168117D01*
G01Y168492D02*
X873442Y168742D01*
X873233Y168950D01*
X872983Y169033D01*
X872733Y168950D01*
X872525Y168742D01*
X872400Y168367D01*
X872442Y167992D01*
X872608Y167617D01*
G01X874525Y170383D02*
X874733Y170633D01*
X874858Y170925D01*
X874900Y171300D01*
X874817Y171675D01*
X874650Y171967D01*
X874358Y172175D01*
X874025Y172217D01*
X873692Y172133D01*
X873483Y171925D01*
X873317Y171633D01*
X873275Y171342D01*
X873317Y171050D01*
X873483Y170675D01*
X872400Y170800D01*
Y171925D01*
G01X855608Y159817D02*
X855483Y159567D01*
X855400Y159275D01*
Y158942D01*
X855525Y158567D01*
X855733Y158275D01*
X855983Y158067D01*
X856400Y157900D01*
X856775Y157858D01*
X857150Y157942D01*
X857400Y158067D01*
X857650Y158317D01*
X857817Y158608D01*
X857900Y158900D01*
Y159192D01*
X857817Y159483D01*
X857692Y159733D01*
X857525Y159942D01*
G01Y161083D02*
X857733Y161333D01*
X857858Y161625D01*
X857900Y162000D01*
X857817Y162375D01*
X857650Y162667D01*
X857358Y162875D01*
X857025Y162917D01*
X856692Y162833D01*
X856483Y162625D01*
X856317Y162333D01*
X856275Y162042D01*
X856317Y161750D01*
X856483Y161375D01*
X855400Y161500D01*
Y162625D01*
G01X857900Y164183D02*
X855400D01*
Y165017D01*
X855525Y165350D01*
X855692Y165600D01*
X855942Y165808D01*
X856233Y165975D01*
X856650Y166017D01*
X857067Y165975D01*
X857358Y165808D01*
X857608Y165600D01*
X857775Y165350D01*
X857900Y165017D01*
Y164183D01*
G01X857400Y167283D02*
X857692Y167533D01*
X857858Y167867D01*
X857900Y168242D01*
X857858Y168575D01*
X857650Y168908D01*
X857400Y169117D01*
X857150Y169158D01*
X856858Y169075D01*
X856650Y168783D01*
X856567Y168492D01*
Y168117D01*
G01Y168492D02*
X856442Y168742D01*
X856233Y168950D01*
X855983Y169033D01*
X855733Y168950D01*
X855525Y168742D01*
X855400Y168367D01*
X855442Y167992D01*
X855608Y167617D01*
G01X855400Y171300D02*
X855483Y170967D01*
X855692Y170717D01*
X855942Y170550D01*
X856275Y170425D01*
X856650Y170383D01*
X857025Y170425D01*
X857358Y170550D01*
X857608Y170717D01*
X857817Y170967D01*
X857900Y171300D01*
X857817Y171633D01*
X857608Y171883D01*
X857358Y172050D01*
X857025Y172175D01*
X856650Y172217D01*
X856275Y172175D01*
X855942Y172050D01*
X855692Y171883D01*
X855483Y171633D01*
X855400Y171300D01*
G01X852208Y159817D02*
X852083Y159567D01*
X852000Y159275D01*
Y158942D01*
X852125Y158567D01*
X852333Y158275D01*
X852583Y158067D01*
X853000Y157900D01*
X853375Y157858D01*
X853750Y157942D01*
X854000Y158067D01*
X854250Y158317D01*
X854417Y158608D01*
X854500Y158900D01*
Y159192D01*
X854417Y159483D01*
X854292Y159733D01*
X854125Y159942D01*
G01Y161083D02*
X854333Y161333D01*
X854458Y161625D01*
X854500Y162000D01*
X854417Y162375D01*
X854250Y162667D01*
X853958Y162875D01*
X853625Y162917D01*
X853292Y162833D01*
X853083Y162625D01*
X852917Y162333D01*
X852875Y162042D01*
X852917Y161750D01*
X853083Y161375D01*
X852000Y161500D01*
Y162625D01*
G01X854500Y164183D02*
X852000D01*
Y165017D01*
X852125Y165350D01*
X852292Y165600D01*
X852542Y165808D01*
X852833Y165975D01*
X853250Y166017D01*
X853667Y165975D01*
X853958Y165808D01*
X854208Y165600D01*
X854375Y165350D01*
X854500Y165017D01*
Y164183D01*
G01X852417Y167408D02*
X852167Y167658D01*
X852042Y167950D01*
X852000Y168283D01*
X852083Y168700D01*
X852292Y168992D01*
X852542Y169075D01*
X852792Y169033D01*
X853000Y168867D01*
X853417Y168033D01*
X853708Y167658D01*
X854125Y167408D01*
X854500Y167325D01*
Y169075D01*
G01X854208Y170592D02*
X854417Y170883D01*
X854500Y171217D01*
X854417Y171550D01*
X854167Y171842D01*
X853792Y172050D01*
X853417Y172133D01*
X852958D01*
X852583Y172050D01*
X852250Y171842D01*
X852083Y171592D01*
X852000Y171300D01*
X852083Y170967D01*
X852250Y170717D01*
X852500Y170550D01*
X852833Y170467D01*
X853125Y170550D01*
X853417Y170758D01*
X853583Y171008D01*
X853625Y171300D01*
X853542Y171633D01*
X853333Y171883D01*
X852958Y172133D01*
G01X848808Y159817D02*
X848683Y159567D01*
X848600Y159275D01*
Y158942D01*
X848725Y158567D01*
X848933Y158275D01*
X849183Y158067D01*
X849600Y157900D01*
X849975Y157858D01*
X850350Y157942D01*
X850600Y158067D01*
X850850Y158317D01*
X851017Y158608D01*
X851100Y158900D01*
Y159192D01*
X851017Y159483D01*
X850892Y159733D01*
X850725Y159942D01*
G01Y161083D02*
X850933Y161333D01*
X851058Y161625D01*
X851100Y162000D01*
X851017Y162375D01*
X850850Y162667D01*
X850558Y162875D01*
X850225Y162917D01*
X849892Y162833D01*
X849683Y162625D01*
X849517Y162333D01*
X849475Y162042D01*
X849517Y161750D01*
X849683Y161375D01*
X848600Y161500D01*
Y162625D01*
G01X851100Y164183D02*
X848600D01*
Y165017D01*
X848725Y165350D01*
X848892Y165600D01*
X849142Y165808D01*
X849433Y165975D01*
X849850Y166017D01*
X850267Y165975D01*
X850558Y165808D01*
X850808Y165600D01*
X850975Y165350D01*
X851100Y165017D01*
Y164183D01*
G01X849017Y167408D02*
X848767Y167658D01*
X848642Y167950D01*
X848600Y168283D01*
X848683Y168700D01*
X848892Y168992D01*
X849142Y169075D01*
X849392Y169033D01*
X849600Y168867D01*
X850017Y168033D01*
X850308Y167658D01*
X850725Y167408D01*
X851100Y167325D01*
Y169075D01*
G01Y171300D02*
X851058Y171592D01*
X850933Y171925D01*
X850725Y172133D01*
X850433Y172217D01*
X850142Y172133D01*
X849892Y171883D01*
X849767Y171508D01*
Y171092D01*
X849683Y170842D01*
X849475Y170633D01*
X849183Y170550D01*
X848892Y170675D01*
X848683Y170967D01*
X848600Y171300D01*
X848683Y171633D01*
X848892Y171925D01*
X849183Y172050D01*
X849475Y171967D01*
X849683Y171758D01*
X849767Y171508D01*
Y171092D01*
X849892Y170717D01*
X850142Y170467D01*
X850433Y170383D01*
X850725Y170467D01*
X850933Y170675D01*
X851058Y171008D01*
X851100Y171300D01*
G01X865808Y159817D02*
X865683Y159567D01*
X865600Y159275D01*
Y158942D01*
X865725Y158567D01*
X865933Y158275D01*
X866183Y158067D01*
X866600Y157900D01*
X866975Y157858D01*
X867350Y157942D01*
X867600Y158067D01*
X867850Y158317D01*
X868017Y158608D01*
X868100Y158900D01*
Y159192D01*
X868017Y159483D01*
X867892Y159733D01*
X867725Y159942D01*
G01Y161083D02*
X867933Y161333D01*
X868058Y161625D01*
X868100Y162000D01*
X868017Y162375D01*
X867850Y162667D01*
X867558Y162875D01*
X867225Y162917D01*
X866892Y162833D01*
X866683Y162625D01*
X866517Y162333D01*
X866475Y162042D01*
X866517Y161750D01*
X866683Y161375D01*
X865600Y161500D01*
Y162625D01*
G01X868100Y164183D02*
X865600D01*
Y165017D01*
X865725Y165350D01*
X865892Y165600D01*
X866142Y165808D01*
X866433Y165975D01*
X866850Y166017D01*
X867267Y165975D01*
X867558Y165808D01*
X867808Y165600D01*
X867975Y165350D01*
X868100Y165017D01*
Y164183D01*
G01X867600Y167283D02*
X867892Y167533D01*
X868058Y167867D01*
X868100Y168242D01*
X868058Y168575D01*
X867850Y168908D01*
X867600Y169117D01*
X867350Y169158D01*
X867058Y169075D01*
X866850Y168783D01*
X866767Y168492D01*
Y168117D01*
G01Y168492D02*
X866642Y168742D01*
X866433Y168950D01*
X866183Y169033D01*
X865933Y168950D01*
X865725Y168742D01*
X865600Y168367D01*
X865642Y167992D01*
X865808Y167617D01*
G01X867600Y170383D02*
X867892Y170633D01*
X868058Y170967D01*
X868100Y171342D01*
X868058Y171675D01*
X867850Y172008D01*
X867600Y172217D01*
X867350Y172258D01*
X867058Y172175D01*
X866850Y171883D01*
X866767Y171592D01*
Y171217D01*
G01Y171592D02*
X866642Y171842D01*
X866433Y172050D01*
X866183Y172133D01*
X865933Y172050D01*
X865725Y171842D01*
X865600Y171467D01*
X865642Y171092D01*
X865808Y170717D01*
G01X859008Y159817D02*
X858883Y159567D01*
X858800Y159275D01*
Y158942D01*
X858925Y158567D01*
X859133Y158275D01*
X859383Y158067D01*
X859800Y157900D01*
X860175Y157858D01*
X860550Y157942D01*
X860800Y158067D01*
X861050Y158317D01*
X861217Y158608D01*
X861300Y158900D01*
Y159192D01*
X861217Y159483D01*
X861092Y159733D01*
X860925Y159942D01*
G01Y161083D02*
X861133Y161333D01*
X861258Y161625D01*
X861300Y162000D01*
X861217Y162375D01*
X861050Y162667D01*
X860758Y162875D01*
X860425Y162917D01*
X860092Y162833D01*
X859883Y162625D01*
X859717Y162333D01*
X859675Y162042D01*
X859717Y161750D01*
X859883Y161375D01*
X858800Y161500D01*
Y162625D01*
G01X861300Y164183D02*
X858800D01*
Y165017D01*
X858925Y165350D01*
X859092Y165600D01*
X859342Y165808D01*
X859633Y165975D01*
X860050Y166017D01*
X860467Y165975D01*
X860758Y165808D01*
X861008Y165600D01*
X861175Y165350D01*
X861300Y165017D01*
Y164183D01*
G01X860800Y167283D02*
X861092Y167533D01*
X861258Y167867D01*
X861300Y168242D01*
X861258Y168575D01*
X861050Y168908D01*
X860800Y169117D01*
X860550Y169158D01*
X860258Y169075D01*
X860050Y168783D01*
X859967Y168492D01*
Y168117D01*
G01Y168492D02*
X859842Y168742D01*
X859633Y168950D01*
X859383Y169033D01*
X859133Y168950D01*
X858925Y168742D01*
X858800Y168367D01*
X858842Y167992D01*
X859008Y167617D01*
G01X861300Y171300D02*
X858800D01*
X859300Y170800D01*
G01X861300D02*
Y171800D01*
G01X862408Y159817D02*
X862283Y159567D01*
X862200Y159275D01*
Y158942D01*
X862325Y158567D01*
X862533Y158275D01*
X862783Y158067D01*
X863200Y157900D01*
X863575Y157858D01*
X863950Y157942D01*
X864200Y158067D01*
X864450Y158317D01*
X864617Y158608D01*
X864700Y158900D01*
Y159192D01*
X864617Y159483D01*
X864492Y159733D01*
X864325Y159942D01*
G01Y161083D02*
X864533Y161333D01*
X864658Y161625D01*
X864700Y162000D01*
X864617Y162375D01*
X864450Y162667D01*
X864158Y162875D01*
X863825Y162917D01*
X863492Y162833D01*
X863283Y162625D01*
X863117Y162333D01*
X863075Y162042D01*
X863117Y161750D01*
X863283Y161375D01*
X862200Y161500D01*
Y162625D01*
G01X864700Y164183D02*
X862200D01*
Y165017D01*
X862325Y165350D01*
X862492Y165600D01*
X862742Y165808D01*
X863033Y165975D01*
X863450Y166017D01*
X863867Y165975D01*
X864158Y165808D01*
X864408Y165600D01*
X864575Y165350D01*
X864700Y165017D01*
Y164183D01*
G01X864200Y167283D02*
X864492Y167533D01*
X864658Y167867D01*
X864700Y168242D01*
X864658Y168575D01*
X864450Y168908D01*
X864200Y169117D01*
X863950Y169158D01*
X863658Y169075D01*
X863450Y168783D01*
X863367Y168492D01*
Y168117D01*
G01Y168492D02*
X863242Y168742D01*
X863033Y168950D01*
X862783Y169033D01*
X862533Y168950D01*
X862325Y168742D01*
X862200Y168367D01*
X862242Y167992D01*
X862408Y167617D01*
G01X862617Y170508D02*
X862367Y170758D01*
X862242Y171050D01*
X862200Y171383D01*
X862283Y171800D01*
X862492Y172092D01*
X862742Y172175D01*
X862992Y172133D01*
X863200Y171967D01*
X863617Y171133D01*
X863908Y170758D01*
X864325Y170508D01*
X864700Y170425D01*
Y172175D01*
G01X849026Y218931D02*
X848901Y218681D01*
X848818Y218389D01*
Y218056D01*
X848943Y217681D01*
X849151Y217389D01*
X849401Y217181D01*
X849818Y217014D01*
X850193Y216972D01*
X850568Y217056D01*
X850818Y217181D01*
X851068Y217431D01*
X851235Y217722D01*
X851318Y218014D01*
Y218306D01*
X851235Y218597D01*
X851110Y218847D01*
X850943Y219056D01*
G01X851318Y221614D02*
X848818D01*
X850610Y220072D01*
Y222156D01*
G01X851318Y225047D02*
Y223381D01*
X848818D01*
Y225047D01*
G01X850026Y224381D02*
Y223381D01*
G01X851318Y227314D02*
X848818D01*
X849318Y226814D01*
G01X851318D02*
Y227814D01*
G01Y230414D02*
X848818D01*
X849318Y229914D01*
G01X851318D02*
Y230914D01*
G01X865208Y177417D02*
X865083Y177167D01*
X865000Y176875D01*
Y176542D01*
X865125Y176167D01*
X865333Y175875D01*
X865583Y175667D01*
X866000Y175500D01*
X866375Y175458D01*
X866750Y175542D01*
X867000Y175667D01*
X867250Y175917D01*
X867417Y176208D01*
X867500Y176500D01*
Y176792D01*
X867417Y177083D01*
X867292Y177333D01*
X867125Y177542D01*
G01Y178683D02*
X867333Y178933D01*
X867458Y179225D01*
X867500Y179600D01*
X867417Y179975D01*
X867250Y180267D01*
X866958Y180475D01*
X866625Y180517D01*
X866292Y180433D01*
X866083Y180225D01*
X865917Y179933D01*
X865875Y179642D01*
X865917Y179350D01*
X866083Y178975D01*
X865000Y179100D01*
Y180225D01*
G01Y181450D02*
X867500Y182033D01*
X865000Y182700D01*
X867500Y183367D01*
X865000Y183950D01*
G01X867500Y185800D02*
X865000D01*
X865500Y185300D01*
G01X867500D02*
Y186300D01*
G01X872108Y177467D02*
X871983Y177217D01*
X871900Y176925D01*
Y176592D01*
X872025Y176217D01*
X872233Y175925D01*
X872483Y175717D01*
X872900Y175550D01*
X873275Y175508D01*
X873650Y175592D01*
X873900Y175717D01*
X874150Y175967D01*
X874317Y176258D01*
X874400Y176550D01*
Y176842D01*
X874317Y177133D01*
X874192Y177383D01*
X874025Y177592D01*
G01Y178733D02*
X874233Y178983D01*
X874358Y179275D01*
X874400Y179650D01*
X874317Y180025D01*
X874150Y180317D01*
X873858Y180525D01*
X873525Y180567D01*
X873192Y180483D01*
X872983Y180275D01*
X872817Y179983D01*
X872775Y179692D01*
X872817Y179400D01*
X872983Y179025D01*
X871900Y179150D01*
Y180275D01*
G01Y181500D02*
X874400Y182083D01*
X871900Y182750D01*
X874400Y183417D01*
X871900Y184000D01*
G01X872317Y185058D02*
X872067Y185308D01*
X871942Y185600D01*
X871900Y185933D01*
X871983Y186350D01*
X872192Y186642D01*
X872442Y186725D01*
X872692Y186683D01*
X872900Y186517D01*
X873317Y185683D01*
X873608Y185308D01*
X874025Y185058D01*
X874400Y184975D01*
Y186725D01*
G01X874982Y217950D02*
X874732Y218075D01*
X874440Y218158D01*
X874107D01*
X873732Y218033D01*
X873440Y217825D01*
X873232Y217575D01*
X873065Y217158D01*
X873023Y216783D01*
X873107Y216408D01*
X873232Y216158D01*
X873482Y215908D01*
X873773Y215741D01*
X874065Y215658D01*
X874357D01*
X874648Y215741D01*
X874898Y215866D01*
X875107Y216033D01*
G01X877082Y215658D02*
X877165Y216200D01*
X877290Y216658D01*
X877457Y217075D01*
X877665Y217533D01*
X877998Y218158D01*
X876332D01*
G01X880515Y216908D02*
X881348D01*
Y216158D01*
X881098Y215908D01*
X880807Y215741D01*
X880390Y215658D01*
X879973Y215741D01*
X879682Y215908D01*
X879432Y216158D01*
X879265Y216450D01*
X879182Y216783D01*
Y217075D01*
X879265Y217325D01*
X879432Y217616D01*
X879682Y217866D01*
X879932Y218033D01*
X880265Y218158D01*
X880557D01*
X880890Y218075D01*
X881140Y217908D01*
G01X882448Y216158D02*
X882698Y215866D01*
X883032Y215700D01*
X883407Y215658D01*
X883740Y215700D01*
X884073Y215908D01*
X884282Y216158D01*
X884323Y216408D01*
X884240Y216700D01*
X883948Y216908D01*
X883657Y216991D01*
X883282D01*
G01X883657D02*
X883907Y217116D01*
X884115Y217325D01*
X884198Y217575D01*
X884115Y217825D01*
X883907Y218033D01*
X883532Y218158D01*
X883157Y218116D01*
X882782Y217950D01*
G01X886465Y215658D02*
X886757Y215700D01*
X887090Y215825D01*
X887298Y216033D01*
X887382Y216325D01*
X887298Y216616D01*
X887048Y216866D01*
X886673Y216991D01*
X886257D01*
X886007Y217075D01*
X885798Y217283D01*
X885715Y217575D01*
X885840Y217866D01*
X886132Y218075D01*
X886465Y218158D01*
X886798Y218075D01*
X887090Y217866D01*
X887215Y217575D01*
X887132Y217283D01*
X886923Y217075D01*
X886673Y216991D01*
X886257D01*
X885882Y216866D01*
X885632Y216616D01*
X885548Y216325D01*
X885632Y216033D01*
X885840Y215825D01*
X886173Y215700D01*
X886465Y215658D01*
G01X891263Y213935D02*
X891138Y213685D01*
X891055Y213393D01*
Y213060D01*
X891180Y212685D01*
X891388Y212393D01*
X891638Y212185D01*
X892055Y212018D01*
X892430Y211976D01*
X892805Y212060D01*
X893055Y212185D01*
X893305Y212435D01*
X893472Y212726D01*
X893555Y213018D01*
Y213310D01*
X893472Y213601D01*
X893347Y213851D01*
X893180Y214060D01*
G01X891055Y216118D02*
X893555D01*
G01X891055Y215160D02*
Y217076D01*
G01X893180Y218301D02*
X893388Y218551D01*
X893513Y218843D01*
X893555Y219218D01*
X893472Y219593D01*
X893305Y219885D01*
X893013Y220093D01*
X892680Y220135D01*
X892347Y220051D01*
X892138Y219843D01*
X891972Y219551D01*
X891930Y219260D01*
X891972Y218968D01*
X892138Y218593D01*
X891055Y218718D01*
Y219843D01*
G01X893555Y222818D02*
X891055D01*
X892847Y221276D01*
Y223360D01*
G01X874752Y213710D02*
X874502Y213835D01*
X874210Y213918D01*
X873877D01*
X873502Y213793D01*
X873210Y213585D01*
X873002Y213335D01*
X872835Y212918D01*
X872793Y212543D01*
X872877Y212168D01*
X873002Y211918D01*
X873252Y211668D01*
X873543Y211501D01*
X873835Y211418D01*
X874127D01*
X874418Y211501D01*
X874668Y211626D01*
X874877Y211793D01*
G01X876852Y211418D02*
X876935Y211960D01*
X877060Y212418D01*
X877227Y212835D01*
X877435Y213293D01*
X877768Y213918D01*
X876102D01*
G01X880285Y212668D02*
X881118D01*
Y211918D01*
X880868Y211668D01*
X880577Y211501D01*
X880160Y211418D01*
X879743Y211501D01*
X879452Y211668D01*
X879202Y211918D01*
X879035Y212210D01*
X878952Y212543D01*
Y212835D01*
X879035Y213085D01*
X879202Y213376D01*
X879452Y213626D01*
X879702Y213793D01*
X880035Y213918D01*
X880327D01*
X880660Y213835D01*
X880910Y213668D01*
G01X882218Y211918D02*
X882468Y211626D01*
X882802Y211460D01*
X883177Y211418D01*
X883510Y211460D01*
X883843Y211668D01*
X884052Y211918D01*
X884093Y212168D01*
X884010Y212460D01*
X883718Y212668D01*
X883427Y212751D01*
X883052D01*
G01X883427D02*
X883677Y212876D01*
X883885Y213085D01*
X883968Y213335D01*
X883885Y213585D01*
X883677Y213793D01*
X883302Y213918D01*
X882927Y213876D01*
X882552Y213710D01*
G01X886152Y211418D02*
X886235Y211960D01*
X886360Y212418D01*
X886527Y212835D01*
X886735Y213293D01*
X887068Y213918D01*
X885402D01*
G01X929134Y413583D02*
Y423622D01*
X901575D01*
Y332874D01*
X915354Y319095D01*
Y313189D01*
X917323D01*
Y289567D01*
X915354D01*
Y283662D01*
X901575Y269882D01*
Y179134D01*
X929134D01*
Y189174D01*
X1056693D01*
Y185237D01*
X1060630D01*
Y262992D01*
X1037559D01*
X1011614Y278583D01*
Y324174D01*
X1037559Y339764D01*
X1062992D01*
Y413583D01*
X1060630D01*
Y417520D01*
X1056693D01*
Y413583D01*
X929134D01*
G01X861428Y279390D02*
X858928D01*
Y280431D01*
X859053Y280765D01*
X859220Y280973D01*
X859553Y281056D01*
X859886Y280973D01*
X860095Y280723D01*
X860220Y280431D01*
Y279390D01*
G01Y280431D02*
X861428Y281056D01*
G01Y283823D02*
X858928D01*
X860720Y282281D01*
Y284365D01*
G01X861428Y285506D02*
X858928D01*
Y286340D01*
X859053Y286673D01*
X859220Y286923D01*
X859470Y287131D01*
X859761Y287298D01*
X860178Y287340D01*
X860595Y287298D01*
X860886Y287131D01*
X861136Y286923D01*
X861303Y286673D01*
X861428Y286340D01*
Y285506D01*
G01Y289440D02*
X860886Y289523D01*
X860428Y289648D01*
X860011Y289815D01*
X859553Y290023D01*
X858928Y290356D01*
Y288690D01*
G01X859345Y291831D02*
X859095Y292081D01*
X858970Y292373D01*
X858928Y292706D01*
X859011Y293123D01*
X859220Y293415D01*
X859470Y293498D01*
X859720Y293456D01*
X859928Y293290D01*
X860345Y292456D01*
X860636Y292081D01*
X861053Y291831D01*
X861428Y291748D01*
Y293498D01*
G01X876582Y220298D02*
Y222798D01*
X877623D01*
X877957Y222673D01*
X878165Y222506D01*
X878248Y222173D01*
X878165Y221840D01*
X877915Y221631D01*
X877623Y221506D01*
X876582D01*
G01X877623D02*
X878248Y220298D01*
G01X880515Y222798D02*
Y220298D01*
G01X879557Y222798D02*
X881473D01*
G01X882698Y220798D02*
X882948Y220506D01*
X883282Y220340D01*
X883657Y220298D01*
X883990Y220340D01*
X884323Y220548D01*
X884532Y220798D01*
X884573Y221048D01*
X884490Y221340D01*
X884198Y221548D01*
X883907Y221631D01*
X883532D01*
G01X883907D02*
X884157Y221756D01*
X884365Y221965D01*
X884448Y222215D01*
X884365Y222465D01*
X884157Y222673D01*
X883782Y222798D01*
X883407Y222756D01*
X883032Y222590D01*
G01X885923Y221340D02*
X886215Y221631D01*
X886465Y221798D01*
X886798Y221881D01*
X887090Y221798D01*
X887298Y221631D01*
X887465Y221381D01*
X887507Y221090D01*
X887465Y220840D01*
X887298Y220590D01*
X887048Y220381D01*
X886757Y220298D01*
X886423Y220381D01*
X886132Y220631D01*
X885965Y221006D01*
X885923Y221423D01*
X886007Y221965D01*
X886132Y222256D01*
X886340Y222548D01*
X886632Y222756D01*
X886923Y222798D01*
X887215Y222715D01*
X887423Y222506D01*
G01X898577Y228845D02*
X896077D01*
Y229886D01*
X896202Y230220D01*
X896369Y230428D01*
X896702Y230511D01*
X897035Y230428D01*
X897244Y230178D01*
X897369Y229886D01*
Y228845D01*
G01Y229886D02*
X898577Y230511D01*
G01X896077Y232778D02*
X898577D01*
G01X896077Y231820D02*
Y233736D01*
G01X898077Y234961D02*
X898369Y235211D01*
X898535Y235545D01*
X898577Y235920D01*
X898535Y236253D01*
X898327Y236586D01*
X898077Y236795D01*
X897827Y236836D01*
X897535Y236753D01*
X897327Y236461D01*
X897244Y236170D01*
Y235795D01*
G01Y236170D02*
X897119Y236420D01*
X896910Y236628D01*
X896660Y236711D01*
X896410Y236628D01*
X896202Y236420D01*
X896077Y236045D01*
X896119Y235670D01*
X896285Y235295D01*
G01X898077Y238061D02*
X898369Y238311D01*
X898535Y238645D01*
X898577Y239020D01*
X898535Y239353D01*
X898327Y239686D01*
X898077Y239895D01*
X897827Y239936D01*
X897535Y239853D01*
X897327Y239561D01*
X897244Y239270D01*
Y238895D01*
G01Y239270D02*
X897119Y239520D01*
X896910Y239728D01*
X896660Y239811D01*
X896410Y239728D01*
X896202Y239520D01*
X896077Y239145D01*
X896119Y238770D01*
X896285Y238395D01*
G01X849226Y235481D02*
X849101Y235231D01*
X849018Y234939D01*
Y234606D01*
X849143Y234231D01*
X849351Y233939D01*
X849601Y233731D01*
X850018Y233564D01*
X850393Y233522D01*
X850768Y233606D01*
X851018Y233731D01*
X851268Y233981D01*
X851435Y234272D01*
X851518Y234564D01*
Y234856D01*
X851435Y235147D01*
X851310Y235397D01*
X851143Y235606D01*
G01X851518Y238164D02*
X849018D01*
X850810Y236622D01*
Y238706D01*
G01X851518Y241597D02*
Y239931D01*
X849018D01*
Y241597D01*
G01X850226Y240931D02*
Y239931D01*
G01X851018Y242947D02*
X851310Y243197D01*
X851476Y243531D01*
X851518Y243906D01*
X851476Y244239D01*
X851268Y244572D01*
X851018Y244781D01*
X850768Y244822D01*
X850476Y244739D01*
X850268Y244447D01*
X850185Y244156D01*
Y243781D01*
G01Y244156D02*
X850060Y244406D01*
X849851Y244614D01*
X849601Y244697D01*
X849351Y244614D01*
X849143Y244406D01*
X849018Y244031D01*
X849060Y243656D01*
X849226Y243281D01*
G01X895534Y280113D02*
X895409Y279863D01*
X895326Y279571D01*
Y279238D01*
X895451Y278863D01*
X895659Y278571D01*
X895909Y278363D01*
X896326Y278196D01*
X896701Y278154D01*
X897076Y278238D01*
X897326Y278363D01*
X897576Y278613D01*
X897743Y278904D01*
X897826Y279196D01*
Y279488D01*
X897743Y279779D01*
X897618Y280029D01*
X897451Y280238D01*
G01X897826Y282796D02*
X895326D01*
X897118Y281254D01*
Y283338D01*
G01X897826Y284479D02*
X895326D01*
Y285313D01*
X895451Y285646D01*
X895618Y285896D01*
X895868Y286104D01*
X896159Y286271D01*
X896576Y286313D01*
X896993Y286271D01*
X897284Y286104D01*
X897534Y285896D01*
X897701Y285646D01*
X897826Y285313D01*
Y284479D01*
G01X897326Y287579D02*
X897618Y287829D01*
X897784Y288163D01*
X897826Y288538D01*
X897784Y288871D01*
X897576Y289204D01*
X897326Y289413D01*
X897076Y289454D01*
X896784Y289371D01*
X896576Y289079D01*
X896493Y288788D01*
Y288413D01*
G01Y288788D02*
X896368Y289038D01*
X896159Y289246D01*
X895909Y289329D01*
X895659Y289246D01*
X895451Y289038D01*
X895326Y288663D01*
X895368Y288288D01*
X895534Y287913D01*
G01X897826Y292096D02*
X895326D01*
X897118Y290554D01*
Y292638D01*
G01X862564Y277327D02*
X862439Y277077D01*
X862356Y276785D01*
Y276452D01*
X862481Y276077D01*
X862689Y275785D01*
X862939Y275577D01*
X863356Y275410D01*
X863731Y275368D01*
X864106Y275452D01*
X864356Y275577D01*
X864606Y275827D01*
X864773Y276118D01*
X864856Y276410D01*
Y276702D01*
X864773Y276993D01*
X864648Y277243D01*
X864481Y277452D01*
G01X862356Y279510D02*
X864856D01*
G01X862356Y278552D02*
Y280468D01*
G01X864356Y281693D02*
X864648Y281943D01*
X864814Y282277D01*
X864856Y282652D01*
X864814Y282985D01*
X864606Y283318D01*
X864356Y283527D01*
X864106Y283568D01*
X863814Y283485D01*
X863606Y283193D01*
X863523Y282902D01*
Y282527D01*
G01Y282902D02*
X863398Y283152D01*
X863189Y283360D01*
X862939Y283443D01*
X862689Y283360D01*
X862481Y283152D01*
X862356Y282777D01*
X862398Y282402D01*
X862564Y282027D01*
G01X864564Y285002D02*
X864773Y285293D01*
X864856Y285627D01*
X864773Y285960D01*
X864523Y286252D01*
X864148Y286460D01*
X863773Y286543D01*
X863314D01*
X862939Y286460D01*
X862606Y286252D01*
X862439Y286002D01*
X862356Y285710D01*
X862439Y285377D01*
X862606Y285127D01*
X862856Y284960D01*
X863189Y284877D01*
X863481Y284960D01*
X863773Y285168D01*
X863939Y285418D01*
X863981Y285710D01*
X863898Y286043D01*
X863689Y286293D01*
X863314Y286543D01*
G01X852113Y269221D02*
X851863Y269346D01*
X851571Y269429D01*
X851238D01*
X850863Y269304D01*
X850571Y269096D01*
X850363Y268846D01*
X850196Y268429D01*
X850154Y268054D01*
X850238Y267679D01*
X850363Y267429D01*
X850613Y267179D01*
X850904Y267012D01*
X851196Y266929D01*
X851488D01*
X851779Y267012D01*
X852029Y267137D01*
X852238Y267304D01*
G01X854796Y266929D02*
Y269429D01*
X853254Y267637D01*
X855338D01*
G01X856479Y266929D02*
Y269429D01*
X857313D01*
X857646Y269304D01*
X857896Y269137D01*
X858104Y268887D01*
X858271Y268596D01*
X858313Y268179D01*
X858271Y267762D01*
X858104Y267471D01*
X857896Y267221D01*
X857646Y267054D01*
X857313Y266929D01*
X856479D01*
G01X859579Y267304D02*
X859829Y267096D01*
X860121Y266971D01*
X860496Y266929D01*
X860871Y267012D01*
X861163Y267179D01*
X861371Y267471D01*
X861413Y267804D01*
X861329Y268137D01*
X861121Y268346D01*
X860829Y268512D01*
X860538Y268554D01*
X860246Y268512D01*
X859871Y268346D01*
X859996Y269429D01*
X861121D01*
G01X863596D02*
X863263Y269346D01*
X863013Y269137D01*
X862846Y268887D01*
X862721Y268554D01*
X862679Y268179D01*
X862721Y267804D01*
X862846Y267471D01*
X863013Y267221D01*
X863263Y267012D01*
X863596Y266929D01*
X863929Y267012D01*
X864179Y267221D01*
X864346Y267471D01*
X864471Y267804D01*
X864513Y268179D01*
X864471Y268554D01*
X864346Y268887D01*
X864179Y269137D01*
X863929Y269346D01*
X863596Y269429D01*
G01X852113Y272898D02*
X851863Y273023D01*
X851571Y273106D01*
X851238D01*
X850863Y272981D01*
X850571Y272773D01*
X850363Y272523D01*
X850196Y272106D01*
X850154Y271731D01*
X850238Y271356D01*
X850363Y271106D01*
X850613Y270856D01*
X850904Y270689D01*
X851196Y270606D01*
X851488D01*
X851779Y270689D01*
X852029Y270814D01*
X852238Y270981D01*
G01X854796Y270606D02*
Y273106D01*
X853254Y271314D01*
X855338D01*
G01X856479Y270606D02*
Y273106D01*
X857313D01*
X857646Y272981D01*
X857896Y272814D01*
X858104Y272564D01*
X858271Y272273D01*
X858313Y271856D01*
X858271Y271439D01*
X858104Y271148D01*
X857896Y270898D01*
X857646Y270731D01*
X857313Y270606D01*
X856479D01*
G01X860996D02*
Y273106D01*
X859454Y271314D01*
X861538D01*
G01X863596Y270606D02*
X863888Y270648D01*
X864221Y270773D01*
X864429Y270981D01*
X864513Y271273D01*
X864429Y271564D01*
X864179Y271814D01*
X863804Y271939D01*
X863388D01*
X863138Y272023D01*
X862929Y272231D01*
X862846Y272523D01*
X862971Y272814D01*
X863263Y273023D01*
X863596Y273106D01*
X863929Y273023D01*
X864221Y272814D01*
X864346Y272523D01*
X864263Y272231D01*
X864054Y272023D01*
X863804Y271939D01*
X863388D01*
X863013Y271814D01*
X862763Y271564D01*
X862679Y271273D01*
X862763Y270981D01*
X862971Y270773D01*
X863304Y270648D01*
X863596Y270606D01*
G01X869327Y262846D02*
X869077Y262971D01*
X868785Y263054D01*
X868452D01*
X868077Y262929D01*
X867785Y262721D01*
X867577Y262471D01*
X867410Y262054D01*
X867368Y261679D01*
X867452Y261304D01*
X867577Y261054D01*
X867827Y260804D01*
X868118Y260637D01*
X868410Y260554D01*
X868702D01*
X868993Y260637D01*
X869243Y260762D01*
X869452Y260929D01*
G01X872010Y260554D02*
Y263054D01*
X870468Y261262D01*
X872552D01*
G01X875443Y260554D02*
X873777D01*
Y263054D01*
X875443D01*
G01X874777Y261846D02*
X873777D01*
G01X876918Y262637D02*
X877168Y262887D01*
X877460Y263012D01*
X877793Y263054D01*
X878210Y262971D01*
X878502Y262762D01*
X878585Y262512D01*
X878543Y262262D01*
X878377Y262054D01*
X877543Y261637D01*
X877168Y261346D01*
X876918Y260929D01*
X876835Y260554D01*
X878585D01*
G01X880727D02*
X880810Y261096D01*
X880935Y261554D01*
X881102Y261971D01*
X881310Y262429D01*
X881643Y263054D01*
X879977D01*
G01X869457Y258469D02*
X869207Y258594D01*
X868915Y258677D01*
X868582D01*
X868207Y258552D01*
X867915Y258344D01*
X867707Y258094D01*
X867540Y257677D01*
X867498Y257302D01*
X867582Y256927D01*
X867707Y256677D01*
X867957Y256427D01*
X868248Y256260D01*
X868540Y256177D01*
X868832D01*
X869123Y256260D01*
X869373Y256385D01*
X869582Y256552D01*
G01X872140Y256177D02*
Y258677D01*
X870598Y256885D01*
X872682D01*
G01X875573Y256177D02*
X873907D01*
Y258677D01*
X875573D01*
G01X874907Y257469D02*
X873907D01*
G01X877048Y258260D02*
X877298Y258510D01*
X877590Y258635D01*
X877923Y258677D01*
X878340Y258594D01*
X878632Y258385D01*
X878715Y258135D01*
X878673Y257885D01*
X878507Y257677D01*
X877673Y257260D01*
X877298Y256969D01*
X877048Y256552D01*
X876965Y256177D01*
X878715D01*
G01X880940Y258677D02*
X880607Y258594D01*
X880357Y258385D01*
X880190Y258135D01*
X880065Y257802D01*
X880023Y257427D01*
X880065Y257052D01*
X880190Y256719D01*
X880357Y256469D01*
X880607Y256260D01*
X880940Y256177D01*
X881273Y256260D01*
X881523Y256469D01*
X881690Y256719D01*
X881815Y257052D01*
X881857Y257427D01*
X881815Y257802D01*
X881690Y258135D01*
X881523Y258385D01*
X881273Y258594D01*
X880940Y258677D01*
G01X853827Y259018D02*
X853577Y259143D01*
X853285Y259226D01*
X852952D01*
X852577Y259101D01*
X852285Y258893D01*
X852077Y258643D01*
X851910Y258226D01*
X851868Y257851D01*
X851952Y257476D01*
X852077Y257226D01*
X852327Y256976D01*
X852618Y256809D01*
X852910Y256726D01*
X853202D01*
X853493Y256809D01*
X853743Y256934D01*
X853952Y257101D01*
G01X856510Y256726D02*
Y259226D01*
X854968Y257434D01*
X857052D01*
G01X859943Y256726D02*
X858277D01*
Y259226D01*
X859943D01*
G01X859277Y258018D02*
X858277D01*
G01X861418Y258809D02*
X861668Y259059D01*
X861960Y259184D01*
X862293Y259226D01*
X862710Y259143D01*
X863002Y258934D01*
X863085Y258684D01*
X863043Y258434D01*
X862877Y258226D01*
X862043Y257809D01*
X861668Y257518D01*
X861418Y257101D01*
X861335Y256726D01*
X863085D01*
G01X864518Y257768D02*
X864810Y258059D01*
X865060Y258226D01*
X865393Y258309D01*
X865685Y258226D01*
X865893Y258059D01*
X866060Y257809D01*
X866102Y257518D01*
X866060Y257268D01*
X865893Y257018D01*
X865643Y256809D01*
X865352Y256726D01*
X865018Y256809D01*
X864727Y257059D01*
X864560Y257434D01*
X864518Y257851D01*
X864602Y258393D01*
X864727Y258684D01*
X864935Y258976D01*
X865227Y259184D01*
X865518Y259226D01*
X865810Y259143D01*
X866018Y258934D01*
G01X889329Y259285D02*
X889204Y259035D01*
X889121Y258743D01*
Y258410D01*
X889246Y258035D01*
X889454Y257743D01*
X889704Y257535D01*
X890121Y257368D01*
X890496Y257326D01*
X890871Y257410D01*
X891121Y257535D01*
X891371Y257785D01*
X891538Y258076D01*
X891621Y258368D01*
Y258660D01*
X891538Y258951D01*
X891413Y259201D01*
X891246Y259410D01*
G01X889121Y261468D02*
X891621D01*
G01X889121Y260510D02*
Y262426D01*
G01X891246Y263651D02*
X891454Y263901D01*
X891579Y264193D01*
X891621Y264568D01*
X891538Y264943D01*
X891371Y265235D01*
X891079Y265443D01*
X890746Y265485D01*
X890413Y265401D01*
X890204Y265193D01*
X890038Y264901D01*
X889996Y264610D01*
X890038Y264318D01*
X890204Y263943D01*
X889121Y264068D01*
Y265193D01*
G01X890364Y281757D02*
X890239Y281507D01*
X890156Y281215D01*
Y280882D01*
X890281Y280507D01*
X890489Y280215D01*
X890739Y280007D01*
X891156Y279840D01*
X891531Y279798D01*
X891906Y279882D01*
X892156Y280007D01*
X892406Y280257D01*
X892573Y280548D01*
X892656Y280840D01*
Y281132D01*
X892573Y281423D01*
X892448Y281673D01*
X892281Y281882D01*
G01X890156Y283940D02*
X892656D01*
G01X890156Y282982D02*
Y284898D01*
G01X892156Y286123D02*
X892448Y286373D01*
X892614Y286707D01*
X892656Y287082D01*
X892614Y287415D01*
X892406Y287748D01*
X892156Y287957D01*
X891906Y287998D01*
X891614Y287915D01*
X891406Y287623D01*
X891323Y287332D01*
Y286957D01*
G01Y287332D02*
X891198Y287582D01*
X890989Y287790D01*
X890739Y287873D01*
X890489Y287790D01*
X890281Y287582D01*
X890156Y287207D01*
X890198Y286832D01*
X890364Y286457D01*
G01X892656Y290140D02*
X892614Y290432D01*
X892489Y290765D01*
X892281Y290973D01*
X891989Y291057D01*
X891698Y290973D01*
X891448Y290723D01*
X891323Y290348D01*
Y289932D01*
X891239Y289682D01*
X891031Y289473D01*
X890739Y289390D01*
X890448Y289515D01*
X890239Y289807D01*
X890156Y290140D01*
X890239Y290473D01*
X890448Y290765D01*
X890739Y290890D01*
X891031Y290807D01*
X891239Y290598D01*
X891323Y290348D01*
Y289932D01*
X891448Y289557D01*
X891698Y289307D01*
X891989Y289223D01*
X892281Y289307D01*
X892489Y289515D01*
X892614Y289848D01*
X892656Y290140D01*
G01X871822Y237536D02*
X871572Y237661D01*
X871280Y237744D01*
X870947D01*
X870572Y237619D01*
X870280Y237411D01*
X870072Y237161D01*
X869905Y236744D01*
X869863Y236369D01*
X869947Y235994D01*
X870072Y235744D01*
X870322Y235494D01*
X870613Y235327D01*
X870905Y235244D01*
X871197D01*
X871488Y235327D01*
X871738Y235452D01*
X871947Y235619D01*
G01X873922Y235244D02*
X874005Y235786D01*
X874130Y236244D01*
X874297Y236661D01*
X874505Y237119D01*
X874838Y237744D01*
X873172D01*
G01X877355Y236494D02*
X878188D01*
Y235744D01*
X877938Y235494D01*
X877647Y235327D01*
X877230Y235244D01*
X876813Y235327D01*
X876522Y235494D01*
X876272Y235744D01*
X876105Y236036D01*
X876022Y236369D01*
Y236661D01*
X876105Y236911D01*
X876272Y237202D01*
X876522Y237452D01*
X876772Y237619D01*
X877105Y237744D01*
X877397D01*
X877730Y237661D01*
X877980Y237494D01*
G01X880705Y235244D02*
Y237744D01*
X879163Y235952D01*
X881247D01*
G01X883305Y237744D02*
X882972Y237661D01*
X882722Y237452D01*
X882555Y237202D01*
X882430Y236869D01*
X882388Y236494D01*
X882430Y236119D01*
X882555Y235786D01*
X882722Y235536D01*
X882972Y235327D01*
X883305Y235244D01*
X883638Y235327D01*
X883888Y235536D01*
X884055Y235786D01*
X884180Y236119D01*
X884222Y236494D01*
X884180Y236869D01*
X884055Y237202D01*
X883888Y237452D01*
X883638Y237661D01*
X883305Y237744D01*
G01X864559Y241226D02*
X864309Y241351D01*
X864017Y241434D01*
X863684D01*
X863309Y241309D01*
X863017Y241101D01*
X862809Y240851D01*
X862642Y240434D01*
X862600Y240059D01*
X862684Y239684D01*
X862809Y239434D01*
X863059Y239184D01*
X863350Y239017D01*
X863642Y238934D01*
X863934D01*
X864225Y239017D01*
X864475Y239142D01*
X864684Y239309D01*
G01X866659Y238934D02*
X866742Y239476D01*
X866867Y239934D01*
X867034Y240351D01*
X867242Y240809D01*
X867575Y241434D01*
X865909D01*
G01X870092Y240184D02*
X870925D01*
Y239434D01*
X870675Y239184D01*
X870384Y239017D01*
X869967Y238934D01*
X869550Y239017D01*
X869259Y239184D01*
X869009Y239434D01*
X868842Y239726D01*
X868759Y240059D01*
Y240351D01*
X868842Y240601D01*
X869009Y240892D01*
X869259Y241142D01*
X869509Y241309D01*
X869842Y241434D01*
X870134D01*
X870467Y241351D01*
X870717Y241184D01*
G01X873442Y238934D02*
Y241434D01*
X871900Y239642D01*
X873984D01*
G01X876042Y238934D02*
Y241434D01*
X875542Y240934D01*
G01Y238934D02*
X876542D01*
G01X864472Y245206D02*
X864222Y245331D01*
X863930Y245414D01*
X863597D01*
X863222Y245289D01*
X862930Y245081D01*
X862722Y244831D01*
X862555Y244414D01*
X862513Y244039D01*
X862597Y243664D01*
X862722Y243414D01*
X862972Y243164D01*
X863263Y242997D01*
X863555Y242914D01*
X863847D01*
X864138Y242997D01*
X864388Y243122D01*
X864597Y243289D01*
G01X866572Y242914D02*
X866655Y243456D01*
X866780Y243914D01*
X866947Y244331D01*
X867155Y244789D01*
X867488Y245414D01*
X865822D01*
G01X870005Y244164D02*
X870838D01*
Y243414D01*
X870588Y243164D01*
X870297Y242997D01*
X869880Y242914D01*
X869463Y242997D01*
X869172Y243164D01*
X868922Y243414D01*
X868755Y243706D01*
X868672Y244039D01*
Y244331D01*
X868755Y244581D01*
X868922Y244872D01*
X869172Y245122D01*
X869422Y245289D01*
X869755Y245414D01*
X870047D01*
X870380Y245331D01*
X870630Y245164D01*
G01X872063Y244997D02*
X872313Y245247D01*
X872605Y245372D01*
X872938Y245414D01*
X873355Y245331D01*
X873647Y245122D01*
X873730Y244872D01*
X873688Y244622D01*
X873522Y244414D01*
X872688Y243997D01*
X872313Y243706D01*
X872063Y243289D01*
X871980Y242914D01*
X873730D01*
G01X875247Y243206D02*
X875538Y242997D01*
X875872Y242914D01*
X876205Y242997D01*
X876497Y243247D01*
X876705Y243622D01*
X876788Y243997D01*
Y244456D01*
X876705Y244831D01*
X876497Y245164D01*
X876247Y245331D01*
X875955Y245414D01*
X875622Y245331D01*
X875372Y245164D01*
X875205Y244914D01*
X875122Y244581D01*
X875205Y244289D01*
X875413Y243997D01*
X875663Y243831D01*
X875955Y243789D01*
X876288Y243872D01*
X876538Y244081D01*
X876788Y244456D01*
G01X868772Y228207D02*
X868522Y228332D01*
X868230Y228415D01*
X867897D01*
X867522Y228290D01*
X867230Y228082D01*
X867022Y227832D01*
X866855Y227415D01*
X866813Y227040D01*
X866897Y226665D01*
X867022Y226415D01*
X867272Y226165D01*
X867563Y225998D01*
X867855Y225915D01*
X868147D01*
X868438Y225998D01*
X868688Y226123D01*
X868897Y226290D01*
G01X870872Y225915D02*
X870955Y226457D01*
X871080Y226915D01*
X871247Y227332D01*
X871455Y227790D01*
X871788Y228415D01*
X870122D01*
G01X874305Y227165D02*
X875138D01*
Y226415D01*
X874888Y226165D01*
X874597Y225998D01*
X874180Y225915D01*
X873763Y225998D01*
X873472Y226165D01*
X873222Y226415D01*
X873055Y226707D01*
X872972Y227040D01*
Y227332D01*
X873055Y227582D01*
X873222Y227873D01*
X873472Y228123D01*
X873722Y228290D01*
X874055Y228415D01*
X874347D01*
X874680Y228332D01*
X874930Y228165D01*
G01X876238Y226415D02*
X876488Y226123D01*
X876822Y225957D01*
X877197Y225915D01*
X877530Y225957D01*
X877863Y226165D01*
X878072Y226415D01*
X878113Y226665D01*
X878030Y226957D01*
X877738Y227165D01*
X877447Y227248D01*
X877072D01*
G01X877447D02*
X877697Y227373D01*
X877905Y227582D01*
X877988Y227832D01*
X877905Y228082D01*
X877697Y228290D01*
X877322Y228415D01*
X876947Y228373D01*
X876572Y228207D01*
G01X879463Y226957D02*
X879755Y227248D01*
X880005Y227415D01*
X880338Y227498D01*
X880630Y227415D01*
X880838Y227248D01*
X881005Y226998D01*
X881047Y226707D01*
X881005Y226457D01*
X880838Y226207D01*
X880588Y225998D01*
X880297Y225915D01*
X879963Y225998D01*
X879672Y226248D01*
X879505Y226623D01*
X879463Y227040D01*
X879547Y227582D01*
X879672Y227873D01*
X879880Y228165D01*
X880172Y228373D01*
X880463Y228415D01*
X880755Y228332D01*
X880963Y228123D01*
G01X889772Y227110D02*
X889522Y227235D01*
X889230Y227318D01*
X888897D01*
X888522Y227193D01*
X888230Y226985D01*
X888022Y226735D01*
X887855Y226318D01*
X887813Y225943D01*
X887897Y225568D01*
X888022Y225318D01*
X888272Y225068D01*
X888563Y224901D01*
X888855Y224818D01*
X889147D01*
X889438Y224901D01*
X889688Y225026D01*
X889897Y225193D01*
G01X891955Y227318D02*
Y224818D01*
G01X890997Y227318D02*
X892913D01*
G01X894138Y225193D02*
X894388Y224985D01*
X894680Y224860D01*
X895055Y224818D01*
X895430Y224901D01*
X895722Y225068D01*
X895930Y225360D01*
X895972Y225693D01*
X895888Y226026D01*
X895680Y226235D01*
X895388Y226401D01*
X895097Y226443D01*
X894805Y226401D01*
X894430Y226235D01*
X894555Y227318D01*
X895680D01*
G01X897363Y226901D02*
X897613Y227151D01*
X897905Y227276D01*
X898238Y227318D01*
X898655Y227235D01*
X898947Y227026D01*
X899030Y226776D01*
X898988Y226526D01*
X898822Y226318D01*
X897988Y225901D01*
X897613Y225610D01*
X897363Y225193D01*
X897280Y224818D01*
X899030D01*
G01X886473Y237825D02*
X886348Y237575D01*
X886265Y237283D01*
Y236950D01*
X886390Y236575D01*
X886598Y236283D01*
X886848Y236075D01*
X887265Y235908D01*
X887640Y235866D01*
X888015Y235950D01*
X888265Y236075D01*
X888515Y236325D01*
X888682Y236616D01*
X888765Y236908D01*
Y237200D01*
X888682Y237491D01*
X888557Y237741D01*
X888390Y237950D01*
G01X888765Y239925D02*
X888223Y240008D01*
X887765Y240133D01*
X887348Y240300D01*
X886890Y240508D01*
X886265Y240841D01*
Y239175D01*
G01X887515Y243358D02*
Y244191D01*
X888265D01*
X888515Y243941D01*
X888682Y243650D01*
X888765Y243233D01*
X888682Y242816D01*
X888515Y242525D01*
X888265Y242275D01*
X887973Y242108D01*
X887640Y242025D01*
X887348D01*
X887098Y242108D01*
X886807Y242275D01*
X886557Y242525D01*
X886390Y242775D01*
X886265Y243108D01*
Y243400D01*
X886348Y243733D01*
X886515Y243983D01*
G01X888265Y245291D02*
X888557Y245541D01*
X888723Y245875D01*
X888765Y246250D01*
X888723Y246583D01*
X888515Y246916D01*
X888265Y247125D01*
X888015Y247166D01*
X887723Y247083D01*
X887515Y246791D01*
X887432Y246500D01*
Y246125D01*
G01Y246500D02*
X887307Y246750D01*
X887098Y246958D01*
X886848Y247041D01*
X886598Y246958D01*
X886390Y246750D01*
X886265Y246375D01*
X886307Y246000D01*
X886473Y245625D01*
G01X886265Y249308D02*
X886348Y248975D01*
X886557Y248725D01*
X886807Y248558D01*
X887140Y248433D01*
X887515Y248391D01*
X887890Y248433D01*
X888223Y248558D01*
X888473Y248725D01*
X888682Y248975D01*
X888765Y249308D01*
X888682Y249641D01*
X888473Y249891D01*
X888223Y250058D01*
X887890Y250183D01*
X887515Y250225D01*
X887140Y250183D01*
X886807Y250058D01*
X886557Y249891D01*
X886348Y249641D01*
X886265Y249308D01*
G01X891203Y230995D02*
X891078Y230745D01*
X890995Y230453D01*
Y230120D01*
X891120Y229745D01*
X891328Y229453D01*
X891578Y229245D01*
X891995Y229078D01*
X892370Y229036D01*
X892745Y229120D01*
X892995Y229245D01*
X893245Y229495D01*
X893412Y229786D01*
X893495Y230078D01*
Y230370D01*
X893412Y230661D01*
X893287Y230911D01*
X893120Y231120D01*
G01X893495Y233095D02*
X892953Y233178D01*
X892495Y233303D01*
X892078Y233470D01*
X891620Y233678D01*
X890995Y234011D01*
Y232345D01*
G01X892245Y236528D02*
Y237361D01*
X892995D01*
X893245Y237111D01*
X893412Y236820D01*
X893495Y236403D01*
X893412Y235986D01*
X893245Y235695D01*
X892995Y235445D01*
X892703Y235278D01*
X892370Y235195D01*
X892078D01*
X891828Y235278D01*
X891537Y235445D01*
X891287Y235695D01*
X891120Y235945D01*
X890995Y236278D01*
Y236570D01*
X891078Y236903D01*
X891245Y237153D01*
G01X892995Y238461D02*
X893287Y238711D01*
X893453Y239045D01*
X893495Y239420D01*
X893453Y239753D01*
X893245Y240086D01*
X892995Y240295D01*
X892745Y240336D01*
X892453Y240253D01*
X892245Y239961D01*
X892162Y239670D01*
Y239295D01*
G01Y239670D02*
X892037Y239920D01*
X891828Y240128D01*
X891578Y240211D01*
X891328Y240128D01*
X891120Y239920D01*
X890995Y239545D01*
X891037Y239170D01*
X891203Y238795D01*
G01X893495Y242478D02*
X890995D01*
X891495Y241978D01*
G01X893495D02*
Y242978D01*
G01X896203Y244015D02*
X896078Y243765D01*
X895995Y243473D01*
Y243140D01*
X896120Y242765D01*
X896328Y242473D01*
X896578Y242265D01*
X896995Y242098D01*
X897370Y242056D01*
X897745Y242140D01*
X897995Y242265D01*
X898245Y242515D01*
X898412Y242806D01*
X898495Y243098D01*
Y243390D01*
X898412Y243681D01*
X898287Y243931D01*
X898120Y244140D01*
G01X895995Y246198D02*
X898495D01*
G01X895995Y245240D02*
Y247156D01*
G01X898495Y249798D02*
X895995D01*
X897787Y248256D01*
Y250340D01*
G01X898203Y251690D02*
X898412Y251981D01*
X898495Y252315D01*
X898412Y252648D01*
X898162Y252940D01*
X897787Y253148D01*
X897412Y253231D01*
X896953D01*
X896578Y253148D01*
X896245Y252940D01*
X896078Y252690D01*
X895995Y252398D01*
X896078Y252065D01*
X896245Y251815D01*
X896495Y251648D01*
X896828Y251565D01*
X897120Y251648D01*
X897412Y251856D01*
X897578Y252106D01*
X897620Y252398D01*
X897537Y252731D01*
X897328Y252981D01*
X896953Y253231D01*
G01X855429Y234824D02*
Y237324D01*
X856470D01*
X856804Y237199D01*
X857012Y237032D01*
X857095Y236699D01*
X857012Y236366D01*
X856762Y236157D01*
X856470Y236032D01*
X855429D01*
G01X856470D02*
X857095Y234824D01*
G01X859362Y237324D02*
Y234824D01*
G01X858404Y237324D02*
X860320D01*
G01X861545Y235324D02*
X861795Y235032D01*
X862129Y234866D01*
X862504Y234824D01*
X862837Y234866D01*
X863170Y235074D01*
X863379Y235324D01*
X863420Y235574D01*
X863337Y235866D01*
X863045Y236074D01*
X862754Y236157D01*
X862379D01*
G01X862754D02*
X863004Y236282D01*
X863212Y236491D01*
X863295Y236741D01*
X863212Y236991D01*
X863004Y237199D01*
X862629Y237324D01*
X862254Y237282D01*
X861879Y237116D01*
G01X864645Y235199D02*
X864895Y234991D01*
X865187Y234866D01*
X865562Y234824D01*
X865937Y234907D01*
X866229Y235074D01*
X866437Y235366D01*
X866479Y235699D01*
X866395Y236032D01*
X866187Y236241D01*
X865895Y236407D01*
X865604Y236449D01*
X865312Y236407D01*
X864937Y236241D01*
X865062Y237324D01*
X866187D01*
G01X887297Y257441D02*
X884797D01*
Y258482D01*
X884922Y258816D01*
X885089Y259024D01*
X885422Y259107D01*
X885755Y259024D01*
X885964Y258774D01*
X886089Y258482D01*
Y257441D01*
G01Y258482D02*
X887297Y259107D01*
G01X884797Y261374D02*
X887297D01*
G01X884797Y260416D02*
Y262332D01*
G01X887297Y264974D02*
X884797D01*
X886589Y263432D01*
Y265516D01*
G01X868124Y266373D02*
Y264707D01*
X865624D01*
Y266373D01*
G01X866832Y265707D02*
Y264707D01*
G01X865624Y267723D02*
X867416D01*
X867791Y267890D01*
X868041Y268223D01*
X868124Y268640D01*
X868041Y269057D01*
X867791Y269390D01*
X867416Y269557D01*
X865624D01*
G01X868124Y272240D02*
X865624D01*
X867416Y270698D01*
Y272782D01*
G01X868124Y273923D02*
X865624D01*
Y274757D01*
X865749Y275090D01*
X865916Y275340D01*
X866166Y275548D01*
X866457Y275715D01*
X866874Y275757D01*
X867291Y275715D01*
X867582Y275548D01*
X867832Y275340D01*
X867999Y275090D01*
X868124Y274757D01*
Y273923D01*
G01X867082Y277148D02*
X866791Y277440D01*
X866624Y277690D01*
X866541Y278023D01*
X866624Y278315D01*
X866791Y278523D01*
X867041Y278690D01*
X867332Y278732D01*
X867582Y278690D01*
X867832Y278523D01*
X868041Y278273D01*
X868124Y277982D01*
X868041Y277648D01*
X867791Y277357D01*
X867416Y277190D01*
X866999Y277148D01*
X866457Y277232D01*
X866166Y277357D01*
X865874Y277565D01*
X865666Y277857D01*
X865624Y278148D01*
X865707Y278440D01*
X865916Y278648D01*
G01X868688Y230215D02*
X867022D01*
Y232715D01*
X868688D01*
G01X868022Y231507D02*
X867022D01*
G01X870038Y232715D02*
Y230923D01*
X870205Y230548D01*
X870538Y230298D01*
X870955Y230215D01*
X871372Y230298D01*
X871705Y230548D01*
X871872Y230923D01*
Y232715D01*
G01X873972Y230215D02*
X874055Y230757D01*
X874180Y231215D01*
X874347Y231632D01*
X874555Y232090D01*
X874888Y232715D01*
X873222D01*
G01X877405Y231465D02*
X878238D01*
Y230715D01*
X877988Y230465D01*
X877697Y230298D01*
X877280Y230215D01*
X876863Y230298D01*
X876572Y230465D01*
X876322Y230715D01*
X876155Y231007D01*
X876072Y231340D01*
Y231632D01*
X876155Y231882D01*
X876322Y232173D01*
X876572Y232423D01*
X876822Y232590D01*
X877155Y232715D01*
X877447D01*
X877780Y232632D01*
X878030Y232465D01*
G01X879338Y230715D02*
X879588Y230423D01*
X879922Y230257D01*
X880297Y230215D01*
X880630Y230257D01*
X880963Y230465D01*
X881172Y230715D01*
X881213Y230965D01*
X881130Y231257D01*
X880838Y231465D01*
X880547Y231548D01*
X880172D01*
G01X880547D02*
X880797Y231673D01*
X881005Y231882D01*
X881088Y232132D01*
X881005Y232382D01*
X880797Y232590D01*
X880422Y232715D01*
X880047Y232673D01*
X879672Y232507D01*
G01X864888Y249014D02*
X863222D01*
Y251514D01*
X864888D01*
G01X864222Y250306D02*
X863222D01*
G01X866238Y251514D02*
Y249722D01*
X866405Y249347D01*
X866738Y249097D01*
X867155Y249014D01*
X867572Y249097D01*
X867905Y249347D01*
X868072Y249722D01*
Y251514D01*
G01X870172Y249014D02*
X870255Y249556D01*
X870380Y250014D01*
X870547Y250431D01*
X870755Y250889D01*
X871088Y251514D01*
X869422D01*
G01X873605Y250264D02*
X874438D01*
Y249514D01*
X874188Y249264D01*
X873897Y249097D01*
X873480Y249014D01*
X873063Y249097D01*
X872772Y249264D01*
X872522Y249514D01*
X872355Y249806D01*
X872272Y250139D01*
Y250431D01*
X872355Y250681D01*
X872522Y250972D01*
X872772Y251222D01*
X873022Y251389D01*
X873355Y251514D01*
X873647D01*
X873980Y251431D01*
X874230Y251264D01*
G01X875663Y251097D02*
X875913Y251347D01*
X876205Y251472D01*
X876538Y251514D01*
X876955Y251431D01*
X877247Y251222D01*
X877330Y250972D01*
X877288Y250722D01*
X877122Y250514D01*
X876288Y250097D01*
X875913Y249806D01*
X875663Y249389D01*
X875580Y249014D01*
X877330D01*
G01X869233Y266617D02*
X871733D01*
Y268283D01*
G01Y271050D02*
X869233D01*
X871025Y269508D01*
Y271592D01*
G01X871733Y272733D02*
X869233D01*
Y273567D01*
X869358Y273900D01*
X869525Y274150D01*
X869775Y274358D01*
X870066Y274525D01*
X870483Y274567D01*
X870900Y274525D01*
X871191Y274358D01*
X871441Y274150D01*
X871608Y273900D01*
X871733Y273567D01*
Y272733D01*
G01X871233Y275833D02*
X871525Y276083D01*
X871691Y276417D01*
X871733Y276792D01*
X871691Y277125D01*
X871483Y277458D01*
X871233Y277667D01*
X870983Y277708D01*
X870691Y277625D01*
X870483Y277333D01*
X870400Y277042D01*
Y276667D01*
G01Y277042D02*
X870275Y277292D01*
X870066Y277500D01*
X869816Y277583D01*
X869566Y277500D01*
X869358Y277292D01*
X869233Y276917D01*
X869275Y276542D01*
X869441Y276167D01*
G01X892570Y314754D02*
X892445Y314504D01*
X892362Y314212D01*
Y313879D01*
X892487Y313504D01*
X892695Y313212D01*
X892945Y313004D01*
X893362Y312837D01*
X893737Y312795D01*
X894112Y312879D01*
X894362Y313004D01*
X894612Y313254D01*
X894779Y313545D01*
X894862Y313837D01*
Y314129D01*
X894779Y314420D01*
X894654Y314670D01*
X894487Y314879D01*
G01X894862Y317437D02*
X892362D01*
X894154Y315895D01*
Y317979D01*
G01X894862Y319120D02*
X892362D01*
Y319954D01*
X892487Y320287D01*
X892654Y320537D01*
X892904Y320745D01*
X893195Y320912D01*
X893612Y320954D01*
X894029Y320912D01*
X894320Y320745D01*
X894570Y320537D01*
X894737Y320287D01*
X894862Y319954D01*
Y319120D01*
G01Y323137D02*
X892362D01*
X892862Y322637D01*
G01X894862D02*
Y323637D01*
G01X892779Y325445D02*
X892529Y325695D01*
X892404Y325987D01*
X892362Y326320D01*
X892445Y326737D01*
X892654Y327029D01*
X892904Y327112D01*
X893154Y327070D01*
X893362Y326904D01*
X893779Y326070D01*
X894070Y325695D01*
X894487Y325445D01*
X894862Y325362D01*
Y327112D01*
G01X863710Y313672D02*
X863585Y313422D01*
X863502Y313130D01*
Y312797D01*
X863627Y312422D01*
X863835Y312130D01*
X864085Y311922D01*
X864502Y311755D01*
X864877Y311713D01*
X865252Y311797D01*
X865502Y311922D01*
X865752Y312172D01*
X865919Y312463D01*
X866002Y312755D01*
Y313047D01*
X865919Y313338D01*
X865794Y313588D01*
X865627Y313797D01*
G01X866002Y316355D02*
X863502D01*
X865294Y314813D01*
Y316897D01*
G01X866002Y318038D02*
X863502D01*
Y318872D01*
X863627Y319205D01*
X863794Y319455D01*
X864044Y319663D01*
X864335Y319830D01*
X864752Y319872D01*
X865169Y319830D01*
X865460Y319663D01*
X865710Y319455D01*
X865877Y319205D01*
X866002Y318872D01*
Y318038D01*
G01Y321972D02*
X865460Y322055D01*
X865002Y322180D01*
X864585Y322347D01*
X864127Y322555D01*
X863502Y322888D01*
Y321222D01*
G01X870187Y283092D02*
X869937Y283217D01*
X869645Y283300D01*
X869312D01*
X868937Y283175D01*
X868645Y282967D01*
X868437Y282717D01*
X868270Y282300D01*
X868228Y281925D01*
X868312Y281550D01*
X868437Y281300D01*
X868687Y281050D01*
X868978Y280883D01*
X869270Y280800D01*
X869562D01*
X869853Y280883D01*
X870103Y281008D01*
X870312Y281175D01*
G01X872870Y280800D02*
Y283300D01*
X871328Y281508D01*
X873412D01*
G01X874553Y280800D02*
Y283300D01*
X875387D01*
X875720Y283175D01*
X875970Y283008D01*
X876178Y282758D01*
X876345Y282467D01*
X876387Y282050D01*
X876345Y281633D01*
X876178Y281342D01*
X875970Y281092D01*
X875720Y280925D01*
X875387Y280800D01*
X874553D01*
G01X879070D02*
Y283300D01*
X877528Y281508D01*
X879612D01*
G01X880962Y281092D02*
X881253Y280883D01*
X881587Y280800D01*
X881920Y280883D01*
X882212Y281133D01*
X882420Y281508D01*
X882503Y281883D01*
Y282342D01*
X882420Y282717D01*
X882212Y283050D01*
X881962Y283217D01*
X881670Y283300D01*
X881337Y283217D01*
X881087Y283050D01*
X880920Y282800D01*
X880837Y282467D01*
X880920Y282175D01*
X881128Y281883D01*
X881378Y281717D01*
X881670Y281675D01*
X882003Y281758D01*
X882253Y281967D01*
X882503Y282342D01*
G01X869527Y318598D02*
X869277Y318723D01*
X868985Y318806D01*
X868652D01*
X868277Y318681D01*
X867985Y318473D01*
X867777Y318223D01*
X867610Y317806D01*
X867568Y317431D01*
X867652Y317056D01*
X867777Y316806D01*
X868027Y316556D01*
X868318Y316389D01*
X868610Y316306D01*
X868902D01*
X869193Y316389D01*
X869443Y316514D01*
X869652Y316681D01*
G01X872210Y316306D02*
Y318806D01*
X870668Y317014D01*
X872752D01*
G01X873893Y316306D02*
Y318806D01*
X874727D01*
X875060Y318681D01*
X875310Y318514D01*
X875518Y318264D01*
X875685Y317973D01*
X875727Y317556D01*
X875685Y317139D01*
X875518Y316848D01*
X875310Y316598D01*
X875060Y316431D01*
X874727Y316306D01*
X873893D01*
G01X876993Y316806D02*
X877243Y316514D01*
X877577Y316348D01*
X877952Y316306D01*
X878285Y316348D01*
X878618Y316556D01*
X878827Y316806D01*
X878868Y317056D01*
X878785Y317348D01*
X878493Y317556D01*
X878202Y317639D01*
X877827D01*
G01X878202D02*
X878452Y317764D01*
X878660Y317973D01*
X878743Y318223D01*
X878660Y318473D01*
X878452Y318681D01*
X878077Y318806D01*
X877702Y318764D01*
X877327Y318598D01*
G01X880093Y316681D02*
X880343Y316473D01*
X880635Y316348D01*
X881010Y316306D01*
X881385Y316389D01*
X881677Y316556D01*
X881885Y316848D01*
X881927Y317181D01*
X881843Y317514D01*
X881635Y317723D01*
X881343Y317889D01*
X881052Y317931D01*
X880760Y317889D01*
X880385Y317723D01*
X880510Y318806D01*
X881635D01*
G01X867363Y290545D02*
X867113Y290670D01*
X866821Y290753D01*
X866488D01*
X866113Y290628D01*
X865821Y290420D01*
X865613Y290170D01*
X865446Y289753D01*
X865404Y289378D01*
X865488Y289003D01*
X865613Y288753D01*
X865863Y288503D01*
X866154Y288336D01*
X866446Y288253D01*
X866738D01*
X867029Y288336D01*
X867279Y288461D01*
X867488Y288628D01*
G01X870046Y288253D02*
Y290753D01*
X868504Y288961D01*
X870588D01*
G01X871729Y288253D02*
Y290753D01*
X872563D01*
X872896Y290628D01*
X873146Y290461D01*
X873354Y290211D01*
X873521Y289920D01*
X873563Y289503D01*
X873521Y289086D01*
X873354Y288795D01*
X873146Y288545D01*
X872896Y288378D01*
X872563Y288253D01*
X871729D01*
G01X875746D02*
Y290753D01*
X875246Y290253D01*
G01Y288253D02*
X876246D01*
G01X878054Y289295D02*
X878346Y289586D01*
X878596Y289753D01*
X878929Y289836D01*
X879221Y289753D01*
X879429Y289586D01*
X879596Y289336D01*
X879638Y289045D01*
X879596Y288795D01*
X879429Y288545D01*
X879179Y288336D01*
X878888Y288253D01*
X878554Y288336D01*
X878263Y288586D01*
X878096Y288961D01*
X878054Y289378D01*
X878138Y289920D01*
X878263Y290211D01*
X878471Y290503D01*
X878763Y290711D01*
X879054Y290753D01*
X879346Y290670D01*
X879554Y290461D01*
G01X859291Y312920D02*
X859166Y312670D01*
X859083Y312378D01*
Y312045D01*
X859208Y311670D01*
X859416Y311378D01*
X859666Y311170D01*
X860083Y311003D01*
X860458Y310961D01*
X860833Y311045D01*
X861083Y311170D01*
X861333Y311420D01*
X861500Y311711D01*
X861583Y312003D01*
Y312295D01*
X861500Y312586D01*
X861375Y312836D01*
X861208Y313045D01*
G01X859083Y315103D02*
X861583D01*
G01X859083Y314145D02*
Y316061D01*
G01X861583Y318703D02*
X859083D01*
X860875Y317161D01*
Y319245D01*
G01X859083Y321303D02*
X859166Y320970D01*
X859375Y320720D01*
X859625Y320553D01*
X859958Y320428D01*
X860333Y320386D01*
X860708Y320428D01*
X861041Y320553D01*
X861291Y320720D01*
X861500Y320970D01*
X861583Y321303D01*
X861500Y321636D01*
X861291Y321886D01*
X861041Y322053D01*
X860708Y322178D01*
X860333Y322220D01*
X859958Y322178D01*
X859625Y322053D01*
X859375Y321886D01*
X859166Y321636D01*
X859083Y321303D01*
G01X850790Y299186D02*
X850540Y299311D01*
X850248Y299394D01*
X849915D01*
X849540Y299269D01*
X849248Y299061D01*
X849040Y298811D01*
X848873Y298394D01*
X848831Y298019D01*
X848915Y297644D01*
X849040Y297394D01*
X849290Y297144D01*
X849581Y296977D01*
X849873Y296894D01*
X850165D01*
X850456Y296977D01*
X850706Y297102D01*
X850915Y297269D01*
G01X853473Y296894D02*
Y299394D01*
X851931Y297602D01*
X854015D01*
G01X855156Y296894D02*
Y299394D01*
X855990D01*
X856323Y299269D01*
X856573Y299102D01*
X856781Y298852D01*
X856948Y298561D01*
X856990Y298144D01*
X856948Y297727D01*
X856781Y297436D01*
X856573Y297186D01*
X856323Y297019D01*
X855990Y296894D01*
X855156D01*
G01X858381Y298977D02*
X858631Y299227D01*
X858923Y299352D01*
X859256Y299394D01*
X859673Y299311D01*
X859965Y299102D01*
X860048Y298852D01*
X860006Y298602D01*
X859840Y298394D01*
X859006Y297977D01*
X858631Y297686D01*
X858381Y297269D01*
X858298Y296894D01*
X860048D01*
G01X862273D02*
X862565Y296936D01*
X862898Y297061D01*
X863106Y297269D01*
X863190Y297561D01*
X863106Y297852D01*
X862856Y298102D01*
X862481Y298227D01*
X862065D01*
X861815Y298311D01*
X861606Y298519D01*
X861523Y298811D01*
X861648Y299102D01*
X861940Y299311D01*
X862273Y299394D01*
X862606Y299311D01*
X862898Y299102D01*
X863023Y298811D01*
X862940Y298519D01*
X862731Y298311D01*
X862481Y298227D01*
X862065D01*
X861690Y298102D01*
X861440Y297852D01*
X861356Y297561D01*
X861440Y297269D01*
X861648Y297061D01*
X861981Y296936D01*
X862273Y296894D01*
G01X850990Y302986D02*
X850740Y303111D01*
X850448Y303194D01*
X850115D01*
X849740Y303069D01*
X849448Y302861D01*
X849240Y302611D01*
X849073Y302194D01*
X849031Y301819D01*
X849115Y301444D01*
X849240Y301194D01*
X849490Y300944D01*
X849781Y300777D01*
X850073Y300694D01*
X850365D01*
X850656Y300777D01*
X850906Y300902D01*
X851115Y301069D01*
G01X853673Y300694D02*
Y303194D01*
X852131Y301402D01*
X854215D01*
G01X855356Y300694D02*
Y303194D01*
X856190D01*
X856523Y303069D01*
X856773Y302902D01*
X856981Y302652D01*
X857148Y302361D01*
X857190Y301944D01*
X857148Y301527D01*
X856981Y301236D01*
X856773Y300986D01*
X856523Y300819D01*
X856190Y300694D01*
X855356D01*
G01X858456Y301194D02*
X858706Y300902D01*
X859040Y300736D01*
X859415Y300694D01*
X859748Y300736D01*
X860081Y300944D01*
X860290Y301194D01*
X860331Y301444D01*
X860248Y301736D01*
X859956Y301944D01*
X859665Y302027D01*
X859290D01*
G01X859665D02*
X859915Y302152D01*
X860123Y302361D01*
X860206Y302611D01*
X860123Y302861D01*
X859915Y303069D01*
X859540Y303194D01*
X859165Y303152D01*
X858790Y302986D01*
G01X862473Y303194D02*
X862140Y303111D01*
X861890Y302902D01*
X861723Y302652D01*
X861598Y302319D01*
X861556Y301944D01*
X861598Y301569D01*
X861723Y301236D01*
X861890Y300986D01*
X862140Y300777D01*
X862473Y300694D01*
X862806Y300777D01*
X863056Y300986D01*
X863223Y301236D01*
X863348Y301569D01*
X863390Y301944D01*
X863348Y302319D01*
X863223Y302652D01*
X863056Y302902D01*
X862806Y303111D01*
X862473Y303194D01*
G01X851180Y329081D02*
X850930Y329206D01*
X850638Y329289D01*
X850305D01*
X849930Y329164D01*
X849638Y328956D01*
X849430Y328706D01*
X849263Y328289D01*
X849221Y327914D01*
X849305Y327539D01*
X849430Y327289D01*
X849680Y327039D01*
X849971Y326872D01*
X850263Y326789D01*
X850555D01*
X850846Y326872D01*
X851096Y326997D01*
X851305Y327164D01*
G01X853863Y326789D02*
Y329289D01*
X852321Y327497D01*
X854405D01*
G01X855546Y326789D02*
Y329289D01*
X856380D01*
X856713Y329164D01*
X856963Y328997D01*
X857171Y328747D01*
X857338Y328456D01*
X857380Y328039D01*
X857338Y327622D01*
X857171Y327331D01*
X856963Y327081D01*
X856713Y326914D01*
X856380Y326789D01*
X855546D01*
G01X858855Y327081D02*
X859146Y326872D01*
X859480Y326789D01*
X859813Y326872D01*
X860105Y327122D01*
X860313Y327497D01*
X860396Y327872D01*
Y328331D01*
X860313Y328706D01*
X860105Y329039D01*
X859855Y329206D01*
X859563Y329289D01*
X859230Y329206D01*
X858980Y329039D01*
X858813Y328789D01*
X858730Y328456D01*
X858813Y328164D01*
X859021Y327872D01*
X859271Y327706D01*
X859563Y327664D01*
X859896Y327747D01*
X860146Y327956D01*
X860396Y328331D01*
G01X851180Y332473D02*
X850930Y332598D01*
X850638Y332681D01*
X850305D01*
X849930Y332556D01*
X849638Y332348D01*
X849430Y332098D01*
X849263Y331681D01*
X849221Y331306D01*
X849305Y330931D01*
X849430Y330681D01*
X849680Y330431D01*
X849971Y330264D01*
X850263Y330181D01*
X850555D01*
X850846Y330264D01*
X851096Y330389D01*
X851305Y330556D01*
G01X853863Y330181D02*
Y332681D01*
X852321Y330889D01*
X854405D01*
G01X855546Y330181D02*
Y332681D01*
X856380D01*
X856713Y332556D01*
X856963Y332389D01*
X857171Y332139D01*
X857338Y331848D01*
X857380Y331431D01*
X857338Y331014D01*
X857171Y330723D01*
X856963Y330473D01*
X856713Y330306D01*
X856380Y330181D01*
X855546D01*
G01X859563D02*
Y332681D01*
X859063Y332181D01*
G01Y330181D02*
X860063D01*
G01X862663Y332681D02*
X862330Y332598D01*
X862080Y332389D01*
X861913Y332139D01*
X861788Y331806D01*
X861746Y331431D01*
X861788Y331056D01*
X861913Y330723D01*
X862080Y330473D01*
X862330Y330264D01*
X862663Y330181D01*
X862996Y330264D01*
X863246Y330473D01*
X863413Y330723D01*
X863538Y331056D01*
X863580Y331431D01*
X863538Y331806D01*
X863413Y332139D01*
X863246Y332389D01*
X862996Y332598D01*
X862663Y332681D01*
G01X858675Y340563D02*
X858550Y340313D01*
X858467Y340021D01*
Y339688D01*
X858592Y339313D01*
X858800Y339021D01*
X859050Y338813D01*
X859467Y338646D01*
X859842Y338604D01*
X860217Y338688D01*
X860467Y338813D01*
X860717Y339063D01*
X860884Y339354D01*
X860967Y339646D01*
Y339938D01*
X860884Y340229D01*
X860759Y340479D01*
X860592Y340688D01*
G01X858467Y342746D02*
X860967D01*
G01X858467Y341788D02*
Y343704D01*
G01X860467Y344929D02*
X860759Y345179D01*
X860925Y345513D01*
X860967Y345888D01*
X860925Y346221D01*
X860717Y346554D01*
X860467Y346763D01*
X860217Y346804D01*
X859925Y346721D01*
X859717Y346429D01*
X859634Y346138D01*
Y345763D01*
G01Y346138D02*
X859509Y346388D01*
X859300Y346596D01*
X859050Y346679D01*
X858800Y346596D01*
X858592Y346388D01*
X858467Y346013D01*
X858509Y345638D01*
X858675Y345263D01*
G01X859925Y348154D02*
X859634Y348446D01*
X859467Y348696D01*
X859384Y349029D01*
X859467Y349321D01*
X859634Y349529D01*
X859884Y349696D01*
X860175Y349738D01*
X860425Y349696D01*
X860675Y349529D01*
X860884Y349279D01*
X860967Y348988D01*
X860884Y348654D01*
X860634Y348363D01*
X860259Y348196D01*
X859842Y348154D01*
X859300Y348238D01*
X859009Y348363D01*
X858717Y348571D01*
X858509Y348863D01*
X858467Y349154D01*
X858550Y349446D01*
X858759Y349654D01*
G01X869963Y286745D02*
X869713Y286870D01*
X869421Y286953D01*
X869088D01*
X868713Y286828D01*
X868421Y286620D01*
X868213Y286370D01*
X868046Y285953D01*
X868004Y285578D01*
X868088Y285203D01*
X868213Y284953D01*
X868463Y284703D01*
X868754Y284536D01*
X869046Y284453D01*
X869338D01*
X869629Y284536D01*
X869879Y284661D01*
X870088Y284828D01*
G01X872646Y284453D02*
Y286953D01*
X871104Y285161D01*
X873188D01*
G01X874329Y284453D02*
Y286953D01*
X875163D01*
X875496Y286828D01*
X875746Y286661D01*
X875954Y286411D01*
X876121Y286120D01*
X876163Y285703D01*
X876121Y285286D01*
X875954Y284995D01*
X875746Y284745D01*
X875496Y284578D01*
X875163Y284453D01*
X874329D01*
G01X878346D02*
Y286953D01*
X877846Y286453D01*
G01Y284453D02*
X878846D01*
G01X880529Y284953D02*
X880779Y284661D01*
X881113Y284495D01*
X881488Y284453D01*
X881821Y284495D01*
X882154Y284703D01*
X882363Y284953D01*
X882404Y285203D01*
X882321Y285495D01*
X882029Y285703D01*
X881738Y285786D01*
X881363D01*
G01X881738D02*
X881988Y285911D01*
X882196Y286120D01*
X882279Y286370D01*
X882196Y286620D01*
X881988Y286828D01*
X881613Y286953D01*
X881238Y286911D01*
X880863Y286745D01*
G01X869517Y322758D02*
X869267Y322883D01*
X868975Y322966D01*
X868642D01*
X868267Y322841D01*
X867975Y322633D01*
X867767Y322383D01*
X867600Y321966D01*
X867558Y321591D01*
X867642Y321216D01*
X867767Y320966D01*
X868017Y320716D01*
X868308Y320549D01*
X868600Y320466D01*
X868892D01*
X869183Y320549D01*
X869433Y320674D01*
X869642Y320841D01*
G01X872200Y320466D02*
Y322966D01*
X870658Y321174D01*
X872742D01*
G01X873883Y320466D02*
Y322966D01*
X874717D01*
X875050Y322841D01*
X875300Y322674D01*
X875508Y322424D01*
X875675Y322133D01*
X875717Y321716D01*
X875675Y321299D01*
X875508Y321008D01*
X875300Y320758D01*
X875050Y320591D01*
X874717Y320466D01*
X873883D01*
G01X876983Y320841D02*
X877233Y320633D01*
X877525Y320508D01*
X877900Y320466D01*
X878275Y320549D01*
X878567Y320716D01*
X878775Y321008D01*
X878817Y321341D01*
X878733Y321674D01*
X878525Y321883D01*
X878233Y322049D01*
X877942Y322091D01*
X877650Y322049D01*
X877275Y321883D01*
X877400Y322966D01*
X878525D01*
G01X888152Y316962D02*
X888027Y316712D01*
X887944Y316420D01*
Y316087D01*
X888069Y315712D01*
X888277Y315420D01*
X888527Y315212D01*
X888944Y315045D01*
X889319Y315003D01*
X889694Y315087D01*
X889944Y315212D01*
X890194Y315462D01*
X890361Y315753D01*
X890444Y316045D01*
Y316337D01*
X890361Y316628D01*
X890236Y316878D01*
X890069Y317087D01*
G01X887944Y319145D02*
X890444D01*
G01X887944Y318187D02*
Y320103D01*
G01X890444Y322745D02*
X887944D01*
X889736Y321203D01*
Y323287D01*
G01X890444Y325345D02*
X887944D01*
X888444Y324845D01*
G01X890444D02*
Y325845D01*
G01X870145Y343170D02*
X869895Y343295D01*
X869603Y343378D01*
X869270D01*
X868895Y343253D01*
X868603Y343045D01*
X868395Y342795D01*
X868228Y342378D01*
X868186Y342003D01*
X868270Y341628D01*
X868395Y341378D01*
X868645Y341128D01*
X868936Y340961D01*
X869228Y340878D01*
X869520D01*
X869811Y340961D01*
X870061Y341086D01*
X870270Y341253D01*
G01X872828Y340878D02*
Y343378D01*
X871286Y341586D01*
X873370D01*
G01X874511Y340878D02*
Y343378D01*
X875345D01*
X875678Y343253D01*
X875928Y343086D01*
X876136Y342836D01*
X876303Y342545D01*
X876345Y342128D01*
X876303Y341711D01*
X876136Y341420D01*
X875928Y341170D01*
X875678Y341003D01*
X875345Y340878D01*
X874511D01*
G01X878528D02*
Y343378D01*
X878028Y342878D01*
G01Y340878D02*
X879028D01*
G01X881628D02*
Y343378D01*
X881128Y342878D01*
G01Y340878D02*
X882128D01*
G01X888331Y280101D02*
X885831D01*
Y281142D01*
X885956Y281476D01*
X886123Y281684D01*
X886456Y281767D01*
X886789Y281684D01*
X886998Y281434D01*
X887123Y281142D01*
Y280101D01*
G01Y281142D02*
X888331Y281767D01*
G01X885831Y284034D02*
X888331D01*
G01X885831Y283076D02*
Y284992D01*
G01X886248Y286342D02*
X885998Y286592D01*
X885873Y286884D01*
X885831Y287217D01*
X885914Y287634D01*
X886123Y287926D01*
X886373Y288009D01*
X886623Y287967D01*
X886831Y287801D01*
X887248Y286967D01*
X887539Y286592D01*
X887956Y286342D01*
X888331Y286259D01*
Y288009D01*
G01X887289Y289442D02*
X886998Y289734D01*
X886831Y289984D01*
X886748Y290317D01*
X886831Y290609D01*
X886998Y290817D01*
X887248Y290984D01*
X887539Y291026D01*
X887789Y290984D01*
X888039Y290817D01*
X888248Y290567D01*
X888331Y290276D01*
X888248Y289942D01*
X887998Y289651D01*
X887623Y289484D01*
X887206Y289442D01*
X886664Y289526D01*
X886373Y289651D01*
X886081Y289859D01*
X885873Y290151D01*
X885831Y290442D01*
X885914Y290734D01*
X886123Y290942D01*
G01X886307Y314930D02*
X883807D01*
Y315971D01*
X883932Y316305D01*
X884099Y316513D01*
X884432Y316596D01*
X884765Y316513D01*
X884974Y316263D01*
X885099Y315971D01*
Y314930D01*
G01Y315971D02*
X886307Y316596D01*
G01X883807Y318863D02*
X886307D01*
G01X883807Y317905D02*
Y319821D01*
G01X884224Y321171D02*
X883974Y321421D01*
X883849Y321713D01*
X883807Y322046D01*
X883890Y322463D01*
X884099Y322755D01*
X884349Y322838D01*
X884599Y322796D01*
X884807Y322630D01*
X885224Y321796D01*
X885515Y321421D01*
X885932Y321171D01*
X886307Y321088D01*
Y322838D01*
G01Y324980D02*
X885765Y325063D01*
X885307Y325188D01*
X884890Y325355D01*
X884432Y325563D01*
X883807Y325896D01*
Y324230D01*
G01X868187Y327805D02*
Y326139D01*
X865687D01*
Y327805D01*
G01X866895Y327139D02*
Y326139D01*
G01X865687Y329155D02*
X867479D01*
X867854Y329322D01*
X868104Y329655D01*
X868187Y330072D01*
X868104Y330489D01*
X867854Y330822D01*
X867479Y330989D01*
X865687D01*
G01X868187Y333672D02*
X865687D01*
X867479Y332130D01*
Y334214D01*
G01X868187Y335355D02*
X865687D01*
Y336189D01*
X865812Y336522D01*
X865979Y336772D01*
X866229Y336980D01*
X866520Y337147D01*
X866937Y337189D01*
X867354Y337147D01*
X867645Y336980D01*
X867895Y336772D01*
X868062Y336522D01*
X868187Y336189D01*
Y335355D01*
G01Y339372D02*
X865687D01*
X866187Y338872D01*
G01X868187D02*
Y339872D01*
G01X886194Y295347D02*
Y293681D01*
X883694D01*
Y295347D01*
G01X884902Y294681D02*
Y293681D01*
G01X883694Y296697D02*
X885486D01*
X885861Y296864D01*
X886111Y297197D01*
X886194Y297614D01*
X886111Y298031D01*
X885861Y298364D01*
X885486Y298531D01*
X883694D01*
G01X886194Y301214D02*
X883694D01*
X885486Y299672D01*
Y301756D01*
G01X886194Y302897D02*
X883694D01*
Y303731D01*
X883819Y304064D01*
X883986Y304314D01*
X884236Y304522D01*
X884527Y304689D01*
X884944Y304731D01*
X885361Y304689D01*
X885652Y304522D01*
X885902Y304314D01*
X886069Y304064D01*
X886194Y303731D01*
Y302897D01*
G01X885694Y305997D02*
X885986Y306247D01*
X886152Y306581D01*
X886194Y306956D01*
X886152Y307289D01*
X885944Y307622D01*
X885694Y307831D01*
X885444Y307872D01*
X885152Y307789D01*
X884944Y307497D01*
X884861Y307206D01*
Y306831D01*
G01Y307206D02*
X884736Y307456D01*
X884527Y307664D01*
X884277Y307747D01*
X884027Y307664D01*
X883819Y307456D01*
X883694Y307081D01*
X883736Y306706D01*
X883902Y306331D01*
G01X887059Y295451D02*
X889559D01*
Y297117D01*
G01Y299884D02*
X887059D01*
X888851Y298342D01*
Y300426D01*
G01X889559Y301567D02*
X887059D01*
Y302401D01*
X887184Y302734D01*
X887351Y302984D01*
X887601Y303192D01*
X887892Y303359D01*
X888309Y303401D01*
X888726Y303359D01*
X889017Y303192D01*
X889267Y302984D01*
X889434Y302734D01*
X889559Y302401D01*
Y301567D01*
G01X887476Y304792D02*
X887226Y305042D01*
X887101Y305334D01*
X887059Y305667D01*
X887142Y306084D01*
X887351Y306376D01*
X887601Y306459D01*
X887851Y306417D01*
X888059Y306251D01*
X888476Y305417D01*
X888767Y305042D01*
X889184Y304792D01*
X889559Y304709D01*
Y306459D01*
G01X869134Y327917D02*
X871634D01*
Y329583D01*
G01Y332350D02*
X869134D01*
X870926Y330808D01*
Y332892D01*
G01X871634Y334033D02*
X869134D01*
Y334867D01*
X869259Y335200D01*
X869426Y335450D01*
X869676Y335658D01*
X869967Y335825D01*
X870384Y335867D01*
X870801Y335825D01*
X871092Y335658D01*
X871342Y335450D01*
X871509Y335200D01*
X871634Y334867D01*
Y334033D01*
G01Y338050D02*
X869134D01*
X869634Y337550D01*
G01X871634D02*
Y338550D01*
G01X892542Y372217D02*
X892417Y371967D01*
X892334Y371675D01*
Y371342D01*
X892459Y370967D01*
X892667Y370675D01*
X892917Y370467D01*
X893334Y370300D01*
X893709Y370258D01*
X894084Y370342D01*
X894334Y370467D01*
X894584Y370717D01*
X894751Y371008D01*
X894834Y371300D01*
Y371592D01*
X894751Y371883D01*
X894626Y372133D01*
X894459Y372342D01*
G01X894834Y374900D02*
X892334D01*
X894126Y373358D01*
Y375442D01*
G01X892542Y378417D02*
X892417Y378167D01*
X892334Y377875D01*
Y377542D01*
X892459Y377167D01*
X892667Y376875D01*
X892917Y376667D01*
X893334Y376500D01*
X893709Y376458D01*
X894084Y376542D01*
X894334Y376667D01*
X894584Y376917D01*
X894751Y377208D01*
X894834Y377500D01*
Y377792D01*
X894751Y378083D01*
X894626Y378333D01*
X894459Y378542D01*
G01X894834Y380600D02*
X892334D01*
X892834Y380100D01*
G01X894834D02*
Y381100D01*
G01Y383700D02*
X892334D01*
X892834Y383200D01*
G01X894834D02*
Y384200D01*
G01X897942Y344267D02*
X897817Y344017D01*
X897734Y343725D01*
Y343392D01*
X897859Y343017D01*
X898067Y342725D01*
X898317Y342517D01*
X898734Y342350D01*
X899109Y342308D01*
X899484Y342392D01*
X899734Y342517D01*
X899984Y342767D01*
X900151Y343058D01*
X900234Y343350D01*
Y343642D01*
X900151Y343933D01*
X900026Y344183D01*
X899859Y344392D01*
G01X900234Y346950D02*
X897734D01*
X899526Y345408D01*
Y347492D01*
G01X900234Y348633D02*
X897734D01*
Y349467D01*
X897859Y349800D01*
X898026Y350050D01*
X898276Y350258D01*
X898567Y350425D01*
X898984Y350467D01*
X899401Y350425D01*
X899692Y350258D01*
X899942Y350050D01*
X900109Y349800D01*
X900234Y349467D01*
Y348633D01*
G01Y353150D02*
X897734D01*
X899526Y351608D01*
Y353692D01*
G01X863567Y374113D02*
X863317Y374238D01*
X863025Y374321D01*
X862692D01*
X862317Y374196D01*
X862025Y373988D01*
X861817Y373738D01*
X861650Y373321D01*
X861608Y372946D01*
X861692Y372571D01*
X861817Y372321D01*
X862067Y372071D01*
X862358Y371904D01*
X862650Y371821D01*
X862942D01*
X863233Y371904D01*
X863483Y372029D01*
X863692Y372196D01*
G01X866250Y371821D02*
Y374321D01*
X864708Y372529D01*
X866792D01*
G01X869767Y374113D02*
X869517Y374238D01*
X869225Y374321D01*
X868892D01*
X868517Y374196D01*
X868225Y373988D01*
X868017Y373738D01*
X867850Y373321D01*
X867808Y372946D01*
X867892Y372571D01*
X868017Y372321D01*
X868267Y372071D01*
X868558Y371904D01*
X868850Y371821D01*
X869142D01*
X869433Y371904D01*
X869683Y372029D01*
X869892Y372196D01*
G01X871950Y371821D02*
Y374321D01*
X871450Y373821D01*
G01Y371821D02*
X872450D01*
G01X874342Y372113D02*
X874633Y371904D01*
X874967Y371821D01*
X875300Y371904D01*
X875592Y372154D01*
X875800Y372529D01*
X875883Y372904D01*
Y373363D01*
X875800Y373738D01*
X875592Y374071D01*
X875342Y374238D01*
X875050Y374321D01*
X874717Y374238D01*
X874467Y374071D01*
X874300Y373821D01*
X874217Y373488D01*
X874300Y373196D01*
X874508Y372904D01*
X874758Y372738D01*
X875050Y372696D01*
X875383Y372779D01*
X875633Y372988D01*
X875883Y373363D01*
G01X866477Y377320D02*
X866227Y377445D01*
X865935Y377528D01*
X865602D01*
X865227Y377403D01*
X864935Y377195D01*
X864727Y376945D01*
X864560Y376528D01*
X864518Y376153D01*
X864602Y375778D01*
X864727Y375528D01*
X864977Y375278D01*
X865268Y375111D01*
X865560Y375028D01*
X865852D01*
X866143Y375111D01*
X866393Y375236D01*
X866602Y375403D01*
G01X869160Y375028D02*
Y377528D01*
X867618Y375736D01*
X869702D01*
G01X872677Y377320D02*
X872427Y377445D01*
X872135Y377528D01*
X871802D01*
X871427Y377403D01*
X871135Y377195D01*
X870927Y376945D01*
X870760Y376528D01*
X870718Y376153D01*
X870802Y375778D01*
X870927Y375528D01*
X871177Y375278D01*
X871468Y375111D01*
X871760Y375028D01*
X872052D01*
X872343Y375111D01*
X872593Y375236D01*
X872802Y375403D01*
G01X873943D02*
X874193Y375195D01*
X874485Y375070D01*
X874860Y375028D01*
X875235Y375111D01*
X875527Y375278D01*
X875735Y375570D01*
X875777Y375903D01*
X875693Y376236D01*
X875485Y376445D01*
X875193Y376611D01*
X874902Y376653D01*
X874610Y376611D01*
X874235Y376445D01*
X874360Y377528D01*
X875485D01*
G01X858977Y381620D02*
X858727Y381745D01*
X858435Y381828D01*
X858102D01*
X857727Y381703D01*
X857435Y381495D01*
X857227Y381245D01*
X857060Y380828D01*
X857018Y380453D01*
X857102Y380078D01*
X857227Y379828D01*
X857477Y379578D01*
X857768Y379411D01*
X858060Y379328D01*
X858352D01*
X858643Y379411D01*
X858893Y379536D01*
X859102Y379703D01*
G01X861660Y379328D02*
Y381828D01*
X860118Y380036D01*
X862202D01*
G01X865177Y381620D02*
X864927Y381745D01*
X864635Y381828D01*
X864302D01*
X863927Y381703D01*
X863635Y381495D01*
X863427Y381245D01*
X863260Y380828D01*
X863218Y380453D01*
X863302Y380078D01*
X863427Y379828D01*
X863677Y379578D01*
X863968Y379411D01*
X864260Y379328D01*
X864552D01*
X864843Y379411D01*
X865093Y379536D01*
X865302Y379703D01*
G01X866568Y380370D02*
X866860Y380661D01*
X867110Y380828D01*
X867443Y380911D01*
X867735Y380828D01*
X867943Y380661D01*
X868110Y380411D01*
X868152Y380120D01*
X868110Y379870D01*
X867943Y379620D01*
X867693Y379411D01*
X867402Y379328D01*
X867068Y379411D01*
X866777Y379661D01*
X866610Y380036D01*
X866568Y380453D01*
X866652Y380995D01*
X866777Y381286D01*
X866985Y381578D01*
X867277Y381786D01*
X867568Y381828D01*
X867860Y381745D01*
X868068Y381536D01*
G01X864363Y351725D02*
X864113Y351850D01*
X863821Y351933D01*
X863488D01*
X863113Y351808D01*
X862821Y351600D01*
X862613Y351350D01*
X862446Y350933D01*
X862404Y350558D01*
X862488Y350183D01*
X862613Y349933D01*
X862863Y349683D01*
X863154Y349516D01*
X863446Y349433D01*
X863738D01*
X864029Y349516D01*
X864279Y349641D01*
X864488Y349808D01*
G01X867046Y349433D02*
Y351933D01*
X865504Y350141D01*
X867588D01*
G01X868729Y349433D02*
Y351933D01*
X869563D01*
X869896Y351808D01*
X870146Y351641D01*
X870354Y351391D01*
X870521Y351100D01*
X870563Y350683D01*
X870521Y350266D01*
X870354Y349975D01*
X870146Y349725D01*
X869896Y349558D01*
X869563Y349433D01*
X868729D01*
G01X873246D02*
Y351933D01*
X871704Y350141D01*
X873788D01*
G01X875054Y350475D02*
X875346Y350766D01*
X875596Y350933D01*
X875929Y351016D01*
X876221Y350933D01*
X876429Y350766D01*
X876596Y350516D01*
X876638Y350225D01*
X876596Y349975D01*
X876429Y349725D01*
X876179Y349516D01*
X875888Y349433D01*
X875554Y349516D01*
X875263Y349766D01*
X875096Y350141D01*
X875054Y350558D01*
X875138Y351100D01*
X875263Y351391D01*
X875471Y351683D01*
X875763Y351891D01*
X876054Y351933D01*
X876346Y351850D01*
X876554Y351641D01*
G01X853280Y372677D02*
X853155Y372427D01*
X853072Y372135D01*
Y371802D01*
X853197Y371427D01*
X853405Y371135D01*
X853655Y370927D01*
X854072Y370760D01*
X854447Y370718D01*
X854822Y370802D01*
X855072Y370927D01*
X855322Y371177D01*
X855489Y371468D01*
X855572Y371760D01*
Y372052D01*
X855489Y372343D01*
X855364Y372593D01*
X855197Y372802D01*
G01X853072Y374860D02*
X855572D01*
G01X853072Y373902D02*
Y375818D01*
G01X854530Y377168D02*
X854239Y377460D01*
X854072Y377710D01*
X853989Y378043D01*
X854072Y378335D01*
X854239Y378543D01*
X854489Y378710D01*
X854780Y378752D01*
X855030Y378710D01*
X855280Y378543D01*
X855489Y378293D01*
X855572Y378002D01*
X855489Y377668D01*
X855239Y377377D01*
X854864Y377210D01*
X854447Y377168D01*
X853905Y377252D01*
X853614Y377377D01*
X853322Y377585D01*
X853114Y377877D01*
X853072Y378168D01*
X853155Y378460D01*
X853364Y378668D01*
G01X853072Y381060D02*
X853155Y380727D01*
X853364Y380477D01*
X853614Y380310D01*
X853947Y380185D01*
X854322Y380143D01*
X854697Y380185D01*
X855030Y380310D01*
X855280Y380477D01*
X855489Y380727D01*
X855572Y381060D01*
X855489Y381393D01*
X855280Y381643D01*
X855030Y381810D01*
X854697Y381935D01*
X854322Y381977D01*
X853947Y381935D01*
X853614Y381810D01*
X853364Y381643D01*
X853155Y381393D01*
X853072Y381060D01*
G01X851596Y361154D02*
X851346Y361279D01*
X851054Y361362D01*
X850721D01*
X850346Y361237D01*
X850054Y361029D01*
X849846Y360779D01*
X849679Y360362D01*
X849637Y359987D01*
X849721Y359612D01*
X849846Y359362D01*
X850096Y359112D01*
X850387Y358945D01*
X850679Y358862D01*
X850971D01*
X851262Y358945D01*
X851512Y359070D01*
X851721Y359237D01*
G01X854279Y358862D02*
Y361362D01*
X852737Y359570D01*
X854821D01*
G01X857796Y361154D02*
X857546Y361279D01*
X857254Y361362D01*
X856921D01*
X856546Y361237D01*
X856254Y361029D01*
X856046Y360779D01*
X855879Y360362D01*
X855837Y359987D01*
X855921Y359612D01*
X856046Y359362D01*
X856296Y359112D01*
X856587Y358945D01*
X856879Y358862D01*
X857171D01*
X857462Y358945D01*
X857712Y359070D01*
X857921Y359237D01*
G01X859979Y358862D02*
Y361362D01*
X859479Y360862D01*
G01Y358862D02*
X860479D01*
G01X862996D02*
X863079Y359404D01*
X863204Y359862D01*
X863371Y360279D01*
X863579Y360737D01*
X863912Y361362D01*
X862246D01*
G01X851496Y364754D02*
X851246Y364879D01*
X850954Y364962D01*
X850621D01*
X850246Y364837D01*
X849954Y364629D01*
X849746Y364379D01*
X849579Y363962D01*
X849537Y363587D01*
X849621Y363212D01*
X849746Y362962D01*
X849996Y362712D01*
X850287Y362545D01*
X850579Y362462D01*
X850871D01*
X851162Y362545D01*
X851412Y362670D01*
X851621Y362837D01*
G01X854179Y362462D02*
Y364962D01*
X852637Y363170D01*
X854721D01*
G01X857696Y364754D02*
X857446Y364879D01*
X857154Y364962D01*
X856821D01*
X856446Y364837D01*
X856154Y364629D01*
X855946Y364379D01*
X855779Y363962D01*
X855737Y363587D01*
X855821Y363212D01*
X855946Y362962D01*
X856196Y362712D01*
X856487Y362545D01*
X856779Y362462D01*
X857071D01*
X857362Y362545D01*
X857612Y362670D01*
X857821Y362837D01*
G01X859879Y362462D02*
Y364962D01*
X859379Y364462D01*
G01Y362462D02*
X860379D01*
G01X862979D02*
X863271Y362504D01*
X863604Y362629D01*
X863812Y362837D01*
X863896Y363129D01*
X863812Y363420D01*
X863562Y363670D01*
X863187Y363795D01*
X862771D01*
X862521Y363879D01*
X862312Y364087D01*
X862229Y364379D01*
X862354Y364670D01*
X862646Y364879D01*
X862979Y364962D01*
X863312Y364879D01*
X863604Y364670D01*
X863729Y364379D01*
X863646Y364087D01*
X863437Y363879D01*
X863187Y363795D01*
X862771D01*
X862396Y363670D01*
X862146Y363420D01*
X862062Y363129D01*
X862146Y362837D01*
X862354Y362629D01*
X862687Y362504D01*
X862979Y362462D01*
G01X887667Y347358D02*
X887417Y347483D01*
X887125Y347566D01*
X886792D01*
X886417Y347441D01*
X886125Y347233D01*
X885917Y346983D01*
X885750Y346566D01*
X885708Y346191D01*
X885792Y345816D01*
X885917Y345566D01*
X886167Y345316D01*
X886458Y345149D01*
X886750Y345066D01*
X887042D01*
X887333Y345149D01*
X887583Y345274D01*
X887792Y345441D01*
G01X889850Y347566D02*
Y345066D01*
G01X888892Y347566D02*
X890808D01*
G01X892033Y345566D02*
X892283Y345274D01*
X892617Y345108D01*
X892992Y345066D01*
X893325Y345108D01*
X893658Y345316D01*
X893867Y345566D01*
X893908Y345816D01*
X893825Y346108D01*
X893533Y346316D01*
X893242Y346399D01*
X892867D01*
G01X893242D02*
X893492Y346524D01*
X893700Y346733D01*
X893783Y346983D01*
X893700Y347233D01*
X893492Y347441D01*
X893117Y347566D01*
X892742Y347524D01*
X892367Y347358D01*
G01X895133Y345441D02*
X895383Y345233D01*
X895675Y345108D01*
X896050Y345066D01*
X896425Y345149D01*
X896717Y345316D01*
X896925Y345608D01*
X896967Y345941D01*
X896883Y346274D01*
X896675Y346483D01*
X896383Y346649D01*
X896092Y346691D01*
X895800Y346649D01*
X895425Y346483D01*
X895550Y347566D01*
X896675D01*
G01X870063Y347225D02*
X869813Y347350D01*
X869521Y347433D01*
X869188D01*
X868813Y347308D01*
X868521Y347100D01*
X868313Y346850D01*
X868146Y346433D01*
X868104Y346058D01*
X868188Y345683D01*
X868313Y345433D01*
X868563Y345183D01*
X868854Y345016D01*
X869146Y344933D01*
X869438D01*
X869729Y345016D01*
X869979Y345141D01*
X870188Y345308D01*
G01X872746Y344933D02*
Y347433D01*
X871204Y345641D01*
X873288D01*
G01X874429Y344933D02*
Y347433D01*
X875263D01*
X875596Y347308D01*
X875846Y347141D01*
X876054Y346891D01*
X876221Y346600D01*
X876263Y346183D01*
X876221Y345766D01*
X876054Y345475D01*
X875846Y345225D01*
X875596Y345058D01*
X875263Y344933D01*
X874429D01*
G01X878946D02*
Y347433D01*
X877404Y345641D01*
X879488D01*
G01X881463Y344933D02*
X881546Y345475D01*
X881671Y345933D01*
X881838Y346350D01*
X882046Y346808D01*
X882379Y347433D01*
X880713D01*
G01X880567Y377258D02*
X880317Y377383D01*
X880025Y377466D01*
X879692D01*
X879317Y377341D01*
X879025Y377133D01*
X878817Y376883D01*
X878650Y376466D01*
X878608Y376091D01*
X878692Y375716D01*
X878817Y375466D01*
X879067Y375216D01*
X879358Y375049D01*
X879650Y374966D01*
X879942D01*
X880233Y375049D01*
X880483Y375174D01*
X880692Y375341D01*
G01X882750Y377466D02*
Y374966D01*
G01X881792Y377466D02*
X883708D01*
G01X884933Y375341D02*
X885183Y375133D01*
X885475Y375008D01*
X885850Y374966D01*
X886225Y375049D01*
X886517Y375216D01*
X886725Y375508D01*
X886767Y375841D01*
X886683Y376174D01*
X886475Y376383D01*
X886183Y376549D01*
X885892Y376591D01*
X885600Y376549D01*
X885225Y376383D01*
X885350Y377466D01*
X886475D01*
G01X888242Y375258D02*
X888533Y375049D01*
X888867Y374966D01*
X889200Y375049D01*
X889492Y375299D01*
X889700Y375674D01*
X889783Y376049D01*
Y376508D01*
X889700Y376883D01*
X889492Y377216D01*
X889242Y377383D01*
X888950Y377466D01*
X888617Y377383D01*
X888367Y377216D01*
X888200Y376966D01*
X888117Y376633D01*
X888200Y376341D01*
X888408Y376049D01*
X888658Y375883D01*
X888950Y375841D01*
X889283Y375924D01*
X889533Y376133D01*
X889783Y376508D01*
G01X880413Y349233D02*
Y351733D01*
X881454D01*
X881788Y351608D01*
X881996Y351441D01*
X882079Y351108D01*
X881996Y350775D01*
X881746Y350566D01*
X881454Y350441D01*
X880413D01*
G01X881454D02*
X882079Y349233D01*
G01X884346Y351733D02*
Y349233D01*
G01X883388Y351733D02*
X885304D01*
G01X886654Y351316D02*
X886904Y351566D01*
X887196Y351691D01*
X887529Y351733D01*
X887946Y351650D01*
X888238Y351441D01*
X888321Y351191D01*
X888279Y350941D01*
X888113Y350733D01*
X887279Y350316D01*
X886904Y350025D01*
X886654Y349608D01*
X886571Y349233D01*
X888321D01*
G01X891046D02*
Y351733D01*
X889504Y349941D01*
X891588D01*
G01X874861Y379078D02*
Y381578D01*
X875902D01*
X876236Y381453D01*
X876444Y381286D01*
X876527Y380953D01*
X876444Y380620D01*
X876194Y380411D01*
X875902Y380286D01*
X874861D01*
G01X875902D02*
X876527Y379078D01*
G01X878794Y381578D02*
Y379078D01*
G01X877836Y381578D02*
X879752D01*
G01X880977Y379578D02*
X881227Y379286D01*
X881561Y379120D01*
X881936Y379078D01*
X882269Y379120D01*
X882602Y379328D01*
X882811Y379578D01*
X882852Y379828D01*
X882769Y380120D01*
X882477Y380328D01*
X882186Y380411D01*
X881811D01*
G01X882186D02*
X882436Y380536D01*
X882644Y380745D01*
X882727Y380995D01*
X882644Y381245D01*
X882436Y381453D01*
X882061Y381578D01*
X881686Y381536D01*
X881311Y381370D01*
G01X884286Y379370D02*
X884577Y379161D01*
X884911Y379078D01*
X885244Y379161D01*
X885536Y379411D01*
X885744Y379786D01*
X885827Y380161D01*
Y380620D01*
X885744Y380995D01*
X885536Y381328D01*
X885286Y381495D01*
X884994Y381578D01*
X884661Y381495D01*
X884411Y381328D01*
X884244Y381078D01*
X884161Y380745D01*
X884244Y380453D01*
X884452Y380161D01*
X884702Y379995D01*
X884994Y379953D01*
X885327Y380036D01*
X885577Y380245D01*
X885827Y380620D01*
G01X868434Y356433D02*
Y354767D01*
X865934D01*
Y356433D01*
G01X867142Y355767D02*
Y354767D01*
G01X865934Y357783D02*
X867726D01*
X868101Y357950D01*
X868351Y358283D01*
X868434Y358700D01*
X868351Y359117D01*
X868101Y359450D01*
X867726Y359617D01*
X865934D01*
G01X868434Y362300D02*
X865934D01*
X867726Y360758D01*
Y362842D01*
G01X866142Y365817D02*
X866017Y365567D01*
X865934Y365275D01*
Y364942D01*
X866059Y364567D01*
X866267Y364275D01*
X866517Y364067D01*
X866934Y363900D01*
X867309Y363858D01*
X867684Y363942D01*
X867934Y364067D01*
X868184Y364317D01*
X868351Y364608D01*
X868434Y364900D01*
Y365192D01*
X868351Y365483D01*
X868226Y365733D01*
X868059Y365942D01*
G01X866351Y367208D02*
X866101Y367458D01*
X865976Y367750D01*
X865934Y368083D01*
X866017Y368500D01*
X866226Y368792D01*
X866476Y368875D01*
X866726Y368833D01*
X866934Y368667D01*
X867351Y367833D01*
X867642Y367458D01*
X868059Y367208D01*
X868434Y367125D01*
Y368875D01*
G01X870134Y354817D02*
X872634D01*
Y356483D01*
G01Y359250D02*
X870134D01*
X871926Y357708D01*
Y359792D01*
G01X870342Y362767D02*
X870217Y362517D01*
X870134Y362225D01*
Y361892D01*
X870259Y361517D01*
X870467Y361225D01*
X870717Y361017D01*
X871134Y360850D01*
X871509Y360808D01*
X871884Y360892D01*
X872134Y361017D01*
X872384Y361267D01*
X872551Y361558D01*
X872634Y361850D01*
Y362142D01*
X872551Y362433D01*
X872426Y362683D01*
X872259Y362892D01*
G01X872134Y364033D02*
X872426Y364283D01*
X872592Y364617D01*
X872634Y364992D01*
X872592Y365325D01*
X872384Y365658D01*
X872134Y365867D01*
X871884Y365908D01*
X871592Y365825D01*
X871384Y365533D01*
X871301Y365242D01*
Y364867D01*
G01Y365242D02*
X871176Y365492D01*
X870967Y365700D01*
X870717Y365783D01*
X870467Y365700D01*
X870259Y365492D01*
X870134Y365117D01*
X870176Y364742D01*
X870342Y364367D01*
G01X916215Y639859D02*
X883515D01*
Y658559D01*
X916215D01*
Y639859D01*
G01X966540Y-53800D02*
Y-56800D01*
X968540D01*
G01X971140D02*
Y-53800D01*
X970540Y-54400D01*
G01Y-56800D02*
X971740D01*
G01X977340Y-53800D02*
Y-56800D01*
X979340D01*
G01X980840Y-56200D02*
X981140Y-56550D01*
X981540Y-56750D01*
X981990Y-56800D01*
X982390Y-56750D01*
X982790Y-56500D01*
X983040Y-56200D01*
X983090Y-55900D01*
X982990Y-55550D01*
X982640Y-55300D01*
X982290Y-55200D01*
X981840D01*
G01X982290D02*
X982590Y-55050D01*
X982840Y-54800D01*
X982940Y-54500D01*
X982840Y-54200D01*
X982590Y-53950D01*
X982140Y-53800D01*
X981690Y-53850D01*
X981240Y-54050D01*
G01X988140Y-53800D02*
Y-56800D01*
X990140D01*
G01X991640Y-56350D02*
X991940Y-56600D01*
X992290Y-56750D01*
X992740Y-56800D01*
X993190Y-56700D01*
X993540Y-56500D01*
X993790Y-56150D01*
X993840Y-55750D01*
X993740Y-55350D01*
X993490Y-55100D01*
X993140Y-54900D01*
X992790Y-54850D01*
X992440Y-54900D01*
X991990Y-55100D01*
X992140Y-53800D01*
X993490D01*
G01X998940D02*
Y-56800D01*
X1000940D01*
G01X1003540D02*
Y-53800D01*
X1002940Y-54400D01*
G01Y-56800D02*
X1004140D01*
G01X1007140Y-53800D02*
X1006740Y-53900D01*
X1006440Y-54150D01*
X1006240Y-54450D01*
X1006090Y-54850D01*
X1006040Y-55300D01*
X1006090Y-55750D01*
X1006240Y-56150D01*
X1006440Y-56450D01*
X1006740Y-56700D01*
X1007140Y-56800D01*
X1007540Y-56700D01*
X1007840Y-56450D01*
X1008040Y-56150D01*
X1008190Y-55750D01*
X1008240Y-55300D01*
X1008190Y-54850D01*
X1008040Y-54450D01*
X1007840Y-54150D01*
X1007540Y-53900D01*
X1007140Y-53800D01*
G01X1013340D02*
Y-56800D01*
X1015340D01*
G01X1017940D02*
Y-53800D01*
X1017340Y-54400D01*
G01Y-56800D02*
X1018540D01*
G01X1020590Y-54300D02*
X1020890Y-54000D01*
X1021240Y-53850D01*
X1021640Y-53800D01*
X1022140Y-53900D01*
X1022490Y-54150D01*
X1022590Y-54450D01*
X1022540Y-54750D01*
X1022340Y-55000D01*
X1021340Y-55500D01*
X1020890Y-55850D01*
X1020590Y-56350D01*
X1020490Y-56800D01*
X1022590D01*
G01X1027740Y-53800D02*
Y-56800D01*
X1029740D01*
G01X1032340D02*
Y-53800D01*
X1031740Y-54400D01*
G01Y-56800D02*
X1032940D01*
G01X1036540D02*
Y-53800D01*
X1034690Y-55950D01*
X1037190D01*
G01X1038040Y-57800D02*
X1041040D01*
G01X1043140Y-56800D02*
X1043490Y-56750D01*
X1043890Y-56600D01*
X1044140Y-56350D01*
X1044240Y-56000D01*
X1044140Y-55650D01*
X1043840Y-55350D01*
X1043390Y-55200D01*
X1042890D01*
X1042590Y-55100D01*
X1042340Y-54850D01*
X1042240Y-54500D01*
X1042390Y-54150D01*
X1042740Y-53900D01*
X1043140Y-53800D01*
X1043540Y-53900D01*
X1043890Y-54150D01*
X1044040Y-54500D01*
X1043940Y-54850D01*
X1043690Y-55100D01*
X1043390Y-55200D01*
X1042890D01*
X1042440Y-55350D01*
X1042140Y-55650D01*
X1042040Y-56000D01*
X1042140Y-56350D01*
X1042390Y-56600D01*
X1042790Y-56750D01*
X1043140Y-56800D01*
G01X1045640Y-56350D02*
X1045940Y-56600D01*
X1046290Y-56750D01*
X1046740Y-56800D01*
X1047190Y-56700D01*
X1047540Y-56500D01*
X1047790Y-56150D01*
X1047840Y-55750D01*
X1047740Y-55350D01*
X1047490Y-55100D01*
X1047140Y-54900D01*
X1046790Y-54850D01*
X1046440Y-54900D01*
X1045990Y-55100D01*
X1046140Y-53800D01*
X1047490D01*
G01X1050340Y-56800D02*
X1049940Y-56750D01*
X1049590Y-56550D01*
X1049290Y-56250D01*
X1049090Y-55900D01*
X1048990Y-55500D01*
Y-55100D01*
X1049090Y-54700D01*
X1049290Y-54350D01*
X1049590Y-54050D01*
X1049940Y-53850D01*
X1050340Y-53800D01*
X1050740Y-53850D01*
X1051090Y-54050D01*
X1051390Y-54350D01*
X1051590Y-54700D01*
X1051690Y-55100D01*
Y-55500D01*
X1051590Y-55900D01*
X1051390Y-56250D01*
X1051090Y-56550D01*
X1050740Y-56750D01*
X1050340Y-56800D01*
G01X1053090D02*
Y-53800D01*
G01Y-55250D02*
X1053340Y-55000D01*
X1053590Y-54850D01*
X1053990Y-54800D01*
X1054290Y-54850D01*
X1054640Y-55050D01*
X1054790Y-55350D01*
Y-56800D01*
G01X1056040D02*
Y-54800D01*
G01Y-55350D02*
X1056190Y-55100D01*
X1056440Y-54900D01*
X1056790Y-54800D01*
X1057140Y-54900D01*
X1057390Y-55100D01*
X1057540Y-55350D01*
Y-56800D01*
G01Y-55350D02*
X1057690Y-55100D01*
X1057940Y-54900D01*
X1058290Y-54800D01*
X1058640Y-54900D01*
X1058890Y-55100D01*
X1059040Y-55400D01*
Y-56800D01*
G01X1059640Y-57800D02*
X1062640D01*
G01X1063640Y-56800D02*
Y-53800D01*
X1064640D01*
X1065040Y-53950D01*
X1065340Y-54150D01*
X1065590Y-54450D01*
X1065790Y-54800D01*
X1065840Y-55300D01*
X1065790Y-55800D01*
X1065590Y-56150D01*
X1065340Y-56450D01*
X1065040Y-56650D01*
X1064640Y-56800D01*
X1063640D01*
G01X943717Y14958D02*
X943467Y15083D01*
X943175Y15166D01*
X942842D01*
X942467Y15041D01*
X942175Y14833D01*
X941967Y14583D01*
X941800Y14166D01*
X941758Y13791D01*
X941842Y13416D01*
X941967Y13166D01*
X942217Y12916D01*
X942508Y12749D01*
X942800Y12666D01*
X943092D01*
X943383Y12749D01*
X943633Y12874D01*
X943842Y13041D01*
G01X944983D02*
X945233Y12833D01*
X945525Y12708D01*
X945900Y12666D01*
X946275Y12749D01*
X946567Y12916D01*
X946775Y13208D01*
X946817Y13541D01*
X946733Y13874D01*
X946525Y14083D01*
X946233Y14249D01*
X945942Y14291D01*
X945650Y14249D01*
X945275Y14083D01*
X945400Y15166D01*
X946525D01*
G01X949250Y13916D02*
X950083D01*
Y13166D01*
X949833Y12916D01*
X949542Y12749D01*
X949125Y12666D01*
X948708Y12749D01*
X948417Y12916D01*
X948167Y13166D01*
X948000Y13458D01*
X947917Y13791D01*
Y14083D01*
X948000Y14333D01*
X948167Y14624D01*
X948417Y14874D01*
X948667Y15041D01*
X949000Y15166D01*
X949292D01*
X949625Y15083D01*
X949875Y14916D01*
G01X951308Y14749D02*
X951558Y14999D01*
X951850Y15124D01*
X952183Y15166D01*
X952600Y15083D01*
X952892Y14874D01*
X952975Y14624D01*
X952933Y14374D01*
X952767Y14166D01*
X951933Y13749D01*
X951558Y13458D01*
X951308Y13041D01*
X951225Y12666D01*
X952975D01*
G01X955200Y15166D02*
X954867Y15083D01*
X954617Y14874D01*
X954450Y14624D01*
X954325Y14291D01*
X954283Y13916D01*
X954325Y13541D01*
X954450Y13208D01*
X954617Y12958D01*
X954867Y12749D01*
X955200Y12666D01*
X955533Y12749D01*
X955783Y12958D01*
X955950Y13208D01*
X956075Y13541D01*
X956117Y13916D01*
X956075Y14291D01*
X955950Y14624D01*
X955783Y14874D01*
X955533Y15083D01*
X955200Y15166D01*
G01X926486Y15292D02*
X926236Y15417D01*
X925944Y15500D01*
X925611D01*
X925236Y15375D01*
X924944Y15167D01*
X924736Y14917D01*
X924569Y14500D01*
X924527Y14125D01*
X924611Y13750D01*
X924736Y13500D01*
X924986Y13250D01*
X925277Y13083D01*
X925569Y13000D01*
X925861D01*
X926152Y13083D01*
X926402Y13208D01*
X926611Y13375D01*
G01X927752D02*
X928002Y13167D01*
X928294Y13042D01*
X928669Y13000D01*
X929044Y13083D01*
X929336Y13250D01*
X929544Y13542D01*
X929586Y13875D01*
X929502Y14208D01*
X929294Y14417D01*
X929002Y14583D01*
X928711Y14625D01*
X928419Y14583D01*
X928044Y14417D01*
X928169Y15500D01*
X929294D01*
G01X932019Y14250D02*
X932852D01*
Y13500D01*
X932602Y13250D01*
X932311Y13083D01*
X931894Y13000D01*
X931477Y13083D01*
X931186Y13250D01*
X930936Y13500D01*
X930769Y13792D01*
X930686Y14125D01*
Y14417D01*
X930769Y14667D01*
X930936Y14958D01*
X931186Y15208D01*
X931436Y15375D01*
X931769Y15500D01*
X932061D01*
X932394Y15417D01*
X932644Y15250D01*
G01X934869Y13000D02*
Y15500D01*
X934369Y15000D01*
G01Y13000D02*
X935369D01*
G01X937261Y13292D02*
X937552Y13083D01*
X937886Y13000D01*
X938219Y13083D01*
X938511Y13333D01*
X938719Y13708D01*
X938802Y14083D01*
Y14542D01*
X938719Y14917D01*
X938511Y15250D01*
X938261Y15417D01*
X937969Y15500D01*
X937636Y15417D01*
X937386Y15250D01*
X937219Y15000D01*
X937136Y14667D01*
X937219Y14375D01*
X937427Y14083D01*
X937677Y13917D01*
X937969Y13875D01*
X938302Y13958D01*
X938552Y14167D01*
X938802Y14542D01*
G01X954042Y47267D02*
X953917Y47017D01*
X953834Y46725D01*
Y46392D01*
X953959Y46017D01*
X954167Y45725D01*
X954417Y45517D01*
X954834Y45350D01*
X955209Y45308D01*
X955584Y45392D01*
X955834Y45517D01*
X956084Y45767D01*
X956251Y46058D01*
X956334Y46350D01*
Y46642D01*
X956251Y46933D01*
X956126Y47183D01*
X955959Y47392D01*
G01Y48533D02*
X956167Y48783D01*
X956292Y49075D01*
X956334Y49450D01*
X956251Y49825D01*
X956084Y50117D01*
X955792Y50325D01*
X955459Y50367D01*
X955126Y50283D01*
X954917Y50075D01*
X954751Y49783D01*
X954709Y49492D01*
X954751Y49200D01*
X954917Y48825D01*
X953834Y48950D01*
Y50075D01*
G01X955084Y52800D02*
Y53633D01*
X955834D01*
X956084Y53383D01*
X956251Y53092D01*
X956334Y52675D01*
X956251Y52258D01*
X956084Y51967D01*
X955834Y51717D01*
X955542Y51550D01*
X955209Y51467D01*
X954917D01*
X954667Y51550D01*
X954376Y51717D01*
X954126Y51967D01*
X953959Y52217D01*
X953834Y52550D01*
Y52842D01*
X953917Y53175D01*
X954084Y53425D01*
G01X956042Y54942D02*
X956251Y55233D01*
X956334Y55567D01*
X956251Y55900D01*
X956001Y56192D01*
X955626Y56400D01*
X955251Y56483D01*
X954792D01*
X954417Y56400D01*
X954084Y56192D01*
X953917Y55942D01*
X953834Y55650D01*
X953917Y55317D01*
X954084Y55067D01*
X954334Y54900D01*
X954667Y54817D01*
X954959Y54900D01*
X955251Y55108D01*
X955417Y55358D01*
X955459Y55650D01*
X955376Y55983D01*
X955167Y56233D01*
X954792Y56483D01*
G01X940416Y51213D02*
X940166Y51338D01*
X939874Y51421D01*
X939541D01*
X939166Y51296D01*
X938874Y51088D01*
X938666Y50838D01*
X938499Y50421D01*
X938457Y50046D01*
X938541Y49671D01*
X938666Y49421D01*
X938916Y49171D01*
X939207Y49004D01*
X939499Y48921D01*
X939791D01*
X940082Y49004D01*
X940332Y49129D01*
X940541Y49296D01*
G01X941682D02*
X941932Y49088D01*
X942224Y48963D01*
X942599Y48921D01*
X942974Y49004D01*
X943266Y49171D01*
X943474Y49463D01*
X943516Y49796D01*
X943432Y50129D01*
X943224Y50338D01*
X942932Y50504D01*
X942641Y50546D01*
X942349Y50504D01*
X941974Y50338D01*
X942099Y51421D01*
X943224D01*
G01X945949Y50171D02*
X946782D01*
Y49421D01*
X946532Y49171D01*
X946241Y49004D01*
X945824Y48921D01*
X945407Y49004D01*
X945116Y49171D01*
X944866Y49421D01*
X944699Y49713D01*
X944616Y50046D01*
Y50338D01*
X944699Y50588D01*
X944866Y50879D01*
X945116Y51129D01*
X945366Y51296D01*
X945699Y51421D01*
X945991D01*
X946324Y51338D01*
X946574Y51171D01*
G01X948799Y48921D02*
Y51421D01*
X948299Y50921D01*
G01Y48921D02*
X949299D01*
G01X951899Y51421D02*
X951566Y51338D01*
X951316Y51129D01*
X951149Y50879D01*
X951024Y50546D01*
X950982Y50171D01*
X951024Y49796D01*
X951149Y49463D01*
X951316Y49213D01*
X951566Y49004D01*
X951899Y48921D01*
X952232Y49004D01*
X952482Y49213D01*
X952649Y49463D01*
X952774Y49796D01*
X952816Y50171D01*
X952774Y50546D01*
X952649Y50879D01*
X952482Y51129D01*
X952232Y51338D01*
X951899Y51421D01*
G01X958840Y98280D02*
X958574Y98192D01*
X958309Y98045D01*
X958074Y97809D01*
X957897Y97455D01*
X957838Y97102D01*
X957867Y96778D01*
X958044Y96365D01*
X958280Y96071D01*
X958604Y95865D01*
X958869Y95776D01*
X959223D01*
X959547Y95865D01*
X959812Y96012D01*
X960018Y96218D01*
X960165Y96483D01*
X960254Y96748D01*
X960283Y97014D01*
G01X961091Y97821D02*
X961415Y97850D01*
X961709Y97968D01*
X962004Y98204D01*
X962210Y98528D01*
X962299Y98852D01*
X962240Y99206D01*
X962033Y99471D01*
X961739Y99648D01*
X961444D01*
X961120Y99559D01*
X960884Y99382D01*
X960708Y99147D01*
X960560Y98764D01*
X959883Y99618D01*
X960678Y100414D01*
G01X963636Y99836D02*
X961868Y101604D01*
X962988Y102723D01*
G01X963430Y101457D02*
X962723Y100749D01*
G01X966388Y102588D02*
X964620Y104356D01*
Y103649D01*
G01X966034Y102234D02*
X966741Y102941D01*
G01X934942Y47240D02*
X934817Y46990D01*
X934734Y46698D01*
Y46365D01*
X934859Y45990D01*
X935067Y45698D01*
X935317Y45490D01*
X935734Y45323D01*
X936109Y45281D01*
X936484Y45365D01*
X936734Y45490D01*
X936984Y45740D01*
X937151Y46031D01*
X937234Y46323D01*
Y46615D01*
X937151Y46906D01*
X937026Y47156D01*
X936859Y47365D01*
G01Y48506D02*
X937067Y48756D01*
X937192Y49048D01*
X937234Y49423D01*
X937151Y49798D01*
X936984Y50090D01*
X936692Y50298D01*
X936359Y50340D01*
X936026Y50256D01*
X935817Y50048D01*
X935651Y49756D01*
X935609Y49465D01*
X935651Y49173D01*
X935817Y48798D01*
X934734Y48923D01*
Y50048D01*
G01X935984Y52773D02*
Y53606D01*
X936734D01*
X936984Y53356D01*
X937151Y53065D01*
X937234Y52648D01*
X937151Y52231D01*
X936984Y51940D01*
X936734Y51690D01*
X936442Y51523D01*
X936109Y51440D01*
X935817D01*
X935567Y51523D01*
X935276Y51690D01*
X935026Y51940D01*
X934859Y52190D01*
X934734Y52523D01*
Y52815D01*
X934817Y53148D01*
X934984Y53398D01*
G01X937234Y56123D02*
X934734D01*
X936526Y54581D01*
Y56665D01*
G01X929462Y47403D02*
X929337Y47153D01*
X929254Y46861D01*
Y46528D01*
X929379Y46153D01*
X929587Y45861D01*
X929837Y45653D01*
X930254Y45486D01*
X930629Y45444D01*
X931004Y45528D01*
X931254Y45653D01*
X931504Y45903D01*
X931671Y46194D01*
X931754Y46486D01*
Y46778D01*
X931671Y47069D01*
X931546Y47319D01*
X931379Y47528D01*
G01Y48669D02*
X931587Y48919D01*
X931712Y49211D01*
X931754Y49586D01*
X931671Y49961D01*
X931504Y50253D01*
X931212Y50461D01*
X930879Y50503D01*
X930546Y50419D01*
X930337Y50211D01*
X930171Y49919D01*
X930129Y49628D01*
X930171Y49336D01*
X930337Y48961D01*
X929254Y49086D01*
Y50211D01*
G01X930504Y52936D02*
Y53769D01*
X931254D01*
X931504Y53519D01*
X931671Y53228D01*
X931754Y52811D01*
X931671Y52394D01*
X931504Y52103D01*
X931254Y51853D01*
X930962Y51686D01*
X930629Y51603D01*
X930337D01*
X930087Y51686D01*
X929796Y51853D01*
X929546Y52103D01*
X929379Y52353D01*
X929254Y52686D01*
Y52978D01*
X929337Y53311D01*
X929504Y53561D01*
G01X931254Y54869D02*
X931546Y55119D01*
X931712Y55453D01*
X931754Y55828D01*
X931712Y56161D01*
X931504Y56494D01*
X931254Y56703D01*
X931004Y56744D01*
X930712Y56661D01*
X930504Y56369D01*
X930421Y56078D01*
Y55703D01*
G01Y56078D02*
X930296Y56328D01*
X930087Y56536D01*
X929837Y56619D01*
X929587Y56536D01*
X929379Y56328D01*
X929254Y55953D01*
X929296Y55578D01*
X929462Y55203D01*
G01X922894Y47300D02*
X922769Y47050D01*
X922686Y46758D01*
Y46425D01*
X922811Y46050D01*
X923019Y45758D01*
X923269Y45550D01*
X923686Y45383D01*
X924061Y45341D01*
X924436Y45425D01*
X924686Y45550D01*
X924936Y45800D01*
X925103Y46091D01*
X925186Y46383D01*
Y46675D01*
X925103Y46966D01*
X924978Y47216D01*
X924811Y47425D01*
G01Y48566D02*
X925019Y48816D01*
X925144Y49108D01*
X925186Y49483D01*
X925103Y49858D01*
X924936Y50150D01*
X924644Y50358D01*
X924311Y50400D01*
X923978Y50316D01*
X923769Y50108D01*
X923603Y49816D01*
X923561Y49525D01*
X923603Y49233D01*
X923769Y48858D01*
X922686Y48983D01*
Y50108D01*
G01X923936Y52833D02*
Y53666D01*
X924686D01*
X924936Y53416D01*
X925103Y53125D01*
X925186Y52708D01*
X925103Y52291D01*
X924936Y52000D01*
X924686Y51750D01*
X924394Y51583D01*
X924061Y51500D01*
X923769D01*
X923519Y51583D01*
X923228Y51750D01*
X922978Y52000D01*
X922811Y52250D01*
X922686Y52583D01*
Y52875D01*
X922769Y53208D01*
X922936Y53458D01*
G01X923103Y54891D02*
X922853Y55141D01*
X922728Y55433D01*
X922686Y55766D01*
X922769Y56183D01*
X922978Y56475D01*
X923228Y56558D01*
X923478Y56516D01*
X923686Y56350D01*
X924103Y55516D01*
X924394Y55141D01*
X924811Y54891D01*
X925186Y54808D01*
Y56558D01*
G01X919042Y47767D02*
X918917Y47517D01*
X918834Y47225D01*
Y46892D01*
X918959Y46517D01*
X919167Y46225D01*
X919417Y46017D01*
X919834Y45850D01*
X920209Y45808D01*
X920584Y45892D01*
X920834Y46017D01*
X921084Y46267D01*
X921251Y46558D01*
X921334Y46850D01*
Y47142D01*
X921251Y47433D01*
X921126Y47683D01*
X920959Y47892D01*
G01Y49033D02*
X921167Y49283D01*
X921292Y49575D01*
X921334Y49950D01*
X921251Y50325D01*
X921084Y50617D01*
X920792Y50825D01*
X920459Y50867D01*
X920126Y50783D01*
X919917Y50575D01*
X919751Y50283D01*
X919709Y49992D01*
X919751Y49700D01*
X919917Y49325D01*
X918834Y49450D01*
Y50575D01*
G01X920084Y53300D02*
Y54133D01*
X920834D01*
X921084Y53883D01*
X921251Y53592D01*
X921334Y53175D01*
X921251Y52758D01*
X921084Y52467D01*
X920834Y52217D01*
X920542Y52050D01*
X920209Y51967D01*
X919917D01*
X919667Y52050D01*
X919376Y52217D01*
X919126Y52467D01*
X918959Y52717D01*
X918834Y53050D01*
Y53342D01*
X918917Y53675D01*
X919084Y53925D01*
G01X921334Y56150D02*
X918834D01*
X919334Y55650D01*
G01X921334D02*
Y56650D01*
G01X917997Y174353D02*
X917729Y174301D01*
X917422Y174146D01*
X917230Y173888D01*
X917154Y173526D01*
X917230Y173165D01*
X917460Y172855D01*
X917805Y172700D01*
X918189D01*
X918419Y172596D01*
X918610Y172338D01*
X918687Y171976D01*
X918572Y171615D01*
X918304Y171356D01*
X917997Y171253D01*
X917690Y171356D01*
X917422Y171615D01*
X917307Y171976D01*
X917384Y172338D01*
X917575Y172596D01*
X917805Y172700D01*
X918189D01*
X918534Y172855D01*
X918764Y173165D01*
X918840Y173526D01*
X918764Y173888D01*
X918572Y174146D01*
X918265Y174301D01*
X917997Y174353D01*
G01X915625Y173061D02*
X915357Y172700D01*
X915127Y172493D01*
X914820Y172390D01*
X914552Y172493D01*
X914360Y172700D01*
X914207Y173010D01*
X914169Y173371D01*
X914207Y173681D01*
X914360Y173991D01*
X914590Y174250D01*
X914859Y174353D01*
X915165Y174250D01*
X915434Y173940D01*
X915587Y173475D01*
X915625Y172958D01*
X915549Y172286D01*
X915434Y171925D01*
X915242Y171563D01*
X914974Y171305D01*
X914705Y171253D01*
X914437Y171356D01*
X914245Y171615D01*
G01X921311Y178056D02*
X921043Y178004D01*
X920736Y177849D01*
X920544Y177591D01*
X920468Y177229D01*
X920544Y176868D01*
X920774Y176558D01*
X921119Y176403D01*
X921503D01*
X921733Y176299D01*
X921924Y176041D01*
X922001Y175679D01*
X921886Y175318D01*
X921618Y175059D01*
X921311Y174956D01*
X921004Y175059D01*
X920736Y175318D01*
X920621Y175679D01*
X920698Y176041D01*
X920889Y176299D01*
X921119Y176403D01*
X921503D01*
X921848Y176558D01*
X922078Y176868D01*
X922154Y177229D01*
X922078Y177591D01*
X921886Y177849D01*
X921579Y178004D01*
X921311Y178056D01*
G01X919054Y177591D02*
X918824Y177849D01*
X918556Y178004D01*
X918211Y178056D01*
X917866Y177953D01*
X917598Y177746D01*
X917406Y177384D01*
X917368Y176971D01*
X917444Y176558D01*
X917636Y176299D01*
X917904Y176093D01*
X918173Y176041D01*
X918441Y176093D01*
X918786Y176299D01*
X918671Y174956D01*
X917636D01*
G01X924756Y174353D02*
X924488Y174301D01*
X924181Y174146D01*
X923989Y173888D01*
X923913Y173526D01*
X923989Y173165D01*
X924219Y172855D01*
X924564Y172700D01*
X924948D01*
X925178Y172596D01*
X925369Y172338D01*
X925446Y171976D01*
X925331Y171615D01*
X925063Y171356D01*
X924756Y171253D01*
X924449Y171356D01*
X924181Y171615D01*
X924066Y171976D01*
X924143Y172338D01*
X924334Y172596D01*
X924564Y172700D01*
X924948D01*
X925293Y172855D01*
X925523Y173165D01*
X925599Y173526D01*
X925523Y173888D01*
X925331Y174146D01*
X925024Y174301D01*
X924756Y174353D01*
G01X921196D02*
Y171253D01*
X922614Y173475D01*
X920698D01*
G01X928071Y178056D02*
X927803Y178004D01*
X927496Y177849D01*
X927304Y177591D01*
X927228Y177229D01*
X927304Y176868D01*
X927534Y176558D01*
X927879Y176403D01*
X928263D01*
X928493Y176299D01*
X928684Y176041D01*
X928761Y175679D01*
X928646Y175318D01*
X928378Y175059D01*
X928071Y174956D01*
X927764Y175059D01*
X927496Y175318D01*
X927381Y175679D01*
X927458Y176041D01*
X927649Y176299D01*
X927879Y176403D01*
X928263D01*
X928608Y176558D01*
X928838Y176868D01*
X928914Y177229D01*
X928838Y177591D01*
X928646Y177849D01*
X928339Y178004D01*
X928071Y178056D01*
G01X925814Y177436D02*
X925584Y177798D01*
X925278Y178004D01*
X924933Y178056D01*
X924626Y178004D01*
X924319Y177746D01*
X924128Y177436D01*
X924089Y177126D01*
X924166Y176764D01*
X924434Y176506D01*
X924703Y176403D01*
X925048D01*
G01X924703D02*
X924473Y176248D01*
X924281Y175989D01*
X924204Y175679D01*
X924281Y175369D01*
X924473Y175111D01*
X924818Y174956D01*
X925163Y175008D01*
X925508Y175214D01*
G01X931516Y174353D02*
X931248Y174301D01*
X930941Y174146D01*
X930749Y173888D01*
X930673Y173526D01*
X930749Y173165D01*
X930979Y172855D01*
X931324Y172700D01*
X931708D01*
X931938Y172596D01*
X932129Y172338D01*
X932206Y171976D01*
X932091Y171615D01*
X931823Y171356D01*
X931516Y171253D01*
X931209Y171356D01*
X930941Y171615D01*
X930826Y171976D01*
X930903Y172338D01*
X931094Y172596D01*
X931324Y172700D01*
X931708D01*
X932053Y172855D01*
X932283Y173165D01*
X932359Y173526D01*
X932283Y173888D01*
X932091Y174146D01*
X931784Y174301D01*
X931516Y174353D01*
G01X929144Y171770D02*
X928914Y171460D01*
X928646Y171305D01*
X928339Y171253D01*
X927956Y171356D01*
X927688Y171615D01*
X927611Y171925D01*
X927649Y172235D01*
X927803Y172493D01*
X928569Y173010D01*
X928914Y173371D01*
X929144Y173888D01*
X929221Y174353D01*
X927611D01*
G01X934831Y178056D02*
X934563Y178004D01*
X934256Y177849D01*
X934064Y177591D01*
X933988Y177229D01*
X934064Y176868D01*
X934294Y176558D01*
X934639Y176403D01*
X935023D01*
X935253Y176299D01*
X935444Y176041D01*
X935521Y175679D01*
X935406Y175318D01*
X935138Y175059D01*
X934831Y174956D01*
X934524Y175059D01*
X934256Y175318D01*
X934141Y175679D01*
X934218Y176041D01*
X934409Y176299D01*
X934639Y176403D01*
X935023D01*
X935368Y176558D01*
X935598Y176868D01*
X935674Y177229D01*
X935598Y177591D01*
X935406Y177849D01*
X935099Y178004D01*
X934831Y178056D01*
G01X931731D02*
Y174956D01*
X932191Y175576D01*
G01Y178056D02*
X931271D01*
G01X938276Y174353D02*
X938008Y174301D01*
X937701Y174146D01*
X937509Y173888D01*
X937433Y173526D01*
X937509Y173165D01*
X937739Y172855D01*
X938084Y172700D01*
X938468D01*
X938698Y172596D01*
X938889Y172338D01*
X938966Y171976D01*
X938851Y171615D01*
X938583Y171356D01*
X938276Y171253D01*
X937969Y171356D01*
X937701Y171615D01*
X937586Y171976D01*
X937663Y172338D01*
X937854Y172596D01*
X938084Y172700D01*
X938468D01*
X938813Y172855D01*
X939043Y173165D01*
X939119Y173526D01*
X939043Y173888D01*
X938851Y174146D01*
X938544Y174301D01*
X938276Y174353D01*
G01X935176Y171253D02*
X935483Y171356D01*
X935713Y171615D01*
X935866Y171925D01*
X935981Y172338D01*
X936019Y172803D01*
X935981Y173268D01*
X935866Y173681D01*
X935713Y173991D01*
X935483Y174250D01*
X935176Y174353D01*
X934869Y174250D01*
X934639Y173991D01*
X934486Y173681D01*
X934371Y173268D01*
X934333Y172803D01*
X934371Y172338D01*
X934486Y171925D01*
X934639Y171615D01*
X934869Y171356D01*
X935176Y171253D01*
G01X941668Y178056D02*
X941591Y177384D01*
X941476Y176816D01*
X941323Y176299D01*
X941131Y175731D01*
X940824Y174956D01*
X942358D01*
G01X939143Y177694D02*
X938874Y177953D01*
X938568Y178056D01*
X938261Y177953D01*
X937993Y177643D01*
X937801Y177178D01*
X937724Y176713D01*
Y176144D01*
X937801Y175679D01*
X937993Y175266D01*
X938223Y175059D01*
X938491Y174956D01*
X938798Y175059D01*
X939028Y175266D01*
X939181Y175576D01*
X939258Y175989D01*
X939181Y176351D01*
X938989Y176713D01*
X938759Y176919D01*
X938491Y176971D01*
X938184Y176868D01*
X937954Y176609D01*
X937724Y176144D01*
G01X945113Y174353D02*
X945036Y173681D01*
X944921Y173113D01*
X944768Y172596D01*
X944576Y172028D01*
X944269Y171253D01*
X945803D01*
G01X941936Y174353D02*
X941668Y174301D01*
X941361Y174146D01*
X941169Y173888D01*
X941093Y173526D01*
X941169Y173165D01*
X941399Y172855D01*
X941744Y172700D01*
X942128D01*
X942358Y172596D01*
X942549Y172338D01*
X942626Y171976D01*
X942511Y171615D01*
X942243Y171356D01*
X941936Y171253D01*
X941629Y171356D01*
X941361Y171615D01*
X941246Y171976D01*
X941323Y172338D01*
X941514Y172596D01*
X941744Y172700D01*
X942128D01*
X942473Y172855D01*
X942703Y173165D01*
X942779Y173526D01*
X942703Y173888D01*
X942511Y174146D01*
X942204Y174301D01*
X941936Y174353D01*
G01X948427Y178056D02*
X948350Y177384D01*
X948235Y176816D01*
X948082Y176299D01*
X947890Y175731D01*
X947583Y174956D01*
X949117D01*
G01X945327Y178056D02*
X945250Y177384D01*
X945135Y176816D01*
X944982Y176299D01*
X944790Y175731D01*
X944483Y174956D01*
X946017D01*
G01X951873Y174353D02*
X951796Y173681D01*
X951681Y173113D01*
X951528Y172596D01*
X951336Y172028D01*
X951029Y171253D01*
X952563D01*
G01X949424Y173061D02*
X949156Y172700D01*
X948926Y172493D01*
X948619Y172390D01*
X948351Y172493D01*
X948159Y172700D01*
X948006Y173010D01*
X947968Y173371D01*
X948006Y173681D01*
X948159Y173991D01*
X948389Y174250D01*
X948658Y174353D01*
X948964Y174250D01*
X949233Y173940D01*
X949386Y173475D01*
X949424Y172958D01*
X949348Y172286D01*
X949233Y171925D01*
X949041Y171563D01*
X948773Y171305D01*
X948504Y171253D01*
X948236Y171356D01*
X948044Y171615D01*
G01X955361Y180003D02*
X955284Y179331D01*
X955169Y178763D01*
X955016Y178246D01*
X954824Y177678D01*
X954517Y176903D01*
X956051D01*
G01X953027Y179538D02*
X952797Y179796D01*
X952529Y179951D01*
X952184Y180003D01*
X951839Y179900D01*
X951571Y179693D01*
X951379Y179331D01*
X951341Y178918D01*
X951417Y178505D01*
X951609Y178246D01*
X951877Y178040D01*
X952146Y177988D01*
X952414Y178040D01*
X952759Y178246D01*
X952644Y176903D01*
X951609D01*
G01X958633Y175853D02*
X958556Y175181D01*
X958441Y174613D01*
X958288Y174096D01*
X958096Y173528D01*
X957789Y172753D01*
X959323D01*
G01X954996Y175853D02*
Y172753D01*
X956414Y174975D01*
X954498D01*
G01X962121Y180003D02*
X962044Y179331D01*
X961929Y178763D01*
X961776Y178246D01*
X961584Y177678D01*
X961277Y176903D01*
X962811D01*
G01X959787Y179383D02*
X959557Y179745D01*
X959251Y179951D01*
X958906Y180003D01*
X958599Y179951D01*
X958292Y179693D01*
X958101Y179383D01*
X958062Y179073D01*
X958139Y178711D01*
X958407Y178453D01*
X958676Y178350D01*
X959021D01*
G01X958676D02*
X958446Y178195D01*
X958254Y177936D01*
X958177Y177626D01*
X958254Y177316D01*
X958446Y177058D01*
X958791Y176903D01*
X959136Y176955D01*
X959481Y177161D01*
G01X965392Y175853D02*
X965315Y175181D01*
X965200Y174613D01*
X965047Y174096D01*
X964855Y173528D01*
X964548Y172753D01*
X966082D01*
G01X962943Y173270D02*
X962713Y172960D01*
X962445Y172805D01*
X962138Y172753D01*
X961755Y172856D01*
X961487Y173115D01*
X961410Y173425D01*
X961448Y173735D01*
X961602Y173993D01*
X962368Y174510D01*
X962713Y174871D01*
X962943Y175388D01*
X963020Y175853D01*
X961410D01*
G01X968881Y180003D02*
X968804Y179331D01*
X968689Y178763D01*
X968536Y178246D01*
X968344Y177678D01*
X968037Y176903D01*
X969571D01*
G01X965704Y180003D02*
Y176903D01*
X966164Y177523D01*
G01Y180003D02*
X965244D01*
G01X972152Y175853D02*
X972075Y175181D01*
X971960Y174613D01*
X971807Y174096D01*
X971615Y173528D01*
X971308Y172753D01*
X972842D01*
G01X968975D02*
X969282Y172856D01*
X969512Y173115D01*
X969665Y173425D01*
X969780Y173838D01*
X969818Y174303D01*
X969780Y174768D01*
X969665Y175181D01*
X969512Y175491D01*
X969282Y175750D01*
X968975Y175853D01*
X968668Y175750D01*
X968438Y175491D01*
X968285Y175181D01*
X968170Y174768D01*
X968132Y174303D01*
X968170Y173838D01*
X968285Y173425D01*
X968438Y173115D01*
X968668Y172856D01*
X968975Y172753D01*
G01X976292Y178711D02*
X976024Y178350D01*
X975794Y178143D01*
X975487Y178040D01*
X975219Y178143D01*
X975027Y178350D01*
X974874Y178660D01*
X974836Y179021D01*
X974874Y179331D01*
X975027Y179641D01*
X975257Y179900D01*
X975526Y180003D01*
X975832Y179900D01*
X976101Y179590D01*
X976254Y179125D01*
X976292Y178608D01*
X976216Y177936D01*
X976101Y177575D01*
X975909Y177213D01*
X975641Y176955D01*
X975372Y176903D01*
X975104Y177006D01*
X974912Y177265D01*
G01X973116Y179641D02*
X972847Y179900D01*
X972541Y180003D01*
X972234Y179900D01*
X971966Y179590D01*
X971774Y179125D01*
X971697Y178660D01*
Y178091D01*
X971774Y177626D01*
X971966Y177213D01*
X972196Y177006D01*
X972464Y176903D01*
X972771Y177006D01*
X973001Y177213D01*
X973154Y177523D01*
X973231Y177936D01*
X973154Y178298D01*
X972962Y178660D01*
X972732Y178866D01*
X972464Y178918D01*
X972157Y178815D01*
X971927Y178556D01*
X971697Y178091D01*
G01X965971Y420886D02*
Y427886D01*
X969171D01*
X970238Y427536D01*
X971038Y426719D01*
X971305Y425786D01*
X971038Y424853D01*
X970371Y424153D01*
X969171Y423802D01*
X965971D01*
G01X967300Y440900D02*
X964101D01*
X964100Y440899D01*
Y414850D01*
X1054000D01*
G01X950233Y418200D02*
Y416408D01*
X950400Y416033D01*
X950733Y415783D01*
X951150Y415700D01*
X951567Y415783D01*
X951900Y416033D01*
X952067Y416408D01*
Y418200D01*
G01X953333Y416075D02*
X953583Y415867D01*
X953875Y415742D01*
X954250Y415700D01*
X954625Y415783D01*
X954917Y415950D01*
X955125Y416242D01*
X955167Y416575D01*
X955083Y416908D01*
X954875Y417117D01*
X954583Y417283D01*
X954292Y417325D01*
X954000Y417283D01*
X953625Y417117D01*
X953750Y418200D01*
X954875D01*
G01X956433Y415700D02*
Y418200D01*
X957267D01*
X957600Y418075D01*
X957850Y417908D01*
X958058Y417658D01*
X958225Y417367D01*
X958267Y416950D01*
X958225Y416533D01*
X958058Y416242D01*
X957850Y415992D01*
X957600Y415825D01*
X957267Y415700D01*
X956433D01*
G01X960450D02*
Y418200D01*
X959950Y417700D01*
G01Y415700D02*
X960950D01*
G01X956795Y492489D02*
X956545Y492614D01*
X956253Y492697D01*
X955920D01*
X955545Y492572D01*
X955253Y492364D01*
X955045Y492114D01*
X954878Y491697D01*
X954836Y491322D01*
X954920Y490947D01*
X955045Y490697D01*
X955295Y490447D01*
X955586Y490280D01*
X955878Y490197D01*
X956170D01*
X956461Y490280D01*
X956711Y490405D01*
X956920Y490572D01*
G01X958061D02*
X958311Y490364D01*
X958603Y490239D01*
X958978Y490197D01*
X959353Y490280D01*
X959645Y490447D01*
X959853Y490739D01*
X959895Y491072D01*
X959811Y491405D01*
X959603Y491614D01*
X959311Y491780D01*
X959020Y491822D01*
X958728Y491780D01*
X958353Y491614D01*
X958478Y492697D01*
X959603D01*
G01X962411Y491530D02*
X962578Y491655D01*
X962703Y491864D01*
X962786Y492155D01*
X962703Y492405D01*
X962536Y492572D01*
X962245Y492697D01*
X961120D01*
Y490197D01*
X962495D01*
X962786Y490364D01*
X962953Y490614D01*
X963036Y490905D01*
X962953Y491197D01*
X962703Y491447D01*
X962411Y491530D01*
X961120D01*
G01X964386Y492280D02*
X964636Y492530D01*
X964928Y492655D01*
X965261Y492697D01*
X965678Y492614D01*
X965970Y492405D01*
X966053Y492155D01*
X966011Y491905D01*
X965845Y491697D01*
X965011Y491280D01*
X964636Y490989D01*
X964386Y490572D01*
X964303Y490197D01*
X966053D01*
G01X958717Y586859D02*
X958467Y586984D01*
X958175Y587067D01*
X957842D01*
X957467Y586942D01*
X957175Y586734D01*
X956967Y586484D01*
X956800Y586067D01*
X956758Y585692D01*
X956842Y585317D01*
X956967Y585067D01*
X957217Y584817D01*
X957508Y584650D01*
X957800Y584567D01*
X958092D01*
X958383Y584650D01*
X958633Y584775D01*
X958842Y584942D01*
G01X959983D02*
X960233Y584734D01*
X960525Y584609D01*
X960900Y584567D01*
X961275Y584650D01*
X961567Y584817D01*
X961775Y585109D01*
X961817Y585442D01*
X961733Y585775D01*
X961525Y585984D01*
X961233Y586150D01*
X960942Y586192D01*
X960650Y586150D01*
X960275Y585984D01*
X960400Y587067D01*
X961525D01*
G01X962958Y584567D02*
X964000Y587067D01*
X965042Y584567D01*
G01X964667Y585442D02*
X963333D01*
G01X967100Y584567D02*
Y587067D01*
X966600Y586567D01*
G01Y584567D02*
X967600D01*
G01X970200Y587067D02*
X969867Y586984D01*
X969617Y586775D01*
X969450Y586525D01*
X969325Y586192D01*
X969283Y585817D01*
X969325Y585442D01*
X969450Y585109D01*
X969617Y584859D01*
X969867Y584650D01*
X970200Y584567D01*
X970533Y584650D01*
X970783Y584859D01*
X970950Y585109D01*
X971075Y585442D01*
X971117Y585817D01*
X971075Y586192D01*
X970950Y586525D01*
X970783Y586775D01*
X970533Y586984D01*
X970200Y587067D01*
G01X952541Y586067D02*
X952416Y585817D01*
X952333Y585525D01*
Y585192D01*
X952458Y584817D01*
X952666Y584525D01*
X952916Y584317D01*
X953333Y584150D01*
X953708Y584108D01*
X954083Y584192D01*
X954333Y584317D01*
X954583Y584567D01*
X954750Y584858D01*
X954833Y585150D01*
Y585442D01*
X954750Y585733D01*
X954625Y585983D01*
X954458Y586192D01*
G01Y587333D02*
X954666Y587583D01*
X954791Y587875D01*
X954833Y588250D01*
X954750Y588625D01*
X954583Y588917D01*
X954291Y589125D01*
X953958Y589167D01*
X953625Y589083D01*
X953416Y588875D01*
X953250Y588583D01*
X953208Y588292D01*
X953250Y588000D01*
X953416Y587625D01*
X952333Y587750D01*
Y588875D01*
G01X954833Y590308D02*
X952333Y591350D01*
X954833Y592392D01*
G01X953958Y592017D02*
Y590683D01*
G01X954458Y593533D02*
X954666Y593783D01*
X954791Y594075D01*
X954833Y594450D01*
X954750Y594825D01*
X954583Y595117D01*
X954291Y595325D01*
X953958Y595367D01*
X953625Y595283D01*
X953416Y595075D01*
X953250Y594783D01*
X953208Y594492D01*
X953250Y594200D01*
X953416Y593825D01*
X952333Y593950D01*
Y595075D01*
G01X968917Y548959D02*
X968667Y549084D01*
X968375Y549167D01*
X968042D01*
X967667Y549042D01*
X967375Y548834D01*
X967167Y548584D01*
X967000Y548167D01*
X966958Y547792D01*
X967042Y547417D01*
X967167Y547167D01*
X967417Y546917D01*
X967708Y546750D01*
X968000Y546667D01*
X968292D01*
X968583Y546750D01*
X968833Y546875D01*
X969042Y547042D01*
G01X970183D02*
X970433Y546834D01*
X970725Y546709D01*
X971100Y546667D01*
X971475Y546750D01*
X971767Y546917D01*
X971975Y547209D01*
X972017Y547542D01*
X971933Y547875D01*
X971725Y548084D01*
X971433Y548250D01*
X971142Y548292D01*
X970850Y548250D01*
X970475Y548084D01*
X970600Y549167D01*
X971725D01*
G01X973158Y546667D02*
X974200Y549167D01*
X975242Y546667D01*
G01X974867Y547542D02*
X973533D01*
G01X977300Y546667D02*
Y549167D01*
X976800Y548667D01*
G01Y546667D02*
X977800D01*
G01X980900D02*
Y549167D01*
X979358Y547375D01*
X981442D01*
G01X950117Y548658D02*
X949867Y548783D01*
X949575Y548866D01*
X949242D01*
X948867Y548741D01*
X948575Y548533D01*
X948367Y548283D01*
X948200Y547866D01*
X948158Y547491D01*
X948242Y547116D01*
X948367Y546866D01*
X948617Y546616D01*
X948908Y546449D01*
X949200Y546366D01*
X949492D01*
X949783Y546449D01*
X950033Y546574D01*
X950242Y546741D01*
G01X951383D02*
X951633Y546533D01*
X951925Y546408D01*
X952300Y546366D01*
X952675Y546449D01*
X952967Y546616D01*
X953175Y546908D01*
X953217Y547241D01*
X953133Y547574D01*
X952925Y547783D01*
X952633Y547949D01*
X952342Y547991D01*
X952050Y547949D01*
X951675Y547783D01*
X951800Y548866D01*
X952925D01*
G01X954358Y546366D02*
X955400Y548866D01*
X956442Y546366D01*
G01X956067Y547241D02*
X954733D01*
G01X958500Y546366D02*
Y548866D01*
X958000Y548366D01*
G01Y546366D02*
X959000D01*
G01X960683Y546866D02*
X960933Y546574D01*
X961267Y546408D01*
X961642Y546366D01*
X961975Y546408D01*
X962308Y546616D01*
X962517Y546866D01*
X962558Y547116D01*
X962475Y547408D01*
X962183Y547616D01*
X961892Y547699D01*
X961517D01*
G01X961892D02*
X962142Y547824D01*
X962350Y548033D01*
X962433Y548283D01*
X962350Y548533D01*
X962142Y548741D01*
X961767Y548866D01*
X961392Y548824D01*
X961017Y548658D01*
G01X941738Y552591D02*
X941488Y552716D01*
X941196Y552799D01*
X940863D01*
X940488Y552674D01*
X940196Y552466D01*
X939988Y552216D01*
X939821Y551799D01*
X939779Y551424D01*
X939863Y551049D01*
X939988Y550799D01*
X940238Y550549D01*
X940529Y550382D01*
X940821Y550299D01*
X941113D01*
X941404Y550382D01*
X941654Y550507D01*
X941863Y550674D01*
G01X943004D02*
X943254Y550466D01*
X943546Y550341D01*
X943921Y550299D01*
X944296Y550382D01*
X944588Y550549D01*
X944796Y550841D01*
X944838Y551174D01*
X944754Y551507D01*
X944546Y551716D01*
X944254Y551882D01*
X943963Y551924D01*
X943671Y551882D01*
X943296Y551716D01*
X943421Y552799D01*
X944546D01*
G01X945979Y550299D02*
X947021Y552799D01*
X948063Y550299D01*
G01X947688Y551174D02*
X946354D01*
G01X950121Y550299D02*
Y552799D01*
X949621Y552299D01*
G01Y550299D02*
X950621D01*
G01X952429Y552382D02*
X952679Y552632D01*
X952971Y552757D01*
X953304Y552799D01*
X953721Y552716D01*
X954013Y552507D01*
X954096Y552257D01*
X954054Y552007D01*
X953888Y551799D01*
X953054Y551382D01*
X952679Y551091D01*
X952429Y550674D01*
X952346Y550299D01*
X954096D01*
G01X941481Y557273D02*
X941231Y557398D01*
X940939Y557481D01*
X940606D01*
X940231Y557356D01*
X939939Y557148D01*
X939731Y556898D01*
X939564Y556481D01*
X939522Y556106D01*
X939606Y555731D01*
X939731Y555481D01*
X939981Y555231D01*
X940272Y555064D01*
X940564Y554981D01*
X940856D01*
X941147Y555064D01*
X941397Y555189D01*
X941606Y555356D01*
G01X942747D02*
X942997Y555148D01*
X943289Y555023D01*
X943664Y554981D01*
X944039Y555064D01*
X944331Y555231D01*
X944539Y555523D01*
X944581Y555856D01*
X944497Y556189D01*
X944289Y556398D01*
X943997Y556564D01*
X943706Y556606D01*
X943414Y556564D01*
X943039Y556398D01*
X943164Y557481D01*
X944289D01*
G01X945722Y554981D02*
X946764Y557481D01*
X947806Y554981D01*
G01X947431Y555856D02*
X946097D01*
G01X949864Y554981D02*
Y557481D01*
X949364Y556981D01*
G01Y554981D02*
X950364D01*
G01X952964D02*
Y557481D01*
X952464Y556981D01*
G01Y554981D02*
X953464D01*
G01X947542Y585767D02*
X947417Y585517D01*
X947334Y585225D01*
Y584892D01*
X947459Y584517D01*
X947667Y584225D01*
X947917Y584017D01*
X948334Y583850D01*
X948709Y583808D01*
X949084Y583892D01*
X949334Y584017D01*
X949584Y584267D01*
X949751Y584558D01*
X949834Y584850D01*
Y585142D01*
X949751Y585433D01*
X949626Y585683D01*
X949459Y585892D01*
G01Y587033D02*
X949667Y587283D01*
X949792Y587575D01*
X949834Y587950D01*
X949751Y588325D01*
X949584Y588617D01*
X949292Y588825D01*
X948959Y588867D01*
X948626Y588783D01*
X948417Y588575D01*
X948251Y588283D01*
X948209Y587992D01*
X948251Y587700D01*
X948417Y587325D01*
X947334Y587450D01*
Y588575D01*
G01X949834Y590008D02*
X947334Y591050D01*
X949834Y592092D01*
G01X948959Y591717D02*
Y590383D01*
G01X949834Y594650D02*
X947334D01*
X949126Y593108D01*
Y595192D01*
G01X942942Y586067D02*
X942817Y585817D01*
X942734Y585525D01*
Y585192D01*
X942859Y584817D01*
X943067Y584525D01*
X943317Y584317D01*
X943734Y584150D01*
X944109Y584108D01*
X944484Y584192D01*
X944734Y584317D01*
X944984Y584567D01*
X945151Y584858D01*
X945234Y585150D01*
Y585442D01*
X945151Y585733D01*
X945026Y585983D01*
X944859Y586192D01*
G01Y587333D02*
X945067Y587583D01*
X945192Y587875D01*
X945234Y588250D01*
X945151Y588625D01*
X944984Y588917D01*
X944692Y589125D01*
X944359Y589167D01*
X944026Y589083D01*
X943817Y588875D01*
X943651Y588583D01*
X943609Y588292D01*
X943651Y588000D01*
X943817Y587625D01*
X942734Y587750D01*
Y588875D01*
G01X945234Y590308D02*
X942734Y591350D01*
X945234Y592392D01*
G01X944359Y592017D02*
Y590683D01*
G01X944734Y593533D02*
X945026Y593783D01*
X945192Y594117D01*
X945234Y594492D01*
X945192Y594825D01*
X944984Y595158D01*
X944734Y595367D01*
X944484Y595408D01*
X944192Y595325D01*
X943984Y595033D01*
X943901Y594742D01*
Y594367D01*
G01Y594742D02*
X943776Y594992D01*
X943567Y595200D01*
X943317Y595283D01*
X943067Y595200D01*
X942859Y594992D01*
X942734Y594617D01*
X942776Y594242D01*
X942942Y593867D01*
G01X939442Y586067D02*
X939317Y585817D01*
X939234Y585525D01*
Y585192D01*
X939359Y584817D01*
X939567Y584525D01*
X939817Y584317D01*
X940234Y584150D01*
X940609Y584108D01*
X940984Y584192D01*
X941234Y584317D01*
X941484Y584567D01*
X941651Y584858D01*
X941734Y585150D01*
Y585442D01*
X941651Y585733D01*
X941526Y585983D01*
X941359Y586192D01*
G01Y587333D02*
X941567Y587583D01*
X941692Y587875D01*
X941734Y588250D01*
X941651Y588625D01*
X941484Y588917D01*
X941192Y589125D01*
X940859Y589167D01*
X940526Y589083D01*
X940317Y588875D01*
X940151Y588583D01*
X940109Y588292D01*
X940151Y588000D01*
X940317Y587625D01*
X939234Y587750D01*
Y588875D01*
G01X941734Y590308D02*
X939234Y591350D01*
X941734Y592392D01*
G01X940859Y592017D02*
Y590683D01*
G01X939651Y593658D02*
X939401Y593908D01*
X939276Y594200D01*
X939234Y594533D01*
X939317Y594950D01*
X939526Y595242D01*
X939776Y595325D01*
X940026Y595283D01*
X940234Y595117D01*
X940651Y594283D01*
X940942Y593908D01*
X941359Y593658D01*
X941734Y593575D01*
Y595325D01*
G01X935142Y586467D02*
X935017Y586217D01*
X934934Y585925D01*
Y585592D01*
X935059Y585217D01*
X935267Y584925D01*
X935517Y584717D01*
X935934Y584550D01*
X936309Y584508D01*
X936684Y584592D01*
X936934Y584717D01*
X937184Y584967D01*
X937351Y585258D01*
X937434Y585550D01*
Y585842D01*
X937351Y586133D01*
X937226Y586383D01*
X937059Y586592D01*
G01Y587733D02*
X937267Y587983D01*
X937392Y588275D01*
X937434Y588650D01*
X937351Y589025D01*
X937184Y589317D01*
X936892Y589525D01*
X936559Y589567D01*
X936226Y589483D01*
X936017Y589275D01*
X935851Y588983D01*
X935809Y588692D01*
X935851Y588400D01*
X936017Y588025D01*
X934934Y588150D01*
Y589275D01*
G01X937434Y590708D02*
X934934Y591750D01*
X937434Y592792D01*
G01X936559Y592417D02*
Y591083D01*
G01X937434Y594850D02*
X934934D01*
X935434Y594350D01*
G01X937434D02*
Y595350D01*
G01X918252Y658620D02*
X950952D01*
Y639920D01*
X918252D01*
Y658620D01*
G01X1023285Y-22650D02*
X1023362Y-21978D01*
X1023477Y-21410D01*
X1023630Y-20893D01*
X1023822Y-20325D01*
X1024129Y-19550D01*
X1022595D01*
G01X1026385Y-22650D02*
X1026462Y-21978D01*
X1026577Y-21410D01*
X1026730Y-20893D01*
X1026922Y-20325D01*
X1027229Y-19550D01*
X1025695D01*
G01X1022924Y9583D02*
X1023154Y9893D01*
X1023422Y10048D01*
X1023729Y10100D01*
X1024112Y9997D01*
X1024380Y9738D01*
X1024457Y9428D01*
X1024419Y9118D01*
X1024265Y8860D01*
X1023499Y8343D01*
X1023154Y7982D01*
X1022924Y7465D01*
X1022847Y7000D01*
X1024457D01*
G01X1026024Y9583D02*
X1026254Y9893D01*
X1026522Y10048D01*
X1026829Y10100D01*
X1027212Y9997D01*
X1027480Y9738D01*
X1027557Y9428D01*
X1027519Y9118D01*
X1027365Y8860D01*
X1026599Y8343D01*
X1026254Y7982D01*
X1026024Y7465D01*
X1025947Y7000D01*
X1027557D01*
G01X1029852D02*
Y10100D01*
X1029392Y9480D01*
G01Y7000D02*
X1030312D01*
G01X1024075Y16500D02*
X1024152Y17172D01*
X1024267Y17740D01*
X1024420Y18257D01*
X1024612Y18825D01*
X1024919Y19600D01*
X1023385D01*
G01X1027175Y16500D02*
X1027252Y17172D01*
X1027367Y17740D01*
X1027520Y18257D01*
X1027712Y18825D01*
X1028019Y19600D01*
X1026485D01*
G01X1023575Y54500D02*
X1023652Y55172D01*
X1023767Y55740D01*
X1023920Y56257D01*
X1024112Y56825D01*
X1024419Y57600D01*
X1022885D01*
G01X1026675Y54500D02*
X1026752Y55172D01*
X1026867Y55740D01*
X1027020Y56257D01*
X1027212Y56825D01*
X1027519Y57600D01*
X1025985D01*
G01X1021424Y86083D02*
X1021654Y86393D01*
X1021922Y86548D01*
X1022229Y86600D01*
X1022612Y86497D01*
X1022880Y86238D01*
X1022957Y85928D01*
X1022919Y85618D01*
X1022765Y85360D01*
X1021999Y84843D01*
X1021654Y84482D01*
X1021424Y83965D01*
X1021347Y83500D01*
X1022957D01*
G01X1024524Y86083D02*
X1024754Y86393D01*
X1025022Y86548D01*
X1025329Y86600D01*
X1025712Y86497D01*
X1025980Y86238D01*
X1026057Y85928D01*
X1026019Y85618D01*
X1025865Y85360D01*
X1025099Y84843D01*
X1024754Y84482D01*
X1024524Y83965D01*
X1024447Y83500D01*
X1026057D01*
G01X1028352D02*
Y86600D01*
X1027892Y85980D01*
G01Y83500D02*
X1028812D01*
G01X1023424Y47083D02*
X1023654Y47393D01*
X1023922Y47548D01*
X1024229Y47600D01*
X1024612Y47497D01*
X1024880Y47238D01*
X1024957Y46928D01*
X1024919Y46618D01*
X1024765Y46360D01*
X1023999Y45843D01*
X1023654Y45482D01*
X1023424Y44965D01*
X1023347Y44500D01*
X1024957D01*
G01X1026524Y47083D02*
X1026754Y47393D01*
X1027022Y47548D01*
X1027329Y47600D01*
X1027712Y47497D01*
X1027980Y47238D01*
X1028057Y46928D01*
X1028019Y46618D01*
X1027865Y46360D01*
X1027099Y45843D01*
X1026754Y45482D01*
X1026524Y44965D01*
X1026447Y44500D01*
X1028057D01*
G01X1030352D02*
Y47600D01*
X1029892Y46980D01*
G01Y44500D02*
X1030812D01*
G01X1024541Y91267D02*
X1024416Y91017D01*
X1024333Y90725D01*
Y90392D01*
X1024458Y90017D01*
X1024666Y89725D01*
X1024916Y89517D01*
X1025333Y89350D01*
X1025708Y89308D01*
X1026083Y89392D01*
X1026333Y89517D01*
X1026583Y89767D01*
X1026750Y90058D01*
X1026833Y90350D01*
Y90642D01*
X1026750Y90933D01*
X1026625Y91183D01*
X1026458Y91392D01*
G01Y92533D02*
X1026666Y92783D01*
X1026791Y93075D01*
X1026833Y93450D01*
X1026750Y93825D01*
X1026583Y94117D01*
X1026291Y94325D01*
X1025958Y94367D01*
X1025625Y94283D01*
X1025416Y94075D01*
X1025250Y93783D01*
X1025208Y93492D01*
X1025250Y93200D01*
X1025416Y92825D01*
X1024333Y92950D01*
Y94075D01*
G01X1026833Y95758D02*
X1024333D01*
Y97342D01*
G01X1025541Y96758D02*
Y95758D01*
G01X1024750Y98858D02*
X1024500Y99108D01*
X1024375Y99400D01*
X1024333Y99733D01*
X1024416Y100150D01*
X1024625Y100442D01*
X1024875Y100525D01*
X1025125Y100483D01*
X1025333Y100317D01*
X1025750Y99483D01*
X1026041Y99108D01*
X1026458Y98858D01*
X1026833Y98775D01*
Y100525D01*
G01X1029397Y122850D02*
X1032730Y129850D01*
X1036063Y122850D01*
G01X1034863Y125300D02*
X1030597D01*
G01X1044263Y129267D02*
X1043463Y129617D01*
X1042530Y129850D01*
X1041463D01*
X1040263Y129500D01*
X1039330Y128917D01*
X1038663Y128217D01*
X1038130Y127050D01*
X1037997Y126000D01*
X1038263Y124950D01*
X1038663Y124250D01*
X1039463Y123550D01*
X1040397Y123083D01*
X1041330Y122850D01*
X1042263D01*
X1043197Y123083D01*
X1043997Y123433D01*
X1044663Y123900D01*
G01X1107500Y117000D02*
X1027000D01*
Y135600D01*
X1107500D01*
Y135500D01*
G01Y149500D02*
X1099300D01*
Y171310D01*
X987630D01*
Y147000D01*
X1027000D01*
Y135600D01*
G01X1002758Y152571D02*
X1000258D01*
Y153612D01*
X1000383Y153946D01*
X1000550Y154154D01*
X1000883Y154237D01*
X1001216Y154154D01*
X1001425Y153904D01*
X1001550Y153612D01*
Y152571D01*
G01Y153612D02*
X1002758Y154237D01*
G01X1002258Y155587D02*
X1002550Y155837D01*
X1002716Y156171D01*
X1002758Y156546D01*
X1002716Y156879D01*
X1002508Y157212D01*
X1002258Y157421D01*
X1002008Y157462D01*
X1001716Y157379D01*
X1001508Y157087D01*
X1001425Y156796D01*
Y156421D01*
G01Y156796D02*
X1001300Y157046D01*
X1001091Y157254D01*
X1000841Y157337D01*
X1000591Y157254D01*
X1000383Y157046D01*
X1000258Y156671D01*
X1000300Y156296D01*
X1000466Y155921D01*
G01X1002758Y158646D02*
X1000258D01*
X1002758Y160562D01*
X1000258D01*
G01X1002758Y162704D02*
X1000258D01*
X1000758Y162204D01*
G01X1002758D02*
Y163204D01*
G01Y165721D02*
X1002216Y165804D01*
X1001758Y165929D01*
X1001341Y166096D01*
X1000883Y166304D01*
X1000258Y166637D01*
Y164971D01*
G01X1013858Y152571D02*
X1011358D01*
Y153612D01*
X1011483Y153946D01*
X1011650Y154154D01*
X1011983Y154237D01*
X1012316Y154154D01*
X1012525Y153904D01*
X1012650Y153612D01*
Y152571D01*
G01Y153612D02*
X1013858Y154237D01*
G01X1013358Y155587D02*
X1013650Y155837D01*
X1013816Y156171D01*
X1013858Y156546D01*
X1013816Y156879D01*
X1013608Y157212D01*
X1013358Y157421D01*
X1013108Y157462D01*
X1012816Y157379D01*
X1012608Y157087D01*
X1012525Y156796D01*
Y156421D01*
G01Y156796D02*
X1012400Y157046D01*
X1012191Y157254D01*
X1011941Y157337D01*
X1011691Y157254D01*
X1011483Y157046D01*
X1011358Y156671D01*
X1011400Y156296D01*
X1011566Y155921D01*
G01X1013858Y158646D02*
X1011358D01*
X1013858Y160562D01*
X1011358D01*
G01X1011775Y161912D02*
X1011525Y162162D01*
X1011400Y162454D01*
X1011358Y162787D01*
X1011441Y163204D01*
X1011650Y163496D01*
X1011900Y163579D01*
X1012150Y163537D01*
X1012358Y163371D01*
X1012775Y162537D01*
X1013066Y162162D01*
X1013483Y161912D01*
X1013858Y161829D01*
Y163579D01*
G01Y166304D02*
X1011358D01*
X1013150Y164762D01*
Y166846D01*
G01X1017558Y152571D02*
X1015058D01*
Y153612D01*
X1015183Y153946D01*
X1015350Y154154D01*
X1015683Y154237D01*
X1016016Y154154D01*
X1016225Y153904D01*
X1016350Y153612D01*
Y152571D01*
G01Y153612D02*
X1017558Y154237D01*
G01X1015475Y155712D02*
X1015225Y155962D01*
X1015100Y156254D01*
X1015058Y156587D01*
X1015141Y157004D01*
X1015350Y157296D01*
X1015600Y157379D01*
X1015850Y157337D01*
X1016058Y157171D01*
X1016475Y156337D01*
X1016766Y155962D01*
X1017183Y155712D01*
X1017558Y155629D01*
Y157379D01*
G01X1017183Y158687D02*
X1017391Y158937D01*
X1017516Y159229D01*
X1017558Y159604D01*
X1017475Y159979D01*
X1017308Y160271D01*
X1017016Y160479D01*
X1016683Y160521D01*
X1016350Y160437D01*
X1016141Y160229D01*
X1015975Y159937D01*
X1015933Y159646D01*
X1015975Y159354D01*
X1016141Y158979D01*
X1015058Y159104D01*
Y160229D01*
G01Y161454D02*
X1017558Y162037D01*
X1015058Y162704D01*
X1017558Y163371D01*
X1015058Y163954D01*
G01X1016516Y165012D02*
X1016225Y165304D01*
X1016058Y165554D01*
X1015975Y165887D01*
X1016058Y166179D01*
X1016225Y166387D01*
X1016475Y166554D01*
X1016766Y166596D01*
X1017016Y166554D01*
X1017266Y166387D01*
X1017475Y166137D01*
X1017558Y165846D01*
X1017475Y165512D01*
X1017225Y165221D01*
X1016850Y165054D01*
X1016433Y165012D01*
X1015891Y165096D01*
X1015600Y165221D01*
X1015308Y165429D01*
X1015100Y165721D01*
X1015058Y166012D01*
X1015141Y166304D01*
X1015350Y166512D01*
G01X1017558Y168904D02*
X1017516Y169196D01*
X1017391Y169529D01*
X1017183Y169737D01*
X1016891Y169821D01*
X1016600Y169737D01*
X1016350Y169487D01*
X1016225Y169112D01*
Y168696D01*
X1016141Y168446D01*
X1015933Y168237D01*
X1015641Y168154D01*
X1015350Y168279D01*
X1015141Y168571D01*
X1015058Y168904D01*
X1015141Y169237D01*
X1015350Y169529D01*
X1015641Y169654D01*
X1015933Y169571D01*
X1016141Y169362D01*
X1016225Y169112D01*
Y168696D01*
X1016350Y168321D01*
X1016600Y168071D01*
X1016891Y167987D01*
X1017183Y168071D01*
X1017391Y168279D01*
X1017516Y168612D01*
X1017558Y168904D01*
G01X1010158Y152571D02*
X1007658D01*
Y153612D01*
X1007783Y153946D01*
X1007950Y154154D01*
X1008283Y154237D01*
X1008616Y154154D01*
X1008825Y153904D01*
X1008950Y153612D01*
Y152571D01*
G01Y153612D02*
X1010158Y154237D01*
G01X1008075Y155712D02*
X1007825Y155962D01*
X1007700Y156254D01*
X1007658Y156587D01*
X1007741Y157004D01*
X1007950Y157296D01*
X1008200Y157379D01*
X1008450Y157337D01*
X1008658Y157171D01*
X1009075Y156337D01*
X1009366Y155962D01*
X1009783Y155712D01*
X1010158Y155629D01*
Y157379D01*
G01X1009783Y158687D02*
X1009991Y158937D01*
X1010116Y159229D01*
X1010158Y159604D01*
X1010075Y159979D01*
X1009908Y160271D01*
X1009616Y160479D01*
X1009283Y160521D01*
X1008950Y160437D01*
X1008741Y160229D01*
X1008575Y159937D01*
X1008533Y159646D01*
X1008575Y159354D01*
X1008741Y158979D01*
X1007658Y159104D01*
Y160229D01*
G01Y161454D02*
X1010158Y162037D01*
X1007658Y162704D01*
X1010158Y163371D01*
X1007658Y163954D01*
G01X1009116Y165012D02*
X1008825Y165304D01*
X1008658Y165554D01*
X1008575Y165887D01*
X1008658Y166179D01*
X1008825Y166387D01*
X1009075Y166554D01*
X1009366Y166596D01*
X1009616Y166554D01*
X1009866Y166387D01*
X1010075Y166137D01*
X1010158Y165846D01*
X1010075Y165512D01*
X1009825Y165221D01*
X1009450Y165054D01*
X1009033Y165012D01*
X1008491Y165096D01*
X1008200Y165221D01*
X1007908Y165429D01*
X1007700Y165721D01*
X1007658Y166012D01*
X1007741Y166304D01*
X1007950Y166512D01*
G01X1009866Y168196D02*
X1010075Y168487D01*
X1010158Y168821D01*
X1010075Y169154D01*
X1009825Y169446D01*
X1009450Y169654D01*
X1009075Y169737D01*
X1008616D01*
X1008241Y169654D01*
X1007908Y169446D01*
X1007741Y169196D01*
X1007658Y168904D01*
X1007741Y168571D01*
X1007908Y168321D01*
X1008158Y168154D01*
X1008491Y168071D01*
X1008783Y168154D01*
X1009075Y168362D01*
X1009241Y168612D01*
X1009283Y168904D01*
X1009200Y169237D01*
X1008991Y169487D01*
X1008616Y169737D01*
G01X1006458Y152571D02*
X1003958D01*
Y153612D01*
X1004083Y153946D01*
X1004250Y154154D01*
X1004583Y154237D01*
X1004916Y154154D01*
X1005125Y153904D01*
X1005250Y153612D01*
Y152571D01*
G01Y153612D02*
X1006458Y154237D01*
G01Y156421D02*
X1005916Y156504D01*
X1005458Y156629D01*
X1005041Y156796D01*
X1004583Y157004D01*
X1003958Y157337D01*
Y155671D01*
G01X1006458Y158687D02*
X1003958D01*
Y159521D01*
X1004083Y159854D01*
X1004250Y160104D01*
X1004500Y160312D01*
X1004791Y160479D01*
X1005208Y160521D01*
X1005625Y160479D01*
X1005916Y160312D01*
X1006166Y160104D01*
X1006333Y159854D01*
X1006458Y159521D01*
Y158687D01*
G01X1004375Y161912D02*
X1004125Y162162D01*
X1004000Y162454D01*
X1003958Y162787D01*
X1004041Y163204D01*
X1004250Y163496D01*
X1004500Y163579D01*
X1004750Y163537D01*
X1004958Y163371D01*
X1005375Y162537D01*
X1005666Y162162D01*
X1006083Y161912D01*
X1006458Y161829D01*
Y163579D01*
G01X999058Y152571D02*
X996558D01*
Y153612D01*
X996683Y153946D01*
X996850Y154154D01*
X997183Y154237D01*
X997516Y154154D01*
X997725Y153904D01*
X997850Y153612D01*
Y152571D01*
G01Y153612D02*
X999058Y154237D01*
G01X996975Y155712D02*
X996725Y155962D01*
X996600Y156254D01*
X996558Y156587D01*
X996641Y157004D01*
X996850Y157296D01*
X997100Y157379D01*
X997350Y157337D01*
X997558Y157171D01*
X997975Y156337D01*
X998266Y155962D01*
X998683Y155712D01*
X999058Y155629D01*
Y157379D01*
G01X996558Y159604D02*
X999058D01*
G01X996558Y158646D02*
Y160562D01*
G01X999058Y162704D02*
X996558D01*
X997058Y162204D01*
G01X999058D02*
Y163204D01*
G01X991658Y152571D02*
X989158D01*
Y153612D01*
X989283Y153946D01*
X989450Y154154D01*
X989783Y154237D01*
X990116Y154154D01*
X990325Y153904D01*
X990450Y153612D01*
Y152571D01*
G01Y153612D02*
X991658Y154237D01*
G01Y156421D02*
X991116Y156504D01*
X990658Y156629D01*
X990241Y156796D01*
X989783Y157004D01*
X989158Y157337D01*
Y155671D01*
G01X989366Y160521D02*
X989241Y160271D01*
X989158Y159979D01*
Y159646D01*
X989283Y159271D01*
X989491Y158979D01*
X989741Y158771D01*
X990158Y158604D01*
X990533Y158562D01*
X990908Y158646D01*
X991158Y158771D01*
X991408Y159021D01*
X991575Y159312D01*
X991658Y159604D01*
Y159896D01*
X991575Y160187D01*
X991450Y160437D01*
X991283Y160646D01*
G01X991658Y162704D02*
X989158D01*
X989658Y162204D01*
G01X991658D02*
Y163204D01*
G01X991283Y164887D02*
X991491Y165137D01*
X991616Y165429D01*
X991658Y165804D01*
X991575Y166179D01*
X991408Y166471D01*
X991116Y166679D01*
X990783Y166721D01*
X990450Y166637D01*
X990241Y166429D01*
X990075Y166137D01*
X990033Y165846D01*
X990075Y165554D01*
X990241Y165179D01*
X989158Y165304D01*
Y166429D01*
G01X995358Y152571D02*
X992858D01*
Y153612D01*
X992983Y153946D01*
X993150Y154154D01*
X993483Y154237D01*
X993816Y154154D01*
X994025Y153904D01*
X994150Y153612D01*
Y152571D01*
G01Y153612D02*
X995358Y154237D01*
G01Y156421D02*
X994816Y156504D01*
X994358Y156629D01*
X993941Y156796D01*
X993483Y157004D01*
X992858Y157337D01*
Y155671D01*
G01X993066Y160521D02*
X992941Y160271D01*
X992858Y159979D01*
Y159646D01*
X992983Y159271D01*
X993191Y158979D01*
X993441Y158771D01*
X993858Y158604D01*
X994233Y158562D01*
X994608Y158646D01*
X994858Y158771D01*
X995108Y159021D01*
X995275Y159312D01*
X995358Y159604D01*
Y159896D01*
X995275Y160187D01*
X995150Y160437D01*
X994983Y160646D01*
G01X995358Y162704D02*
X992858D01*
X993358Y162204D01*
G01X995358D02*
Y163204D01*
G01X994316Y165012D02*
X994025Y165304D01*
X993858Y165554D01*
X993775Y165887D01*
X993858Y166179D01*
X994025Y166387D01*
X994275Y166554D01*
X994566Y166596D01*
X994816Y166554D01*
X995066Y166387D01*
X995275Y166137D01*
X995358Y165846D01*
X995275Y165512D01*
X995025Y165221D01*
X994650Y165054D01*
X994233Y165012D01*
X993691Y165096D01*
X993400Y165221D01*
X993108Y165429D01*
X992900Y165721D01*
X992858Y166012D01*
X992941Y166304D01*
X993150Y166512D01*
G01X1028658Y152571D02*
X1026158D01*
Y153612D01*
X1026283Y153946D01*
X1026450Y154154D01*
X1026783Y154237D01*
X1027116Y154154D01*
X1027325Y153904D01*
X1027450Y153612D01*
Y152571D01*
G01Y153612D02*
X1028658Y154237D01*
G01Y156421D02*
X1028116Y156504D01*
X1027658Y156629D01*
X1027241Y156796D01*
X1026783Y157004D01*
X1026158Y157337D01*
Y155671D01*
G01X1028658Y158687D02*
X1026158D01*
Y159521D01*
X1026283Y159854D01*
X1026450Y160104D01*
X1026700Y160312D01*
X1026991Y160479D01*
X1027408Y160521D01*
X1027825Y160479D01*
X1028116Y160312D01*
X1028366Y160104D01*
X1028533Y159854D01*
X1028658Y159521D01*
Y158687D01*
G01Y162704D02*
X1028616Y162996D01*
X1028491Y163329D01*
X1028283Y163537D01*
X1027991Y163621D01*
X1027700Y163537D01*
X1027450Y163287D01*
X1027325Y162912D01*
Y162496D01*
X1027241Y162246D01*
X1027033Y162037D01*
X1026741Y161954D01*
X1026450Y162079D01*
X1026241Y162371D01*
X1026158Y162704D01*
X1026241Y163037D01*
X1026450Y163329D01*
X1026741Y163454D01*
X1027033Y163371D01*
X1027241Y163162D01*
X1027325Y162912D01*
Y162496D01*
X1027450Y162121D01*
X1027700Y161871D01*
X1027991Y161787D01*
X1028283Y161871D01*
X1028491Y162079D01*
X1028616Y162412D01*
X1028658Y162704D01*
G01X1032358Y152571D02*
X1029858D01*
Y153612D01*
X1029983Y153946D01*
X1030150Y154154D01*
X1030483Y154237D01*
X1030816Y154154D01*
X1031025Y153904D01*
X1031150Y153612D01*
Y152571D01*
G01Y153612D02*
X1032358Y154237D01*
G01Y156421D02*
X1031816Y156504D01*
X1031358Y156629D01*
X1030941Y156796D01*
X1030483Y157004D01*
X1029858Y157337D01*
Y155671D01*
G01X1032358Y158687D02*
X1029858D01*
Y159521D01*
X1029983Y159854D01*
X1030150Y160104D01*
X1030400Y160312D01*
X1030691Y160479D01*
X1031108Y160521D01*
X1031525Y160479D01*
X1031816Y160312D01*
X1032066Y160104D01*
X1032233Y159854D01*
X1032358Y159521D01*
Y158687D01*
G01X1032066Y161996D02*
X1032275Y162287D01*
X1032358Y162621D01*
X1032275Y162954D01*
X1032025Y163246D01*
X1031650Y163454D01*
X1031275Y163537D01*
X1030816D01*
X1030441Y163454D01*
X1030108Y163246D01*
X1029941Y162996D01*
X1029858Y162704D01*
X1029941Y162371D01*
X1030108Y162121D01*
X1030358Y161954D01*
X1030691Y161871D01*
X1030983Y161954D01*
X1031275Y162162D01*
X1031441Y162412D01*
X1031483Y162704D01*
X1031400Y163037D01*
X1031191Y163287D01*
X1030816Y163537D01*
G01X1024958Y152571D02*
X1022458D01*
Y153612D01*
X1022583Y153946D01*
X1022750Y154154D01*
X1023083Y154237D01*
X1023416Y154154D01*
X1023625Y153904D01*
X1023750Y153612D01*
Y152571D01*
G01Y153612D02*
X1024958Y154237D01*
G01Y156421D02*
X1024416Y156504D01*
X1023958Y156629D01*
X1023541Y156796D01*
X1023083Y157004D01*
X1022458Y157337D01*
Y155671D01*
G01X1024958Y158687D02*
X1022458D01*
Y159521D01*
X1022583Y159854D01*
X1022750Y160104D01*
X1023000Y160312D01*
X1023291Y160479D01*
X1023708Y160521D01*
X1024125Y160479D01*
X1024416Y160312D01*
X1024666Y160104D01*
X1024833Y159854D01*
X1024958Y159521D01*
Y158687D01*
G01Y162621D02*
X1024416Y162704D01*
X1023958Y162829D01*
X1023541Y162996D01*
X1023083Y163204D01*
X1022458Y163537D01*
Y161871D01*
G01X1021258Y152571D02*
X1018758D01*
Y153612D01*
X1018883Y153946D01*
X1019050Y154154D01*
X1019383Y154237D01*
X1019716Y154154D01*
X1019925Y153904D01*
X1020050Y153612D01*
Y152571D01*
G01Y153612D02*
X1021258Y154237D01*
G01X1020758Y155587D02*
X1021050Y155837D01*
X1021216Y156171D01*
X1021258Y156546D01*
X1021216Y156879D01*
X1021008Y157212D01*
X1020758Y157421D01*
X1020508Y157462D01*
X1020216Y157379D01*
X1020008Y157087D01*
X1019925Y156796D01*
Y156421D01*
G01Y156796D02*
X1019800Y157046D01*
X1019591Y157254D01*
X1019341Y157337D01*
X1019091Y157254D01*
X1018883Y157046D01*
X1018758Y156671D01*
X1018800Y156296D01*
X1018966Y155921D01*
G01X1021258Y158646D02*
X1018758D01*
X1021258Y160562D01*
X1018758D01*
G01X1019175Y161912D02*
X1018925Y162162D01*
X1018800Y162454D01*
X1018758Y162787D01*
X1018841Y163204D01*
X1019050Y163496D01*
X1019300Y163579D01*
X1019550Y163537D01*
X1019758Y163371D01*
X1020175Y162537D01*
X1020466Y162162D01*
X1020883Y161912D01*
X1021258Y161829D01*
Y163579D01*
G01X1020216Y165012D02*
X1019925Y165304D01*
X1019758Y165554D01*
X1019675Y165887D01*
X1019758Y166179D01*
X1019925Y166387D01*
X1020175Y166554D01*
X1020466Y166596D01*
X1020716Y166554D01*
X1020966Y166387D01*
X1021175Y166137D01*
X1021258Y165846D01*
X1021175Y165512D01*
X1020925Y165221D01*
X1020550Y165054D01*
X1020133Y165012D01*
X1019591Y165096D01*
X1019300Y165221D01*
X1019008Y165429D01*
X1018800Y165721D01*
X1018758Y166012D01*
X1018841Y166304D01*
X1019050Y166512D01*
G01X979563Y174561D02*
X979295Y174200D01*
X979065Y173993D01*
X978758Y173890D01*
X978490Y173993D01*
X978298Y174200D01*
X978145Y174510D01*
X978107Y174871D01*
X978145Y175181D01*
X978298Y175491D01*
X978528Y175750D01*
X978797Y175853D01*
X979103Y175750D01*
X979372Y175440D01*
X979525Y174975D01*
X979563Y174458D01*
X979487Y173786D01*
X979372Y173425D01*
X979180Y173063D01*
X978912Y172805D01*
X978643Y172753D01*
X978375Y172856D01*
X978183Y173115D01*
G01X975735Y175853D02*
X975467Y175801D01*
X975160Y175646D01*
X974968Y175388D01*
X974892Y175026D01*
X974968Y174665D01*
X975198Y174355D01*
X975543Y174200D01*
X975927D01*
X976157Y174096D01*
X976348Y173838D01*
X976425Y173476D01*
X976310Y173115D01*
X976042Y172856D01*
X975735Y172753D01*
X975428Y172856D01*
X975160Y173115D01*
X975045Y173476D01*
X975122Y173838D01*
X975313Y174096D01*
X975543Y174200D01*
X975927D01*
X976272Y174355D01*
X976502Y174665D01*
X976578Y175026D01*
X976502Y175388D01*
X976310Y175646D01*
X976003Y175801D01*
X975735Y175853D01*
G01X983052Y178711D02*
X982784Y178350D01*
X982554Y178143D01*
X982247Y178040D01*
X981979Y178143D01*
X981787Y178350D01*
X981634Y178660D01*
X981596Y179021D01*
X981634Y179331D01*
X981787Y179641D01*
X982017Y179900D01*
X982286Y180003D01*
X982592Y179900D01*
X982861Y179590D01*
X983014Y179125D01*
X983052Y178608D01*
X982976Y177936D01*
X982861Y177575D01*
X982669Y177213D01*
X982401Y176955D01*
X982132Y176903D01*
X981864Y177006D01*
X981672Y177265D01*
G01X979301Y180003D02*
X979224Y179331D01*
X979109Y178763D01*
X978956Y178246D01*
X978764Y177678D01*
X978457Y176903D01*
X979991D01*
G01X986323Y174561D02*
X986055Y174200D01*
X985825Y173993D01*
X985518Y173890D01*
X985250Y173993D01*
X985058Y174200D01*
X984905Y174510D01*
X984867Y174871D01*
X984905Y175181D01*
X985058Y175491D01*
X985288Y175750D01*
X985557Y175853D01*
X985863Y175750D01*
X986132Y175440D01*
X986285Y174975D01*
X986323Y174458D01*
X986247Y173786D01*
X986132Y173425D01*
X985940Y173063D01*
X985672Y172805D01*
X985403Y172753D01*
X985135Y172856D01*
X984943Y173115D01*
G01X983223Y174561D02*
X982955Y174200D01*
X982725Y173993D01*
X982418Y173890D01*
X982150Y173993D01*
X981958Y174200D01*
X981805Y174510D01*
X981767Y174871D01*
X981805Y175181D01*
X981958Y175491D01*
X982188Y175750D01*
X982457Y175853D01*
X982763Y175750D01*
X983032Y175440D01*
X983185Y174975D01*
X983223Y174458D01*
X983147Y173786D01*
X983032Y173425D01*
X982840Y173063D01*
X982572Y172805D01*
X982303Y172753D01*
X982035Y172856D01*
X981843Y173115D01*
G01X989812Y178711D02*
X989544Y178350D01*
X989314Y178143D01*
X989007Y178040D01*
X988739Y178143D01*
X988547Y178350D01*
X988394Y178660D01*
X988356Y179021D01*
X988394Y179331D01*
X988547Y179641D01*
X988777Y179900D01*
X989046Y180003D01*
X989352Y179900D01*
X989621Y179590D01*
X989774Y179125D01*
X989812Y178608D01*
X989736Y177936D01*
X989621Y177575D01*
X989429Y177213D01*
X989161Y176955D01*
X988892Y176903D01*
X988624Y177006D01*
X988432Y177265D01*
G01X986827Y179538D02*
X986597Y179796D01*
X986329Y179951D01*
X985984Y180003D01*
X985639Y179900D01*
X985371Y179693D01*
X985179Y179331D01*
X985141Y178918D01*
X985217Y178505D01*
X985409Y178246D01*
X985677Y178040D01*
X985946Y177988D01*
X986214Y178040D01*
X986559Y178246D01*
X986444Y176903D01*
X985409D01*
G01X993083Y174561D02*
X992815Y174200D01*
X992585Y173993D01*
X992278Y173890D01*
X992010Y173993D01*
X991818Y174200D01*
X991665Y174510D01*
X991627Y174871D01*
X991665Y175181D01*
X991818Y175491D01*
X992048Y175750D01*
X992317Y175853D01*
X992623Y175750D01*
X992892Y175440D01*
X993045Y174975D01*
X993083Y174458D01*
X993007Y173786D01*
X992892Y173425D01*
X992700Y173063D01*
X992432Y172805D01*
X992163Y172753D01*
X991895Y172856D01*
X991703Y173115D01*
G01X988795Y175853D02*
Y172753D01*
X990213Y174975D01*
X988297D01*
G01X996571Y178711D02*
X996303Y178350D01*
X996073Y178143D01*
X995766Y178040D01*
X995498Y178143D01*
X995306Y178350D01*
X995153Y178660D01*
X995115Y179021D01*
X995153Y179331D01*
X995306Y179641D01*
X995536Y179900D01*
X995805Y180003D01*
X996111Y179900D01*
X996380Y179590D01*
X996533Y179125D01*
X996571Y178608D01*
X996495Y177936D01*
X996380Y177575D01*
X996188Y177213D01*
X995920Y176955D01*
X995651Y176903D01*
X995383Y177006D01*
X995191Y177265D01*
G01X993586Y179383D02*
X993356Y179745D01*
X993050Y179951D01*
X992705Y180003D01*
X992398Y179951D01*
X992091Y179693D01*
X991900Y179383D01*
X991861Y179073D01*
X991938Y178711D01*
X992206Y178453D01*
X992475Y178350D01*
X992820D01*
G01X992475D02*
X992245Y178195D01*
X992053Y177936D01*
X991976Y177626D01*
X992053Y177316D01*
X992245Y177058D01*
X992590Y176903D01*
X992935Y176955D01*
X993280Y177161D01*
G01X999843Y174561D02*
X999575Y174200D01*
X999345Y173993D01*
X999038Y173890D01*
X998770Y173993D01*
X998578Y174200D01*
X998425Y174510D01*
X998387Y174871D01*
X998425Y175181D01*
X998578Y175491D01*
X998808Y175750D01*
X999077Y175853D01*
X999383Y175750D01*
X999652Y175440D01*
X999805Y174975D01*
X999843Y174458D01*
X999767Y173786D01*
X999652Y173425D01*
X999460Y173063D01*
X999192Y172805D01*
X998923Y172753D01*
X998655Y172856D01*
X998463Y173115D01*
G01X996743Y173270D02*
X996513Y172960D01*
X996245Y172805D01*
X995938Y172753D01*
X995555Y172856D01*
X995287Y173115D01*
X995210Y173425D01*
X995248Y173735D01*
X995402Y173993D01*
X996168Y174510D01*
X996513Y174871D01*
X996743Y175388D01*
X996820Y175853D01*
X995210D01*
G01X1003331Y178711D02*
X1003063Y178350D01*
X1002833Y178143D01*
X1002526Y178040D01*
X1002258Y178143D01*
X1002066Y178350D01*
X1001913Y178660D01*
X1001875Y179021D01*
X1001913Y179331D01*
X1002066Y179641D01*
X1002296Y179900D01*
X1002565Y180003D01*
X1002871Y179900D01*
X1003140Y179590D01*
X1003293Y179125D01*
X1003331Y178608D01*
X1003255Y177936D01*
X1003140Y177575D01*
X1002948Y177213D01*
X1002680Y176955D01*
X1002411Y176903D01*
X1002143Y177006D01*
X1001951Y177265D01*
G01X999503Y180003D02*
Y176903D01*
X999963Y177523D01*
G01Y180003D02*
X999043D01*
G01X1006602Y174561D02*
X1006334Y174200D01*
X1006104Y173993D01*
X1005797Y173890D01*
X1005529Y173993D01*
X1005337Y174200D01*
X1005184Y174510D01*
X1005146Y174871D01*
X1005184Y175181D01*
X1005337Y175491D01*
X1005567Y175750D01*
X1005836Y175853D01*
X1006142Y175750D01*
X1006411Y175440D01*
X1006564Y174975D01*
X1006602Y174458D01*
X1006526Y173786D01*
X1006411Y173425D01*
X1006219Y173063D01*
X1005951Y172805D01*
X1005682Y172753D01*
X1005414Y172856D01*
X1005222Y173115D01*
G01X1002774Y172753D02*
X1003081Y172856D01*
X1003311Y173115D01*
X1003464Y173425D01*
X1003579Y173838D01*
X1003617Y174303D01*
X1003579Y174768D01*
X1003464Y175181D01*
X1003311Y175491D01*
X1003081Y175750D01*
X1002774Y175853D01*
X1002467Y175750D01*
X1002237Y175491D01*
X1002084Y175181D01*
X1001969Y174768D01*
X1001931Y174303D01*
X1001969Y173838D01*
X1002084Y173425D01*
X1002237Y173115D01*
X1002467Y172856D01*
X1002774Y172753D01*
G01X1010206Y179538D02*
X1009976Y179796D01*
X1009708Y179951D01*
X1009363Y180003D01*
X1009018Y179900D01*
X1008750Y179693D01*
X1008558Y179331D01*
X1008520Y178918D01*
X1008596Y178505D01*
X1008788Y178246D01*
X1009056Y178040D01*
X1009325Y177988D01*
X1009593Y178040D01*
X1009938Y178246D01*
X1009823Y176903D01*
X1008788D01*
G01X1006915Y179641D02*
X1006646Y179900D01*
X1006340Y180003D01*
X1006033Y179900D01*
X1005765Y179590D01*
X1005573Y179125D01*
X1005496Y178660D01*
Y178091D01*
X1005573Y177626D01*
X1005765Y177213D01*
X1005995Y177006D01*
X1006263Y176903D01*
X1006570Y177006D01*
X1006800Y177213D01*
X1006953Y177523D01*
X1007030Y177936D01*
X1006953Y178298D01*
X1006761Y178660D01*
X1006531Y178866D01*
X1006263Y178918D01*
X1005956Y178815D01*
X1005726Y178556D01*
X1005496Y178091D01*
G01X1013477Y175388D02*
X1013247Y175646D01*
X1012979Y175801D01*
X1012634Y175853D01*
X1012289Y175750D01*
X1012021Y175543D01*
X1011829Y175181D01*
X1011791Y174768D01*
X1011867Y174355D01*
X1012059Y174096D01*
X1012327Y173890D01*
X1012596Y173838D01*
X1012864Y173890D01*
X1013209Y174096D01*
X1013094Y172753D01*
X1012059D01*
G01X1009534Y175853D02*
X1009266Y175801D01*
X1008959Y175646D01*
X1008767Y175388D01*
X1008691Y175026D01*
X1008767Y174665D01*
X1008997Y174355D01*
X1009342Y174200D01*
X1009726D01*
X1009956Y174096D01*
X1010147Y173838D01*
X1010224Y173476D01*
X1010109Y173115D01*
X1009841Y172856D01*
X1009534Y172753D01*
X1009227Y172856D01*
X1008959Y173115D01*
X1008844Y173476D01*
X1008921Y173838D01*
X1009112Y174096D01*
X1009342Y174200D01*
X1009726D01*
X1010071Y174355D01*
X1010301Y174665D01*
X1010377Y175026D01*
X1010301Y175388D01*
X1010109Y175646D01*
X1009802Y175801D01*
X1009534Y175853D01*
G01X1016966Y179538D02*
X1016736Y179796D01*
X1016468Y179951D01*
X1016123Y180003D01*
X1015778Y179900D01*
X1015510Y179693D01*
X1015318Y179331D01*
X1015280Y178918D01*
X1015356Y178505D01*
X1015548Y178246D01*
X1015816Y178040D01*
X1016085Y177988D01*
X1016353Y178040D01*
X1016698Y178246D01*
X1016583Y176903D01*
X1015548D01*
G01X1013100Y180003D02*
X1013023Y179331D01*
X1012908Y178763D01*
X1012755Y178246D01*
X1012563Y177678D01*
X1012256Y176903D01*
X1013790D01*
G01X1020237Y175388D02*
X1020007Y175646D01*
X1019739Y175801D01*
X1019394Y175853D01*
X1019049Y175750D01*
X1018781Y175543D01*
X1018589Y175181D01*
X1018551Y174768D01*
X1018627Y174355D01*
X1018819Y174096D01*
X1019087Y173890D01*
X1019356Y173838D01*
X1019624Y173890D01*
X1019969Y174096D01*
X1019854Y172753D01*
X1018819D01*
G01X1017022Y174561D02*
X1016754Y174200D01*
X1016524Y173993D01*
X1016217Y173890D01*
X1015949Y173993D01*
X1015757Y174200D01*
X1015604Y174510D01*
X1015566Y174871D01*
X1015604Y175181D01*
X1015757Y175491D01*
X1015987Y175750D01*
X1016256Y175853D01*
X1016562Y175750D01*
X1016831Y175440D01*
X1016984Y174975D01*
X1017022Y174458D01*
X1016946Y173786D01*
X1016831Y173425D01*
X1016639Y173063D01*
X1016371Y172805D01*
X1016102Y172753D01*
X1015834Y172856D01*
X1015642Y173115D01*
G01X1023726Y179538D02*
X1023496Y179796D01*
X1023228Y179951D01*
X1022883Y180003D01*
X1022538Y179900D01*
X1022270Y179693D01*
X1022078Y179331D01*
X1022040Y178918D01*
X1022116Y178505D01*
X1022308Y178246D01*
X1022576Y178040D01*
X1022845Y177988D01*
X1023113Y178040D01*
X1023458Y178246D01*
X1023343Y176903D01*
X1022308D01*
G01X1020626Y179538D02*
X1020396Y179796D01*
X1020128Y179951D01*
X1019783Y180003D01*
X1019438Y179900D01*
X1019170Y179693D01*
X1018978Y179331D01*
X1018940Y178918D01*
X1019016Y178505D01*
X1019208Y178246D01*
X1019476Y178040D01*
X1019745Y177988D01*
X1020013Y178040D01*
X1020358Y178246D01*
X1020243Y176903D01*
X1019208D01*
G01X1026997Y175388D02*
X1026767Y175646D01*
X1026499Y175801D01*
X1026154Y175853D01*
X1025809Y175750D01*
X1025541Y175543D01*
X1025349Y175181D01*
X1025311Y174768D01*
X1025387Y174355D01*
X1025579Y174096D01*
X1025847Y173890D01*
X1026116Y173838D01*
X1026384Y173890D01*
X1026729Y174096D01*
X1026614Y172753D01*
X1025579D01*
G01X1022594Y175853D02*
Y172753D01*
X1024012Y174975D01*
X1022096D01*
G01X1030486Y179538D02*
X1030256Y179796D01*
X1029988Y179951D01*
X1029643Y180003D01*
X1029298Y179900D01*
X1029030Y179693D01*
X1028838Y179331D01*
X1028800Y178918D01*
X1028876Y178505D01*
X1029068Y178246D01*
X1029336Y178040D01*
X1029605Y177988D01*
X1029873Y178040D01*
X1030218Y178246D01*
X1030103Y176903D01*
X1029068D01*
G01X1027386Y179383D02*
X1027156Y179745D01*
X1026850Y179951D01*
X1026505Y180003D01*
X1026198Y179951D01*
X1025891Y179693D01*
X1025700Y179383D01*
X1025661Y179073D01*
X1025738Y178711D01*
X1026006Y178453D01*
X1026275Y178350D01*
X1026620D01*
G01X1026275D02*
X1026045Y178195D01*
X1025853Y177936D01*
X1025776Y177626D01*
X1025853Y177316D01*
X1026045Y177058D01*
X1026390Y176903D01*
X1026735Y176955D01*
X1027080Y177161D01*
G01X1033757Y175388D02*
X1033527Y175646D01*
X1033259Y175801D01*
X1032914Y175853D01*
X1032569Y175750D01*
X1032301Y175543D01*
X1032109Y175181D01*
X1032071Y174768D01*
X1032147Y174355D01*
X1032339Y174096D01*
X1032607Y173890D01*
X1032876Y173838D01*
X1033144Y173890D01*
X1033489Y174096D01*
X1033374Y172753D01*
X1032339D01*
G01X1030542Y173270D02*
X1030312Y172960D01*
X1030044Y172805D01*
X1029737Y172753D01*
X1029354Y172856D01*
X1029086Y173115D01*
X1029009Y173425D01*
X1029047Y173735D01*
X1029201Y173993D01*
X1029967Y174510D01*
X1030312Y174871D01*
X1030542Y175388D01*
X1030619Y175853D01*
X1029009D01*
G01X1037245Y179538D02*
X1037015Y179796D01*
X1036747Y179951D01*
X1036402Y180003D01*
X1036057Y179900D01*
X1035789Y179693D01*
X1035597Y179331D01*
X1035559Y178918D01*
X1035635Y178505D01*
X1035827Y178246D01*
X1036095Y178040D01*
X1036364Y177988D01*
X1036632Y178040D01*
X1036977Y178246D01*
X1036862Y176903D01*
X1035827D01*
G01X1033302Y180003D02*
Y176903D01*
X1033762Y177523D01*
G01Y180003D02*
X1032842D01*
G01X985400Y440900D02*
X1053999D01*
X1054000Y440899D01*
Y414850D01*
G01X1033824Y416309D02*
Y418809D01*
X1034865D01*
X1035199Y418684D01*
X1035407Y418517D01*
X1035490Y418184D01*
X1035407Y417851D01*
X1035157Y417642D01*
X1034865Y417517D01*
X1033824D01*
G01X1034865D02*
X1035490Y416309D01*
G01X1037757D02*
X1038049Y416351D01*
X1038382Y416476D01*
X1038590Y416684D01*
X1038674Y416976D01*
X1038590Y417267D01*
X1038340Y417517D01*
X1037965Y417642D01*
X1037549D01*
X1037299Y417726D01*
X1037090Y417934D01*
X1037007Y418226D01*
X1037132Y418517D01*
X1037424Y418726D01*
X1037757Y418809D01*
X1038090Y418726D01*
X1038382Y418517D01*
X1038507Y418226D01*
X1038424Y417934D01*
X1038215Y417726D01*
X1037965Y417642D01*
X1037549D01*
X1037174Y417517D01*
X1036924Y417267D01*
X1036840Y416976D01*
X1036924Y416684D01*
X1037132Y416476D01*
X1037465Y416351D01*
X1037757Y416309D01*
G01X1041107Y417559D02*
X1041940D01*
Y416809D01*
X1041690Y416559D01*
X1041399Y416392D01*
X1040982Y416309D01*
X1040565Y416392D01*
X1040274Y416559D01*
X1040024Y416809D01*
X1039857Y417101D01*
X1039774Y417434D01*
Y417726D01*
X1039857Y417976D01*
X1040024Y418267D01*
X1040274Y418517D01*
X1040524Y418684D01*
X1040857Y418809D01*
X1041149D01*
X1041482Y418726D01*
X1041732Y418559D01*
G01X1043165Y418392D02*
X1043415Y418642D01*
X1043707Y418767D01*
X1044040Y418809D01*
X1044457Y418726D01*
X1044749Y418517D01*
X1044832Y418267D01*
X1044790Y418017D01*
X1044624Y417809D01*
X1043790Y417392D01*
X1043415Y417101D01*
X1043165Y416684D01*
X1043082Y416309D01*
X1044832D01*
G01X1046140Y416809D02*
X1046390Y416517D01*
X1046724Y416351D01*
X1047099Y416309D01*
X1047432Y416351D01*
X1047765Y416559D01*
X1047974Y416809D01*
X1048015Y417059D01*
X1047932Y417351D01*
X1047640Y417559D01*
X1047349Y417642D01*
X1046974D01*
G01X1047349D02*
X1047599Y417767D01*
X1047807Y417976D01*
X1047890Y418226D01*
X1047807Y418476D01*
X1047599Y418684D01*
X1047224Y418809D01*
X1046849Y418767D01*
X1046474Y418601D01*
G01X1018052Y420090D02*
Y422590D01*
X1019093D01*
X1019427Y422465D01*
X1019635Y422298D01*
X1019718Y421965D01*
X1019635Y421632D01*
X1019385Y421423D01*
X1019093Y421298D01*
X1018052D01*
G01X1019093D02*
X1019718Y420090D01*
G01X1021985D02*
X1022277Y420132D01*
X1022610Y420257D01*
X1022818Y420465D01*
X1022902Y420757D01*
X1022818Y421048D01*
X1022568Y421298D01*
X1022193Y421423D01*
X1021777D01*
X1021527Y421507D01*
X1021318Y421715D01*
X1021235Y422007D01*
X1021360Y422298D01*
X1021652Y422507D01*
X1021985Y422590D01*
X1022318Y422507D01*
X1022610Y422298D01*
X1022735Y422007D01*
X1022652Y421715D01*
X1022443Y421507D01*
X1022193Y421423D01*
X1021777D01*
X1021402Y421298D01*
X1021152Y421048D01*
X1021068Y420757D01*
X1021152Y420465D01*
X1021360Y420257D01*
X1021693Y420132D01*
X1021985Y420090D01*
G01X1025335Y421340D02*
X1026168D01*
Y420590D01*
X1025918Y420340D01*
X1025627Y420173D01*
X1025210Y420090D01*
X1024793Y420173D01*
X1024502Y420340D01*
X1024252Y420590D01*
X1024085Y420882D01*
X1024002Y421215D01*
Y421507D01*
X1024085Y421757D01*
X1024252Y422048D01*
X1024502Y422298D01*
X1024752Y422465D01*
X1025085Y422590D01*
X1025377D01*
X1025710Y422507D01*
X1025960Y422340D01*
G01X1027393Y422173D02*
X1027643Y422423D01*
X1027935Y422548D01*
X1028268Y422590D01*
X1028685Y422507D01*
X1028977Y422298D01*
X1029060Y422048D01*
X1029018Y421798D01*
X1028852Y421590D01*
X1028018Y421173D01*
X1027643Y420882D01*
X1027393Y420465D01*
X1027310Y420090D01*
X1029060D01*
G01X1031285Y422590D02*
X1030952Y422507D01*
X1030702Y422298D01*
X1030535Y422048D01*
X1030410Y421715D01*
X1030368Y421340D01*
X1030410Y420965D01*
X1030535Y420632D01*
X1030702Y420382D01*
X1030952Y420173D01*
X1031285Y420090D01*
X1031618Y420173D01*
X1031868Y420382D01*
X1032035Y420632D01*
X1032160Y420965D01*
X1032202Y421340D01*
X1032160Y421715D01*
X1032035Y422048D01*
X1031868Y422298D01*
X1031618Y422507D01*
X1031285Y422590D01*
G01X1018302Y416210D02*
Y418710D01*
X1019343D01*
X1019677Y418585D01*
X1019885Y418418D01*
X1019968Y418085D01*
X1019885Y417752D01*
X1019635Y417543D01*
X1019343Y417418D01*
X1018302D01*
G01X1019343D02*
X1019968Y416210D01*
G01X1022235D02*
X1022527Y416252D01*
X1022860Y416377D01*
X1023068Y416585D01*
X1023152Y416877D01*
X1023068Y417168D01*
X1022818Y417418D01*
X1022443Y417543D01*
X1022027D01*
X1021777Y417627D01*
X1021568Y417835D01*
X1021485Y418127D01*
X1021610Y418418D01*
X1021902Y418627D01*
X1022235Y418710D01*
X1022568Y418627D01*
X1022860Y418418D01*
X1022985Y418127D01*
X1022902Y417835D01*
X1022693Y417627D01*
X1022443Y417543D01*
X1022027D01*
X1021652Y417418D01*
X1021402Y417168D01*
X1021318Y416877D01*
X1021402Y416585D01*
X1021610Y416377D01*
X1021943Y416252D01*
X1022235Y416210D01*
G01X1025585Y417460D02*
X1026418D01*
Y416710D01*
X1026168Y416460D01*
X1025877Y416293D01*
X1025460Y416210D01*
X1025043Y416293D01*
X1024752Y416460D01*
X1024502Y416710D01*
X1024335Y417002D01*
X1024252Y417335D01*
Y417627D01*
X1024335Y417877D01*
X1024502Y418168D01*
X1024752Y418418D01*
X1025002Y418585D01*
X1025335Y418710D01*
X1025627D01*
X1025960Y418627D01*
X1026210Y418460D01*
G01X1027643Y418293D02*
X1027893Y418543D01*
X1028185Y418668D01*
X1028518Y418710D01*
X1028935Y418627D01*
X1029227Y418418D01*
X1029310Y418168D01*
X1029268Y417918D01*
X1029102Y417710D01*
X1028268Y417293D01*
X1027893Y417002D01*
X1027643Y416585D01*
X1027560Y416210D01*
X1029310D01*
G01X1031535D02*
Y418710D01*
X1031035Y418210D01*
G01Y416210D02*
X1032035D01*
G01X1019465Y425196D02*
X1016965D01*
Y426237D01*
X1017090Y426571D01*
X1017257Y426779D01*
X1017590Y426862D01*
X1017923Y426779D01*
X1018132Y426529D01*
X1018257Y426237D01*
Y425196D01*
G01Y426237D02*
X1019465Y426862D01*
G01Y429129D02*
X1019423Y429421D01*
X1019298Y429754D01*
X1019090Y429962D01*
X1018798Y430046D01*
X1018507Y429962D01*
X1018257Y429712D01*
X1018132Y429337D01*
Y428921D01*
X1018048Y428671D01*
X1017840Y428462D01*
X1017548Y428379D01*
X1017257Y428504D01*
X1017048Y428796D01*
X1016965Y429129D01*
X1017048Y429462D01*
X1017257Y429754D01*
X1017548Y429879D01*
X1017840Y429796D01*
X1018048Y429587D01*
X1018132Y429337D01*
Y428921D01*
X1018257Y428546D01*
X1018507Y428296D01*
X1018798Y428212D01*
X1019090Y428296D01*
X1019298Y428504D01*
X1019423Y428837D01*
X1019465Y429129D01*
G01X1018215Y432479D02*
Y433312D01*
X1018965D01*
X1019215Y433062D01*
X1019382Y432771D01*
X1019465Y432354D01*
X1019382Y431937D01*
X1019215Y431646D01*
X1018965Y431396D01*
X1018673Y431229D01*
X1018340Y431146D01*
X1018048D01*
X1017798Y431229D01*
X1017507Y431396D01*
X1017257Y431646D01*
X1017090Y431896D01*
X1016965Y432229D01*
Y432521D01*
X1017048Y432854D01*
X1017215Y433104D01*
G01X1019465Y435329D02*
X1016965D01*
X1017465Y434829D01*
G01X1019465D02*
Y435829D01*
G01Y438929D02*
X1016965D01*
X1018757Y437387D01*
Y439471D01*
G01X991465Y425196D02*
X988965D01*
Y426237D01*
X989090Y426571D01*
X989257Y426779D01*
X989590Y426862D01*
X989923Y426779D01*
X990132Y426529D01*
X990257Y426237D01*
Y425196D01*
G01Y426237D02*
X991465Y426862D01*
G01Y429129D02*
X991423Y429421D01*
X991298Y429754D01*
X991090Y429962D01*
X990798Y430046D01*
X990507Y429962D01*
X990257Y429712D01*
X990132Y429337D01*
Y428921D01*
X990048Y428671D01*
X989840Y428462D01*
X989548Y428379D01*
X989257Y428504D01*
X989048Y428796D01*
X988965Y429129D01*
X989048Y429462D01*
X989257Y429754D01*
X989548Y429879D01*
X989840Y429796D01*
X990048Y429587D01*
X990132Y429337D01*
Y428921D01*
X990257Y428546D01*
X990507Y428296D01*
X990798Y428212D01*
X991090Y428296D01*
X991298Y428504D01*
X991423Y428837D01*
X991465Y429129D01*
G01X990215Y432479D02*
Y433312D01*
X990965D01*
X991215Y433062D01*
X991382Y432771D01*
X991465Y432354D01*
X991382Y431937D01*
X991215Y431646D01*
X990965Y431396D01*
X990673Y431229D01*
X990340Y431146D01*
X990048D01*
X989798Y431229D01*
X989507Y431396D01*
X989257Y431646D01*
X989090Y431896D01*
X988965Y432229D01*
Y432521D01*
X989048Y432854D01*
X989215Y433104D01*
G01X991465Y435329D02*
X991423Y435621D01*
X991298Y435954D01*
X991090Y436162D01*
X990798Y436246D01*
X990507Y436162D01*
X990257Y435912D01*
X990132Y435537D01*
Y435121D01*
X990048Y434871D01*
X989840Y434662D01*
X989548Y434579D01*
X989257Y434704D01*
X989048Y434996D01*
X988965Y435329D01*
X989048Y435662D01*
X989257Y435954D01*
X989548Y436079D01*
X989840Y435996D01*
X990048Y435787D01*
X990132Y435537D01*
Y435121D01*
X990257Y434746D01*
X990507Y434496D01*
X990798Y434412D01*
X991090Y434496D01*
X991298Y434704D01*
X991423Y435037D01*
X991465Y435329D01*
G01X985466Y416408D02*
Y418908D01*
X986507D01*
X986841Y418783D01*
X987049Y418616D01*
X987132Y418283D01*
X987049Y417950D01*
X986799Y417741D01*
X986507Y417616D01*
X985466D01*
G01X986507D02*
X987132Y416408D01*
G01X989316D02*
X989399Y416950D01*
X989524Y417408D01*
X989691Y417825D01*
X989899Y418283D01*
X990232Y418908D01*
X988566D01*
G01X992749Y417658D02*
X993582D01*
Y416908D01*
X993332Y416658D01*
X993041Y416491D01*
X992624Y416408D01*
X992207Y416491D01*
X991916Y416658D01*
X991666Y416908D01*
X991499Y417200D01*
X991416Y417533D01*
Y417825D01*
X991499Y418075D01*
X991666Y418366D01*
X991916Y418616D01*
X992166Y418783D01*
X992499Y418908D01*
X992791D01*
X993124Y418825D01*
X993374Y418658D01*
G01X994807Y418491D02*
X995057Y418741D01*
X995349Y418866D01*
X995682Y418908D01*
X996099Y418825D01*
X996391Y418616D01*
X996474Y418366D01*
X996432Y418116D01*
X996266Y417908D01*
X995432Y417491D01*
X995057Y417200D01*
X994807Y416783D01*
X994724Y416408D01*
X996474D01*
G01X997907Y418491D02*
X998157Y418741D01*
X998449Y418866D01*
X998782Y418908D01*
X999199Y418825D01*
X999491Y418616D01*
X999574Y418366D01*
X999532Y418116D01*
X999366Y417908D01*
X998532Y417491D01*
X998157Y417200D01*
X997907Y416783D01*
X997824Y416408D01*
X999574D01*
G01X979086Y415844D02*
X976586D01*
Y416885D01*
X976711Y417219D01*
X976878Y417427D01*
X977211Y417510D01*
X977544Y417427D01*
X977753Y417177D01*
X977878Y416885D01*
Y415844D01*
G01Y416885D02*
X979086Y417510D01*
G01Y419694D02*
X978544Y419777D01*
X978086Y419902D01*
X977669Y420069D01*
X977211Y420277D01*
X976586Y420610D01*
Y418944D01*
G01X977836Y423127D02*
Y423960D01*
X978586D01*
X978836Y423710D01*
X979003Y423419D01*
X979086Y423002D01*
X979003Y422585D01*
X978836Y422294D01*
X978586Y422044D01*
X978294Y421877D01*
X977961Y421794D01*
X977669D01*
X977419Y421877D01*
X977128Y422044D01*
X976878Y422294D01*
X976711Y422544D01*
X976586Y422877D01*
Y423169D01*
X976669Y423502D01*
X976836Y423752D01*
G01X979086Y425977D02*
X976586D01*
X977086Y425477D01*
G01X979086D02*
Y426477D01*
G01X978044Y428285D02*
X977753Y428577D01*
X977586Y428827D01*
X977503Y429160D01*
X977586Y429452D01*
X977753Y429660D01*
X978003Y429827D01*
X978294Y429869D01*
X978544Y429827D01*
X978794Y429660D01*
X979003Y429410D01*
X979086Y429119D01*
X979003Y428785D01*
X978753Y428494D01*
X978378Y428327D01*
X977961Y428285D01*
X977419Y428369D01*
X977128Y428494D01*
X976836Y428702D01*
X976628Y428994D01*
X976586Y429285D01*
X976669Y429577D01*
X976878Y429785D01*
G01X983086Y415844D02*
X980586D01*
Y416885D01*
X980711Y417219D01*
X980878Y417427D01*
X981211Y417510D01*
X981544Y417427D01*
X981753Y417177D01*
X981878Y416885D01*
Y415844D01*
G01Y416885D02*
X983086Y417510D01*
G01Y419694D02*
X982544Y419777D01*
X982086Y419902D01*
X981669Y420069D01*
X981211Y420277D01*
X980586Y420610D01*
Y418944D01*
G01X981836Y423127D02*
Y423960D01*
X982586D01*
X982836Y423710D01*
X983003Y423419D01*
X983086Y423002D01*
X983003Y422585D01*
X982836Y422294D01*
X982586Y422044D01*
X982294Y421877D01*
X981961Y421794D01*
X981669D01*
X981419Y421877D01*
X981128Y422044D01*
X980878Y422294D01*
X980711Y422544D01*
X980586Y422877D01*
Y423169D01*
X980669Y423502D01*
X980836Y423752D01*
G01X983086Y425977D02*
X980586D01*
X981086Y425477D01*
G01X983086D02*
Y426477D01*
G01Y428994D02*
X982544Y429077D01*
X982086Y429202D01*
X981669Y429369D01*
X981211Y429577D01*
X980586Y429910D01*
Y428244D01*
G01X975086Y415844D02*
X972586D01*
Y416885D01*
X972711Y417219D01*
X972878Y417427D01*
X973211Y417510D01*
X973544Y417427D01*
X973753Y417177D01*
X973878Y416885D01*
Y415844D01*
G01Y416885D02*
X975086Y417510D01*
G01Y419694D02*
X974544Y419777D01*
X974086Y419902D01*
X973669Y420069D01*
X973211Y420277D01*
X972586Y420610D01*
Y418944D01*
G01X973836Y423127D02*
Y423960D01*
X974586D01*
X974836Y423710D01*
X975003Y423419D01*
X975086Y423002D01*
X975003Y422585D01*
X974836Y422294D01*
X974586Y422044D01*
X974294Y421877D01*
X973961Y421794D01*
X973669D01*
X973419Y421877D01*
X973128Y422044D01*
X972878Y422294D01*
X972711Y422544D01*
X972586Y422877D01*
Y423169D01*
X972669Y423502D01*
X972836Y423752D01*
G01X975086Y425977D02*
X972586D01*
X973086Y425477D01*
G01X975086D02*
Y426477D01*
G01X974711Y428160D02*
X974919Y428410D01*
X975044Y428702D01*
X975086Y429077D01*
X975003Y429452D01*
X974836Y429744D01*
X974544Y429952D01*
X974211Y429994D01*
X973878Y429910D01*
X973669Y429702D01*
X973503Y429410D01*
X973461Y429119D01*
X973503Y428827D01*
X973669Y428452D01*
X972586Y428577D01*
Y429702D01*
G01X1033747Y419890D02*
Y422390D01*
X1034788D01*
X1035122Y422265D01*
X1035330Y422098D01*
X1035413Y421765D01*
X1035330Y421432D01*
X1035080Y421223D01*
X1034788Y421098D01*
X1033747D01*
G01X1034788D02*
X1035413Y419890D01*
G01X1037680D02*
X1037972Y419932D01*
X1038305Y420057D01*
X1038513Y420265D01*
X1038597Y420557D01*
X1038513Y420848D01*
X1038263Y421098D01*
X1037888Y421223D01*
X1037472D01*
X1037222Y421307D01*
X1037013Y421515D01*
X1036930Y421807D01*
X1037055Y422098D01*
X1037347Y422307D01*
X1037680Y422390D01*
X1038013Y422307D01*
X1038305Y422098D01*
X1038430Y421807D01*
X1038347Y421515D01*
X1038138Y421307D01*
X1037888Y421223D01*
X1037472D01*
X1037097Y421098D01*
X1036847Y420848D01*
X1036763Y420557D01*
X1036847Y420265D01*
X1037055Y420057D01*
X1037388Y419932D01*
X1037680Y419890D01*
G01X1041030Y421140D02*
X1041863D01*
Y420390D01*
X1041613Y420140D01*
X1041322Y419973D01*
X1040905Y419890D01*
X1040488Y419973D01*
X1040197Y420140D01*
X1039947Y420390D01*
X1039780Y420682D01*
X1039697Y421015D01*
Y421307D01*
X1039780Y421557D01*
X1039947Y421848D01*
X1040197Y422098D01*
X1040447Y422265D01*
X1040780Y422390D01*
X1041072D01*
X1041405Y422307D01*
X1041655Y422140D01*
G01X1043088Y421973D02*
X1043338Y422223D01*
X1043630Y422348D01*
X1043963Y422390D01*
X1044380Y422307D01*
X1044672Y422098D01*
X1044755Y421848D01*
X1044713Y421598D01*
X1044547Y421390D01*
X1043713Y420973D01*
X1043338Y420682D01*
X1043088Y420265D01*
X1043005Y419890D01*
X1044755D01*
G01X1046188Y421973D02*
X1046438Y422223D01*
X1046730Y422348D01*
X1047063Y422390D01*
X1047480Y422307D01*
X1047772Y422098D01*
X1047855Y421848D01*
X1047813Y421598D01*
X1047647Y421390D01*
X1046813Y420973D01*
X1046438Y420682D01*
X1046188Y420265D01*
X1046105Y419890D01*
X1047855D01*
G01X1031465Y425196D02*
X1028965D01*
Y426237D01*
X1029090Y426571D01*
X1029257Y426779D01*
X1029590Y426862D01*
X1029923Y426779D01*
X1030132Y426529D01*
X1030257Y426237D01*
Y425196D01*
G01Y426237D02*
X1031465Y426862D01*
G01Y429129D02*
X1031423Y429421D01*
X1031298Y429754D01*
X1031090Y429962D01*
X1030798Y430046D01*
X1030507Y429962D01*
X1030257Y429712D01*
X1030132Y429337D01*
Y428921D01*
X1030048Y428671D01*
X1029840Y428462D01*
X1029548Y428379D01*
X1029257Y428504D01*
X1029048Y428796D01*
X1028965Y429129D01*
X1029048Y429462D01*
X1029257Y429754D01*
X1029548Y429879D01*
X1029840Y429796D01*
X1030048Y429587D01*
X1030132Y429337D01*
Y428921D01*
X1030257Y428546D01*
X1030507Y428296D01*
X1030798Y428212D01*
X1031090Y428296D01*
X1031298Y428504D01*
X1031423Y428837D01*
X1031465Y429129D01*
G01X1030215Y432479D02*
Y433312D01*
X1030965D01*
X1031215Y433062D01*
X1031382Y432771D01*
X1031465Y432354D01*
X1031382Y431937D01*
X1031215Y431646D01*
X1030965Y431396D01*
X1030673Y431229D01*
X1030340Y431146D01*
X1030048D01*
X1029798Y431229D01*
X1029507Y431396D01*
X1029257Y431646D01*
X1029090Y431896D01*
X1028965Y432229D01*
Y432521D01*
X1029048Y432854D01*
X1029215Y433104D01*
G01X1031465Y435329D02*
X1028965D01*
X1029465Y434829D01*
G01X1031465D02*
Y435829D01*
G01X1031090Y437512D02*
X1031298Y437762D01*
X1031423Y438054D01*
X1031465Y438429D01*
X1031382Y438804D01*
X1031215Y439096D01*
X1030923Y439304D01*
X1030590Y439346D01*
X1030257Y439262D01*
X1030048Y439054D01*
X1029882Y438762D01*
X1029840Y438471D01*
X1029882Y438179D01*
X1030048Y437804D01*
X1028965Y437929D01*
Y439054D01*
G01X1023465Y425196D02*
X1020965D01*
Y426237D01*
X1021090Y426571D01*
X1021257Y426779D01*
X1021590Y426862D01*
X1021923Y426779D01*
X1022132Y426529D01*
X1022257Y426237D01*
Y425196D01*
G01Y426237D02*
X1023465Y426862D01*
G01Y429129D02*
X1023423Y429421D01*
X1023298Y429754D01*
X1023090Y429962D01*
X1022798Y430046D01*
X1022507Y429962D01*
X1022257Y429712D01*
X1022132Y429337D01*
Y428921D01*
X1022048Y428671D01*
X1021840Y428462D01*
X1021548Y428379D01*
X1021257Y428504D01*
X1021048Y428796D01*
X1020965Y429129D01*
X1021048Y429462D01*
X1021257Y429754D01*
X1021548Y429879D01*
X1021840Y429796D01*
X1022048Y429587D01*
X1022132Y429337D01*
Y428921D01*
X1022257Y428546D01*
X1022507Y428296D01*
X1022798Y428212D01*
X1023090Y428296D01*
X1023298Y428504D01*
X1023423Y428837D01*
X1023465Y429129D01*
G01X1022215Y432479D02*
Y433312D01*
X1022965D01*
X1023215Y433062D01*
X1023382Y432771D01*
X1023465Y432354D01*
X1023382Y431937D01*
X1023215Y431646D01*
X1022965Y431396D01*
X1022673Y431229D01*
X1022340Y431146D01*
X1022048D01*
X1021798Y431229D01*
X1021507Y431396D01*
X1021257Y431646D01*
X1021090Y431896D01*
X1020965Y432229D01*
Y432521D01*
X1021048Y432854D01*
X1021215Y433104D01*
G01X1023465Y435329D02*
X1020965D01*
X1021465Y434829D01*
G01X1023465D02*
Y435829D01*
G01Y438346D02*
X1022923Y438429D01*
X1022465Y438554D01*
X1022048Y438721D01*
X1021590Y438929D01*
X1020965Y439262D01*
Y437596D01*
G01X1027465Y425196D02*
X1024965D01*
Y426237D01*
X1025090Y426571D01*
X1025257Y426779D01*
X1025590Y426862D01*
X1025923Y426779D01*
X1026132Y426529D01*
X1026257Y426237D01*
Y425196D01*
G01Y426237D02*
X1027465Y426862D01*
G01Y429129D02*
X1027423Y429421D01*
X1027298Y429754D01*
X1027090Y429962D01*
X1026798Y430046D01*
X1026507Y429962D01*
X1026257Y429712D01*
X1026132Y429337D01*
Y428921D01*
X1026048Y428671D01*
X1025840Y428462D01*
X1025548Y428379D01*
X1025257Y428504D01*
X1025048Y428796D01*
X1024965Y429129D01*
X1025048Y429462D01*
X1025257Y429754D01*
X1025548Y429879D01*
X1025840Y429796D01*
X1026048Y429587D01*
X1026132Y429337D01*
Y428921D01*
X1026257Y428546D01*
X1026507Y428296D01*
X1026798Y428212D01*
X1027090Y428296D01*
X1027298Y428504D01*
X1027423Y428837D01*
X1027465Y429129D01*
G01X1026215Y432479D02*
Y433312D01*
X1026965D01*
X1027215Y433062D01*
X1027382Y432771D01*
X1027465Y432354D01*
X1027382Y431937D01*
X1027215Y431646D01*
X1026965Y431396D01*
X1026673Y431229D01*
X1026340Y431146D01*
X1026048D01*
X1025798Y431229D01*
X1025507Y431396D01*
X1025257Y431646D01*
X1025090Y431896D01*
X1024965Y432229D01*
Y432521D01*
X1025048Y432854D01*
X1025215Y433104D01*
G01X1027465Y435329D02*
X1024965D01*
X1025465Y434829D01*
G01X1027465D02*
Y435829D01*
G01X1026423Y437637D02*
X1026132Y437929D01*
X1025965Y438179D01*
X1025882Y438512D01*
X1025965Y438804D01*
X1026132Y439012D01*
X1026382Y439179D01*
X1026673Y439221D01*
X1026923Y439179D01*
X1027173Y439012D01*
X1027382Y438762D01*
X1027465Y438471D01*
X1027382Y438137D01*
X1027132Y437846D01*
X1026757Y437679D01*
X1026340Y437637D01*
X1025798Y437721D01*
X1025507Y437846D01*
X1025215Y438054D01*
X1025007Y438346D01*
X1024965Y438637D01*
X1025048Y438929D01*
X1025257Y439137D01*
G01X1003465Y425196D02*
X1000965D01*
Y426237D01*
X1001090Y426571D01*
X1001257Y426779D01*
X1001590Y426862D01*
X1001923Y426779D01*
X1002132Y426529D01*
X1002257Y426237D01*
Y425196D01*
G01Y426237D02*
X1003465Y426862D01*
G01Y429129D02*
X1003423Y429421D01*
X1003298Y429754D01*
X1003090Y429962D01*
X1002798Y430046D01*
X1002507Y429962D01*
X1002257Y429712D01*
X1002132Y429337D01*
Y428921D01*
X1002048Y428671D01*
X1001840Y428462D01*
X1001548Y428379D01*
X1001257Y428504D01*
X1001048Y428796D01*
X1000965Y429129D01*
X1001048Y429462D01*
X1001257Y429754D01*
X1001548Y429879D01*
X1001840Y429796D01*
X1002048Y429587D01*
X1002132Y429337D01*
Y428921D01*
X1002257Y428546D01*
X1002507Y428296D01*
X1002798Y428212D01*
X1003090Y428296D01*
X1003298Y428504D01*
X1003423Y428837D01*
X1003465Y429129D01*
G01X1002215Y432479D02*
Y433312D01*
X1002965D01*
X1003215Y433062D01*
X1003382Y432771D01*
X1003465Y432354D01*
X1003382Y431937D01*
X1003215Y431646D01*
X1002965Y431396D01*
X1002673Y431229D01*
X1002340Y431146D01*
X1002048D01*
X1001798Y431229D01*
X1001507Y431396D01*
X1001257Y431646D01*
X1001090Y431896D01*
X1000965Y432229D01*
Y432521D01*
X1001048Y432854D01*
X1001215Y433104D01*
G01X1003173Y434621D02*
X1003382Y434912D01*
X1003465Y435246D01*
X1003382Y435579D01*
X1003132Y435871D01*
X1002757Y436079D01*
X1002382Y436162D01*
X1001923D01*
X1001548Y436079D01*
X1001215Y435871D01*
X1001048Y435621D01*
X1000965Y435329D01*
X1001048Y434996D01*
X1001215Y434746D01*
X1001465Y434579D01*
X1001798Y434496D01*
X1002090Y434579D01*
X1002382Y434787D01*
X1002548Y435037D01*
X1002590Y435329D01*
X1002507Y435662D01*
X1002298Y435912D01*
X1001923Y436162D01*
G01X999465Y425196D02*
X996965D01*
Y426237D01*
X997090Y426571D01*
X997257Y426779D01*
X997590Y426862D01*
X997923Y426779D01*
X998132Y426529D01*
X998257Y426237D01*
Y425196D01*
G01Y426237D02*
X999465Y426862D01*
G01Y429046D02*
X998923Y429129D01*
X998465Y429254D01*
X998048Y429421D01*
X997590Y429629D01*
X996965Y429962D01*
Y428296D01*
G01X998215Y432479D02*
Y433312D01*
X998965D01*
X999215Y433062D01*
X999382Y432771D01*
X999465Y432354D01*
X999382Y431937D01*
X999215Y431646D01*
X998965Y431396D01*
X998673Y431229D01*
X998340Y431146D01*
X998048D01*
X997798Y431229D01*
X997507Y431396D01*
X997257Y431646D01*
X997090Y431896D01*
X996965Y432229D01*
Y432521D01*
X997048Y432854D01*
X997215Y433104D01*
G01X999465Y435329D02*
X996965D01*
X997465Y434829D01*
G01X999465D02*
Y435829D01*
G01Y438429D02*
X999423Y438721D01*
X999298Y439054D01*
X999090Y439262D01*
X998798Y439346D01*
X998507Y439262D01*
X998257Y439012D01*
X998132Y438637D01*
Y438221D01*
X998048Y437971D01*
X997840Y437762D01*
X997548Y437679D01*
X997257Y437804D01*
X997048Y438096D01*
X996965Y438429D01*
X997048Y438762D01*
X997257Y439054D01*
X997548Y439179D01*
X997840Y439096D01*
X998048Y438887D01*
X998132Y438637D01*
Y438221D01*
X998257Y437846D01*
X998507Y437596D01*
X998798Y437512D01*
X999090Y437596D01*
X999298Y437804D01*
X999423Y438137D01*
X999465Y438429D01*
G01X1007465Y425196D02*
X1004965D01*
Y426237D01*
X1005090Y426571D01*
X1005257Y426779D01*
X1005590Y426862D01*
X1005923Y426779D01*
X1006132Y426529D01*
X1006257Y426237D01*
Y425196D01*
G01Y426237D02*
X1007465Y426862D01*
G01Y429129D02*
X1007423Y429421D01*
X1007298Y429754D01*
X1007090Y429962D01*
X1006798Y430046D01*
X1006507Y429962D01*
X1006257Y429712D01*
X1006132Y429337D01*
Y428921D01*
X1006048Y428671D01*
X1005840Y428462D01*
X1005548Y428379D01*
X1005257Y428504D01*
X1005048Y428796D01*
X1004965Y429129D01*
X1005048Y429462D01*
X1005257Y429754D01*
X1005548Y429879D01*
X1005840Y429796D01*
X1006048Y429587D01*
X1006132Y429337D01*
Y428921D01*
X1006257Y428546D01*
X1006507Y428296D01*
X1006798Y428212D01*
X1007090Y428296D01*
X1007298Y428504D01*
X1007423Y428837D01*
X1007465Y429129D01*
G01X1006215Y432479D02*
Y433312D01*
X1006965D01*
X1007215Y433062D01*
X1007382Y432771D01*
X1007465Y432354D01*
X1007382Y431937D01*
X1007215Y431646D01*
X1006965Y431396D01*
X1006673Y431229D01*
X1006340Y431146D01*
X1006048D01*
X1005798Y431229D01*
X1005507Y431396D01*
X1005257Y431646D01*
X1005090Y431896D01*
X1004965Y432229D01*
Y432521D01*
X1005048Y432854D01*
X1005215Y433104D01*
G01X1007465Y435329D02*
X1004965D01*
X1005465Y434829D01*
G01X1007465D02*
Y435829D01*
G01X1004965Y438429D02*
X1005048Y438096D01*
X1005257Y437846D01*
X1005507Y437679D01*
X1005840Y437554D01*
X1006215Y437512D01*
X1006590Y437554D01*
X1006923Y437679D01*
X1007173Y437846D01*
X1007382Y438096D01*
X1007465Y438429D01*
X1007382Y438762D01*
X1007173Y439012D01*
X1006923Y439179D01*
X1006590Y439304D01*
X1006215Y439346D01*
X1005840Y439304D01*
X1005507Y439179D01*
X1005257Y439012D01*
X1005048Y438762D01*
X1004965Y438429D01*
G01X1001857Y420188D02*
Y422688D01*
X1002898D01*
X1003232Y422563D01*
X1003440Y422396D01*
X1003523Y422063D01*
X1003440Y421730D01*
X1003190Y421521D01*
X1002898Y421396D01*
X1001857D01*
G01X1002898D02*
X1003523Y420188D01*
G01X1005707D02*
X1005790Y420730D01*
X1005915Y421188D01*
X1006082Y421605D01*
X1006290Y422063D01*
X1006623Y422688D01*
X1004957D01*
G01X1009140Y421438D02*
X1009973D01*
Y420688D01*
X1009723Y420438D01*
X1009432Y420271D01*
X1009015Y420188D01*
X1008598Y420271D01*
X1008307Y420438D01*
X1008057Y420688D01*
X1007890Y420980D01*
X1007807Y421313D01*
Y421605D01*
X1007890Y421855D01*
X1008057Y422146D01*
X1008307Y422396D01*
X1008557Y422563D01*
X1008890Y422688D01*
X1009182D01*
X1009515Y422605D01*
X1009765Y422438D01*
G01X1011198Y422271D02*
X1011448Y422521D01*
X1011740Y422646D01*
X1012073Y422688D01*
X1012490Y422605D01*
X1012782Y422396D01*
X1012865Y422146D01*
X1012823Y421896D01*
X1012657Y421688D01*
X1011823Y421271D01*
X1011448Y420980D01*
X1011198Y420563D01*
X1011115Y420188D01*
X1012865D01*
G01X1014173Y420688D02*
X1014423Y420396D01*
X1014757Y420230D01*
X1015132Y420188D01*
X1015465Y420230D01*
X1015798Y420438D01*
X1016007Y420688D01*
X1016048Y420938D01*
X1015965Y421230D01*
X1015673Y421438D01*
X1015382Y421521D01*
X1015007D01*
G01X1015382D02*
X1015632Y421646D01*
X1015840Y421855D01*
X1015923Y422105D01*
X1015840Y422355D01*
X1015632Y422563D01*
X1015257Y422688D01*
X1014882Y422646D01*
X1014507Y422480D01*
G01X1001783Y416507D02*
Y419007D01*
X1002824D01*
X1003158Y418882D01*
X1003366Y418715D01*
X1003449Y418382D01*
X1003366Y418049D01*
X1003116Y417840D01*
X1002824Y417715D01*
X1001783D01*
G01X1002824D02*
X1003449Y416507D01*
G01X1005716D02*
X1006008Y416549D01*
X1006341Y416674D01*
X1006549Y416882D01*
X1006633Y417174D01*
X1006549Y417465D01*
X1006299Y417715D01*
X1005924Y417840D01*
X1005508D01*
X1005258Y417924D01*
X1005049Y418132D01*
X1004966Y418424D01*
X1005091Y418715D01*
X1005383Y418924D01*
X1005716Y419007D01*
X1006049Y418924D01*
X1006341Y418715D01*
X1006466Y418424D01*
X1006383Y418132D01*
X1006174Y417924D01*
X1005924Y417840D01*
X1005508D01*
X1005133Y417715D01*
X1004883Y417465D01*
X1004799Y417174D01*
X1004883Y416882D01*
X1005091Y416674D01*
X1005424Y416549D01*
X1005716Y416507D01*
G01X1009066Y417757D02*
X1009899D01*
Y417007D01*
X1009649Y416757D01*
X1009358Y416590D01*
X1008941Y416507D01*
X1008524Y416590D01*
X1008233Y416757D01*
X1007983Y417007D01*
X1007816Y417299D01*
X1007733Y417632D01*
Y417924D01*
X1007816Y418174D01*
X1007983Y418465D01*
X1008233Y418715D01*
X1008483Y418882D01*
X1008816Y419007D01*
X1009108D01*
X1009441Y418924D01*
X1009691Y418757D01*
G01X1011916Y416507D02*
Y419007D01*
X1011416Y418507D01*
G01Y416507D02*
X1012416D01*
G01X1014308Y416799D02*
X1014599Y416590D01*
X1014933Y416507D01*
X1015266Y416590D01*
X1015558Y416840D01*
X1015766Y417215D01*
X1015849Y417590D01*
Y418049D01*
X1015766Y418424D01*
X1015558Y418757D01*
X1015308Y418924D01*
X1015016Y419007D01*
X1014683Y418924D01*
X1014433Y418757D01*
X1014266Y418507D01*
X1014183Y418174D01*
X1014266Y417882D01*
X1014474Y417590D01*
X1014724Y417424D01*
X1015016Y417382D01*
X1015349Y417465D01*
X1015599Y417674D01*
X1015849Y418049D01*
G01X995465Y425196D02*
X992965D01*
Y426237D01*
X993090Y426571D01*
X993257Y426779D01*
X993590Y426862D01*
X993923Y426779D01*
X994132Y426529D01*
X994257Y426237D01*
Y425196D01*
G01Y426237D02*
X995465Y426862D01*
G01Y429046D02*
X994923Y429129D01*
X994465Y429254D01*
X994048Y429421D01*
X993590Y429629D01*
X992965Y429962D01*
Y428296D01*
G01X994215Y432479D02*
Y433312D01*
X994965D01*
X995215Y433062D01*
X995382Y432771D01*
X995465Y432354D01*
X995382Y431937D01*
X995215Y431646D01*
X994965Y431396D01*
X994673Y431229D01*
X994340Y431146D01*
X994048D01*
X993798Y431229D01*
X993507Y431396D01*
X993257Y431646D01*
X993090Y431896D01*
X992965Y432229D01*
Y432521D01*
X993048Y432854D01*
X993215Y433104D01*
G01X995465Y435329D02*
X992965D01*
X993465Y434829D01*
G01X995465D02*
Y435829D01*
G01X995173Y437721D02*
X995382Y438012D01*
X995465Y438346D01*
X995382Y438679D01*
X995132Y438971D01*
X994757Y439179D01*
X994382Y439262D01*
X993923D01*
X993548Y439179D01*
X993215Y438971D01*
X993048Y438721D01*
X992965Y438429D01*
X993048Y438096D01*
X993215Y437846D01*
X993465Y437679D01*
X993798Y437596D01*
X994090Y437679D01*
X994382Y437887D01*
X994548Y438137D01*
X994590Y438429D01*
X994507Y438762D01*
X994298Y439012D01*
X993923Y439262D01*
G01X1011465Y425196D02*
X1008965D01*
Y426237D01*
X1009090Y426571D01*
X1009257Y426779D01*
X1009590Y426862D01*
X1009923Y426779D01*
X1010132Y426529D01*
X1010257Y426237D01*
Y425196D01*
G01Y426237D02*
X1011465Y426862D01*
G01Y429129D02*
X1011423Y429421D01*
X1011298Y429754D01*
X1011090Y429962D01*
X1010798Y430046D01*
X1010507Y429962D01*
X1010257Y429712D01*
X1010132Y429337D01*
Y428921D01*
X1010048Y428671D01*
X1009840Y428462D01*
X1009548Y428379D01*
X1009257Y428504D01*
X1009048Y428796D01*
X1008965Y429129D01*
X1009048Y429462D01*
X1009257Y429754D01*
X1009548Y429879D01*
X1009840Y429796D01*
X1010048Y429587D01*
X1010132Y429337D01*
Y428921D01*
X1010257Y428546D01*
X1010507Y428296D01*
X1010798Y428212D01*
X1011090Y428296D01*
X1011298Y428504D01*
X1011423Y428837D01*
X1011465Y429129D01*
G01X1010215Y432479D02*
Y433312D01*
X1010965D01*
X1011215Y433062D01*
X1011382Y432771D01*
X1011465Y432354D01*
X1011382Y431937D01*
X1011215Y431646D01*
X1010965Y431396D01*
X1010673Y431229D01*
X1010340Y431146D01*
X1010048D01*
X1009798Y431229D01*
X1009507Y431396D01*
X1009257Y431646D01*
X1009090Y431896D01*
X1008965Y432229D01*
Y432521D01*
X1009048Y432854D01*
X1009215Y433104D01*
G01X1011465Y435329D02*
X1008965D01*
X1009465Y434829D01*
G01X1011465D02*
Y435829D01*
G01Y438429D02*
X1008965D01*
X1009465Y437929D01*
G01X1011465D02*
Y438929D01*
G01X1015465Y425196D02*
X1012965D01*
Y426237D01*
X1013090Y426571D01*
X1013257Y426779D01*
X1013590Y426862D01*
X1013923Y426779D01*
X1014132Y426529D01*
X1014257Y426237D01*
Y425196D01*
G01Y426237D02*
X1015465Y426862D01*
G01Y429129D02*
X1015423Y429421D01*
X1015298Y429754D01*
X1015090Y429962D01*
X1014798Y430046D01*
X1014507Y429962D01*
X1014257Y429712D01*
X1014132Y429337D01*
Y428921D01*
X1014048Y428671D01*
X1013840Y428462D01*
X1013548Y428379D01*
X1013257Y428504D01*
X1013048Y428796D01*
X1012965Y429129D01*
X1013048Y429462D01*
X1013257Y429754D01*
X1013548Y429879D01*
X1013840Y429796D01*
X1014048Y429587D01*
X1014132Y429337D01*
Y428921D01*
X1014257Y428546D01*
X1014507Y428296D01*
X1014798Y428212D01*
X1015090Y428296D01*
X1015298Y428504D01*
X1015423Y428837D01*
X1015465Y429129D01*
G01X1014215Y432479D02*
Y433312D01*
X1014965D01*
X1015215Y433062D01*
X1015382Y432771D01*
X1015465Y432354D01*
X1015382Y431937D01*
X1015215Y431646D01*
X1014965Y431396D01*
X1014673Y431229D01*
X1014340Y431146D01*
X1014048D01*
X1013798Y431229D01*
X1013507Y431396D01*
X1013257Y431646D01*
X1013090Y431896D01*
X1012965Y432229D01*
Y432521D01*
X1013048Y432854D01*
X1013215Y433104D01*
G01X1015465Y435329D02*
X1012965D01*
X1013465Y434829D01*
G01X1015465D02*
Y435829D01*
G01X1013382Y437637D02*
X1013132Y437887D01*
X1013007Y438179D01*
X1012965Y438512D01*
X1013048Y438929D01*
X1013257Y439221D01*
X1013507Y439304D01*
X1013757Y439262D01*
X1013965Y439096D01*
X1014382Y438262D01*
X1014673Y437887D01*
X1015090Y437637D01*
X1015465Y437554D01*
Y439304D01*
G01X985764Y420487D02*
Y422987D01*
X986805D01*
X987139Y422862D01*
X987347Y422695D01*
X987430Y422362D01*
X987347Y422029D01*
X987097Y421820D01*
X986805Y421695D01*
X985764D01*
G01X986805D02*
X987430Y420487D01*
G01X989614D02*
X989697Y421029D01*
X989822Y421487D01*
X989989Y421904D01*
X990197Y422362D01*
X990530Y422987D01*
X988864D01*
G01X993047Y421737D02*
X993880D01*
Y420987D01*
X993630Y420737D01*
X993339Y420570D01*
X992922Y420487D01*
X992505Y420570D01*
X992214Y420737D01*
X991964Y420987D01*
X991797Y421279D01*
X991714Y421612D01*
Y421904D01*
X991797Y422154D01*
X991964Y422445D01*
X992214Y422695D01*
X992464Y422862D01*
X992797Y422987D01*
X993089D01*
X993422Y422904D01*
X993672Y422737D01*
G01X995105Y422570D02*
X995355Y422820D01*
X995647Y422945D01*
X995980Y422987D01*
X996397Y422904D01*
X996689Y422695D01*
X996772Y422445D01*
X996730Y422195D01*
X996564Y421987D01*
X995730Y421570D01*
X995355Y421279D01*
X995105Y420862D01*
X995022Y420487D01*
X996772D01*
G01X998997D02*
Y422987D01*
X998497Y422487D01*
G01Y420487D02*
X999497D01*
G01X1179200Y480051D02*
Y516800D01*
X1062800D01*
Y501400D01*
X978200D01*
G01X976300Y494500D02*
Y470070D01*
X988210D01*
Y468700D01*
X1075839D01*
X1075840Y468699D01*
Y450161D01*
X1075841Y450160D01*
X1132380D01*
G01X1013935Y491929D02*
Y494429D01*
X1014976D01*
X1015310Y494304D01*
X1015518Y494137D01*
X1015601Y493804D01*
X1015518Y493471D01*
X1015268Y493262D01*
X1014976Y493137D01*
X1013935D01*
G01X1014976D02*
X1015601Y491929D01*
G01X1017785D02*
X1017868Y492471D01*
X1017993Y492929D01*
X1018160Y493346D01*
X1018368Y493804D01*
X1018701Y494429D01*
X1017035D01*
G01X1019926Y491929D02*
X1020968Y494429D01*
X1022010Y491929D01*
G01X1021635Y492804D02*
X1020301D01*
G01X1023276Y494012D02*
X1023526Y494262D01*
X1023818Y494387D01*
X1024151Y494429D01*
X1024568Y494346D01*
X1024860Y494137D01*
X1024943Y493887D01*
X1024901Y493637D01*
X1024735Y493429D01*
X1023901Y493012D01*
X1023526Y492721D01*
X1023276Y492304D01*
X1023193Y491929D01*
X1024943D01*
G01X1027168Y494429D02*
X1026835Y494346D01*
X1026585Y494137D01*
X1026418Y493887D01*
X1026293Y493554D01*
X1026251Y493179D01*
X1026293Y492804D01*
X1026418Y492471D01*
X1026585Y492221D01*
X1026835Y492012D01*
X1027168Y491929D01*
X1027501Y492012D01*
X1027751Y492221D01*
X1027918Y492471D01*
X1028043Y492804D01*
X1028085Y493179D01*
X1028043Y493554D01*
X1027918Y493887D01*
X1027751Y494137D01*
X1027501Y494346D01*
X1027168Y494429D01*
G01X1011185Y484628D02*
Y487128D01*
X1012226D01*
X1012560Y487003D01*
X1012768Y486836D01*
X1012851Y486503D01*
X1012768Y486170D01*
X1012518Y485961D01*
X1012226Y485836D01*
X1011185D01*
G01X1012226D02*
X1012851Y484628D01*
G01X1015118Y487128D02*
Y484628D01*
G01X1014160Y487128D02*
X1016076D01*
G01X1017301Y485128D02*
X1017551Y484836D01*
X1017885Y484670D01*
X1018260Y484628D01*
X1018593Y484670D01*
X1018926Y484878D01*
X1019135Y485128D01*
X1019176Y485378D01*
X1019093Y485670D01*
X1018801Y485878D01*
X1018510Y485961D01*
X1018135D01*
G01X1018510D02*
X1018760Y486086D01*
X1018968Y486295D01*
X1019051Y486545D01*
X1018968Y486795D01*
X1018760Y487003D01*
X1018385Y487128D01*
X1018010Y487086D01*
X1017635Y486920D01*
G01X1021318Y487128D02*
X1020985Y487045D01*
X1020735Y486836D01*
X1020568Y486586D01*
X1020443Y486253D01*
X1020401Y485878D01*
X1020443Y485503D01*
X1020568Y485170D01*
X1020735Y484920D01*
X1020985Y484711D01*
X1021318Y484628D01*
X1021651Y484711D01*
X1021901Y484920D01*
X1022068Y485170D01*
X1022193Y485503D01*
X1022235Y485878D01*
X1022193Y486253D01*
X1022068Y486586D01*
X1021901Y486836D01*
X1021651Y487045D01*
X1021318Y487128D01*
G01X990709Y487029D02*
X990584Y486779D01*
X990501Y486487D01*
Y486154D01*
X990626Y485779D01*
X990834Y485487D01*
X991084Y485279D01*
X991501Y485112D01*
X991876Y485070D01*
X992251Y485154D01*
X992501Y485279D01*
X992751Y485529D01*
X992918Y485820D01*
X993001Y486112D01*
Y486404D01*
X992918Y486695D01*
X992793Y486945D01*
X992626Y487154D01*
G01X990501Y489212D02*
X993001D01*
G01X990501Y488254D02*
Y490170D01*
G01X993001Y492812D02*
X990501D01*
X992293Y491270D01*
Y493354D01*
G01X993001Y495912D02*
X990501D01*
X992293Y494370D01*
Y496454D01*
G01X1011935Y498621D02*
X1011685Y498746D01*
X1011393Y498829D01*
X1011060D01*
X1010685Y498704D01*
X1010393Y498496D01*
X1010185Y498246D01*
X1010018Y497829D01*
X1009976Y497454D01*
X1010060Y497079D01*
X1010185Y496829D01*
X1010435Y496579D01*
X1010726Y496412D01*
X1011018Y496329D01*
X1011310D01*
X1011601Y496412D01*
X1011851Y496537D01*
X1012060Y496704D01*
G01X1014118Y498829D02*
Y496329D01*
G01X1013160Y498829D02*
X1015076D01*
G01X1017718Y496329D02*
Y498829D01*
X1016176Y497037D01*
X1018260D01*
G01X1019401Y496704D02*
X1019651Y496496D01*
X1019943Y496371D01*
X1020318Y496329D01*
X1020693Y496412D01*
X1020985Y496579D01*
X1021193Y496871D01*
X1021235Y497204D01*
X1021151Y497537D01*
X1020943Y497746D01*
X1020651Y497912D01*
X1020360Y497954D01*
X1020068Y497912D01*
X1019693Y497746D01*
X1019818Y498829D01*
X1020943D01*
G01X1012285Y482220D02*
X1012035Y482345D01*
X1011743Y482428D01*
X1011410D01*
X1011035Y482303D01*
X1010743Y482095D01*
X1010535Y481845D01*
X1010368Y481428D01*
X1010326Y481053D01*
X1010410Y480678D01*
X1010535Y480428D01*
X1010785Y480178D01*
X1011076Y480011D01*
X1011368Y479928D01*
X1011660D01*
X1011951Y480011D01*
X1012201Y480136D01*
X1012410Y480303D01*
G01X1014385Y479928D02*
X1014468Y480470D01*
X1014593Y480928D01*
X1014760Y481345D01*
X1014968Y481803D01*
X1015301Y482428D01*
X1013635D01*
G01X1016526Y479928D02*
X1017568Y482428D01*
X1018610Y479928D01*
G01X1018235Y480803D02*
X1016901D01*
G01X1020668Y479928D02*
Y482428D01*
X1020168Y481928D01*
G01Y479928D02*
X1021168D01*
G01X1022976Y482011D02*
X1023226Y482261D01*
X1023518Y482386D01*
X1023851Y482428D01*
X1024268Y482345D01*
X1024560Y482136D01*
X1024643Y481886D01*
X1024601Y481636D01*
X1024435Y481428D01*
X1023601Y481011D01*
X1023226Y480720D01*
X1022976Y480303D01*
X1022893Y479928D01*
X1024643D01*
G01X997985Y473911D02*
X997735Y474036D01*
X997443Y474119D01*
X997110D01*
X996735Y473994D01*
X996443Y473786D01*
X996235Y473536D01*
X996068Y473119D01*
X996026Y472744D01*
X996110Y472369D01*
X996235Y472119D01*
X996485Y471869D01*
X996776Y471702D01*
X997068Y471619D01*
X997360D01*
X997651Y471702D01*
X997901Y471827D01*
X998110Y471994D01*
G01X1000085Y471619D02*
X1000168Y472161D01*
X1000293Y472619D01*
X1000460Y473036D01*
X1000668Y473494D01*
X1001001Y474119D01*
X999335D01*
G01X1002226Y471619D02*
X1003268Y474119D01*
X1004310Y471619D01*
G01X1003935Y472494D02*
X1002601D01*
G01X1005576Y473702D02*
X1005826Y473952D01*
X1006118Y474077D01*
X1006451Y474119D01*
X1006868Y474036D01*
X1007160Y473827D01*
X1007243Y473577D01*
X1007201Y473327D01*
X1007035Y473119D01*
X1006201Y472702D01*
X1005826Y472411D01*
X1005576Y471994D01*
X1005493Y471619D01*
X1007243D01*
G01X1009968D02*
Y474119D01*
X1008426Y472327D01*
X1010510D01*
G01X981285Y473611D02*
X981035Y473736D01*
X980743Y473819D01*
X980410D01*
X980035Y473694D01*
X979743Y473486D01*
X979535Y473236D01*
X979368Y472819D01*
X979326Y472444D01*
X979410Y472069D01*
X979535Y471819D01*
X979785Y471569D01*
X980076Y471402D01*
X980368Y471319D01*
X980660D01*
X980951Y471402D01*
X981201Y471527D01*
X981410Y471694D01*
G01X983385Y471319D02*
X983468Y471861D01*
X983593Y472319D01*
X983760Y472736D01*
X983968Y473194D01*
X984301Y473819D01*
X982635D01*
G01X985526Y471319D02*
X986568Y473819D01*
X987610Y471319D01*
G01X987235Y472194D02*
X985901D01*
G01X988876Y473402D02*
X989126Y473652D01*
X989418Y473777D01*
X989751Y473819D01*
X990168Y473736D01*
X990460Y473527D01*
X990543Y473277D01*
X990501Y473027D01*
X990335Y472819D01*
X989501Y472402D01*
X989126Y472111D01*
X988876Y471694D01*
X988793Y471319D01*
X990543D01*
G01X991851Y471694D02*
X992101Y471486D01*
X992393Y471361D01*
X992768Y471319D01*
X993143Y471402D01*
X993435Y471569D01*
X993643Y471861D01*
X993685Y472194D01*
X993601Y472527D01*
X993393Y472736D01*
X993101Y472902D01*
X992810Y472944D01*
X992518Y472902D01*
X992143Y472736D01*
X992268Y473819D01*
X993393D01*
G01X981735Y477821D02*
X981485Y477946D01*
X981193Y478029D01*
X980860D01*
X980485Y477904D01*
X980193Y477696D01*
X979985Y477446D01*
X979818Y477029D01*
X979776Y476654D01*
X979860Y476279D01*
X979985Y476029D01*
X980235Y475779D01*
X980526Y475612D01*
X980818Y475529D01*
X981110D01*
X981401Y475612D01*
X981651Y475737D01*
X981860Y475904D01*
G01X983835Y475529D02*
X983918Y476071D01*
X984043Y476529D01*
X984210Y476946D01*
X984418Y477404D01*
X984751Y478029D01*
X983085D01*
G01X985976Y475529D02*
X987018Y478029D01*
X988060Y475529D01*
G01X987685Y476404D02*
X986351D01*
G01X989201Y475904D02*
X989451Y475696D01*
X989743Y475571D01*
X990118Y475529D01*
X990493Y475612D01*
X990785Y475779D01*
X990993Y476071D01*
X991035Y476404D01*
X990951Y476737D01*
X990743Y476946D01*
X990451Y477112D01*
X990160Y477154D01*
X989868Y477112D01*
X989493Y476946D01*
X989618Y478029D01*
X990743D01*
G01X1000109Y486579D02*
X999984Y486329D01*
X999901Y486037D01*
Y485704D01*
X1000026Y485329D01*
X1000234Y485037D01*
X1000484Y484829D01*
X1000901Y484662D01*
X1001276Y484620D01*
X1001651Y484704D01*
X1001901Y484829D01*
X1002151Y485079D01*
X1002318Y485370D01*
X1002401Y485662D01*
Y485954D01*
X1002318Y486245D01*
X1002193Y486495D01*
X1002026Y486704D01*
G01X1002401Y488679D02*
X1001859Y488762D01*
X1001401Y488887D01*
X1000984Y489054D01*
X1000526Y489262D01*
X999901Y489595D01*
Y487929D01*
G01X1002401Y490820D02*
X999901Y491862D01*
X1002401Y492904D01*
G01X1001526Y492529D02*
Y491195D01*
G01X1002401Y494962D02*
X999901D01*
X1000401Y494462D01*
G01X1002401D02*
Y495462D01*
G01Y497979D02*
X1001859Y498062D01*
X1001401Y498187D01*
X1000984Y498354D01*
X1000526Y498562D01*
X999901Y498895D01*
Y497229D01*
G01X1004109Y486279D02*
X1003984Y486029D01*
X1003901Y485737D01*
Y485404D01*
X1004026Y485029D01*
X1004234Y484737D01*
X1004484Y484529D01*
X1004901Y484362D01*
X1005276Y484320D01*
X1005651Y484404D01*
X1005901Y484529D01*
X1006151Y484779D01*
X1006318Y485070D01*
X1006401Y485362D01*
Y485654D01*
X1006318Y485945D01*
X1006193Y486195D01*
X1006026Y486404D01*
G01X1006401Y488379D02*
X1005859Y488462D01*
X1005401Y488587D01*
X1004984Y488754D01*
X1004526Y488962D01*
X1003901Y489295D01*
Y487629D01*
G01X1006401Y490520D02*
X1003901Y491562D01*
X1006401Y492604D01*
G01X1005526Y492229D02*
Y490895D01*
G01X1006401Y494662D02*
X1003901D01*
X1004401Y494162D01*
G01X1006401D02*
Y495162D01*
G01X1005359Y496970D02*
X1005068Y497262D01*
X1004901Y497512D01*
X1004818Y497845D01*
X1004901Y498137D01*
X1005068Y498345D01*
X1005318Y498512D01*
X1005609Y498554D01*
X1005859Y498512D01*
X1006109Y498345D01*
X1006318Y498095D01*
X1006401Y497804D01*
X1006318Y497470D01*
X1006068Y497179D01*
X1005693Y497012D01*
X1005276Y496970D01*
X1004734Y497054D01*
X1004443Y497179D01*
X1004151Y497387D01*
X1003943Y497679D01*
X1003901Y497970D01*
X1003984Y498262D01*
X1004193Y498470D01*
G01X1032142Y495631D02*
X1031892Y495756D01*
X1031600Y495839D01*
X1031267D01*
X1030892Y495714D01*
X1030600Y495506D01*
X1030392Y495256D01*
X1030225Y494839D01*
X1030183Y494464D01*
X1030267Y494089D01*
X1030392Y493839D01*
X1030642Y493589D01*
X1030933Y493422D01*
X1031225Y493339D01*
X1031517D01*
X1031808Y493422D01*
X1032058Y493547D01*
X1032267Y493714D01*
G01X1034325Y495839D02*
Y493339D01*
G01X1033367Y495839D02*
X1035283D01*
G01X1036633Y494381D02*
X1036925Y494672D01*
X1037175Y494839D01*
X1037508Y494922D01*
X1037800Y494839D01*
X1038008Y494672D01*
X1038175Y494422D01*
X1038217Y494131D01*
X1038175Y493881D01*
X1038008Y493631D01*
X1037758Y493422D01*
X1037467Y493339D01*
X1037133Y493422D01*
X1036842Y493672D01*
X1036675Y494047D01*
X1036633Y494464D01*
X1036717Y495006D01*
X1036842Y495297D01*
X1037050Y495589D01*
X1037342Y495797D01*
X1037633Y495839D01*
X1037925Y495756D01*
X1038133Y495547D01*
G01X1039733Y494381D02*
X1040025Y494672D01*
X1040275Y494839D01*
X1040608Y494922D01*
X1040900Y494839D01*
X1041108Y494672D01*
X1041275Y494422D01*
X1041317Y494131D01*
X1041275Y493881D01*
X1041108Y493631D01*
X1040858Y493422D01*
X1040567Y493339D01*
X1040233Y493422D01*
X1039942Y493672D01*
X1039775Y494047D01*
X1039733Y494464D01*
X1039817Y495006D01*
X1039942Y495297D01*
X1040150Y495589D01*
X1040442Y495797D01*
X1040733Y495839D01*
X1041025Y495756D01*
X1041233Y495547D01*
G01X1012285Y478021D02*
X1012035Y478146D01*
X1011743Y478229D01*
X1011410D01*
X1011035Y478104D01*
X1010743Y477896D01*
X1010535Y477646D01*
X1010368Y477229D01*
X1010326Y476854D01*
X1010410Y476479D01*
X1010535Y476229D01*
X1010785Y475979D01*
X1011076Y475812D01*
X1011368Y475729D01*
X1011660D01*
X1011951Y475812D01*
X1012201Y475937D01*
X1012410Y476104D01*
G01X1014385Y475729D02*
X1014468Y476271D01*
X1014593Y476729D01*
X1014760Y477146D01*
X1014968Y477604D01*
X1015301Y478229D01*
X1013635D01*
G01X1016526Y475729D02*
X1017568Y478229D01*
X1018610Y475729D01*
G01X1018235Y476604D02*
X1016901D01*
G01X1020668Y475729D02*
Y478229D01*
X1020168Y477729D01*
G01Y475729D02*
X1021168D01*
G01X1023768D02*
Y478229D01*
X1023268Y477729D01*
G01Y475729D02*
X1024268D01*
G01X1019475Y514677D02*
X1019552Y515349D01*
X1019667Y515917D01*
X1019820Y516434D01*
X1020012Y517002D01*
X1020319Y517777D01*
X1018785D01*
G01X1022575Y514677D02*
X1022652Y515349D01*
X1022767Y515917D01*
X1022920Y516434D01*
X1023112Y517002D01*
X1023419Y517777D01*
X1021885D01*
G01X1024370Y504709D02*
X1024245Y504459D01*
X1024162Y504167D01*
Y503834D01*
X1024287Y503459D01*
X1024495Y503167D01*
X1024745Y502959D01*
X1025162Y502792D01*
X1025537Y502750D01*
X1025912Y502834D01*
X1026162Y502959D01*
X1026412Y503209D01*
X1026579Y503500D01*
X1026662Y503792D01*
Y504084D01*
X1026579Y504375D01*
X1026454Y504625D01*
X1026287Y504834D01*
G01Y505975D02*
X1026495Y506225D01*
X1026620Y506517D01*
X1026662Y506892D01*
X1026579Y507267D01*
X1026412Y507559D01*
X1026120Y507767D01*
X1025787Y507809D01*
X1025454Y507725D01*
X1025245Y507517D01*
X1025079Y507225D01*
X1025037Y506934D01*
X1025079Y506642D01*
X1025245Y506267D01*
X1024162Y506392D01*
Y507517D01*
G01X1025329Y510325D02*
X1025204Y510492D01*
X1024995Y510617D01*
X1024704Y510700D01*
X1024454Y510617D01*
X1024287Y510450D01*
X1024162Y510159D01*
Y509034D01*
X1026662D01*
Y510409D01*
X1026495Y510700D01*
X1026245Y510867D01*
X1025954Y510950D01*
X1025662Y510867D01*
X1025412Y510617D01*
X1025329Y510325D01*
Y509034D01*
G01X1026662Y513092D02*
X1024162D01*
X1024662Y512592D01*
G01X1026662D02*
Y513592D01*
G01X996901Y485279D02*
X994401D01*
Y486320D01*
X994526Y486654D01*
X994693Y486862D01*
X995026Y486945D01*
X995359Y486862D01*
X995568Y486612D01*
X995693Y486320D01*
Y485279D01*
G01Y486320D02*
X996901Y486945D01*
G01X994401Y489212D02*
X996901D01*
G01X994401Y488254D02*
Y490170D01*
G01X994818Y491520D02*
X994568Y491770D01*
X994443Y492062D01*
X994401Y492395D01*
X994484Y492812D01*
X994693Y493104D01*
X994943Y493187D01*
X995193Y493145D01*
X995401Y492979D01*
X995818Y492145D01*
X996109Y491770D01*
X996526Y491520D01*
X996901Y491437D01*
Y493187D01*
G01X996609Y494704D02*
X996818Y494995D01*
X996901Y495329D01*
X996818Y495662D01*
X996568Y495954D01*
X996193Y496162D01*
X995818Y496245D01*
X995359D01*
X994984Y496162D01*
X994651Y495954D01*
X994484Y495704D01*
X994401Y495412D01*
X994484Y495079D01*
X994651Y494829D01*
X994901Y494662D01*
X995234Y494579D01*
X995526Y494662D01*
X995818Y494870D01*
X995984Y495120D01*
X996026Y495412D01*
X995943Y495745D01*
X995734Y495995D01*
X995359Y496245D01*
G01X1030255Y475629D02*
X1030130Y475379D01*
X1030047Y475087D01*
Y474754D01*
X1030172Y474379D01*
X1030380Y474087D01*
X1030630Y473879D01*
X1031047Y473712D01*
X1031422Y473670D01*
X1031797Y473754D01*
X1032047Y473879D01*
X1032297Y474129D01*
X1032464Y474420D01*
X1032547Y474712D01*
Y475004D01*
X1032464Y475295D01*
X1032339Y475545D01*
X1032172Y475754D01*
G01X1030464Y477020D02*
X1030214Y477270D01*
X1030089Y477562D01*
X1030047Y477895D01*
X1030130Y478312D01*
X1030339Y478604D01*
X1030589Y478687D01*
X1030839Y478645D01*
X1031047Y478479D01*
X1031464Y477645D01*
X1031755Y477270D01*
X1032172Y477020D01*
X1032547Y476937D01*
Y478687D01*
G01X1030464Y480120D02*
X1030214Y480370D01*
X1030089Y480662D01*
X1030047Y480995D01*
X1030130Y481412D01*
X1030339Y481704D01*
X1030589Y481787D01*
X1030839Y481745D01*
X1031047Y481579D01*
X1031464Y480745D01*
X1031755Y480370D01*
X1032172Y480120D01*
X1032547Y480037D01*
Y481787D01*
G01X1030047Y482762D02*
X1032547Y483345D01*
X1030047Y484012D01*
X1032547Y484679D01*
X1030047Y485262D01*
G01X1030464Y486320D02*
X1030214Y486570D01*
X1030089Y486862D01*
X1030047Y487195D01*
X1030130Y487612D01*
X1030339Y487904D01*
X1030589Y487987D01*
X1030839Y487945D01*
X1031047Y487779D01*
X1031464Y486945D01*
X1031755Y486570D01*
X1032172Y486320D01*
X1032547Y486237D01*
Y487987D01*
G01X1032172Y489295D02*
X1032380Y489545D01*
X1032505Y489837D01*
X1032547Y490212D01*
X1032464Y490587D01*
X1032297Y490879D01*
X1032005Y491087D01*
X1031672Y491129D01*
X1031339Y491045D01*
X1031130Y490837D01*
X1030964Y490545D01*
X1030922Y490254D01*
X1030964Y489962D01*
X1031130Y489587D01*
X1030047Y489712D01*
Y490837D01*
G01X1026755Y475629D02*
X1026630Y475379D01*
X1026547Y475087D01*
Y474754D01*
X1026672Y474379D01*
X1026880Y474087D01*
X1027130Y473879D01*
X1027547Y473712D01*
X1027922Y473670D01*
X1028297Y473754D01*
X1028547Y473879D01*
X1028797Y474129D01*
X1028964Y474420D01*
X1029047Y474712D01*
Y475004D01*
X1028964Y475295D01*
X1028839Y475545D01*
X1028672Y475754D01*
G01X1029047Y477729D02*
X1028505Y477812D01*
X1028047Y477937D01*
X1027630Y478104D01*
X1027172Y478312D01*
X1026547Y478645D01*
Y476979D01*
G01X1029047Y479870D02*
X1026547Y480912D01*
X1029047Y481954D01*
G01X1028172Y481579D02*
Y480245D01*
G01X1029047Y484012D02*
X1026547D01*
X1027047Y483512D01*
G01X1029047D02*
Y484512D01*
G01X1028547Y486195D02*
X1028839Y486445D01*
X1029005Y486779D01*
X1029047Y487154D01*
X1029005Y487487D01*
X1028797Y487820D01*
X1028547Y488029D01*
X1028297Y488070D01*
X1028005Y487987D01*
X1027797Y487695D01*
X1027714Y487404D01*
Y487029D01*
G01Y487404D02*
X1027589Y487654D01*
X1027380Y487862D01*
X1027130Y487945D01*
X1026880Y487862D01*
X1026672Y487654D01*
X1026547Y487279D01*
X1026589Y486904D01*
X1026755Y486529D01*
G01X980301Y479429D02*
X978635D01*
Y481929D01*
X980301D01*
G01X979635Y480721D02*
X978635D01*
G01X981651Y481929D02*
Y480137D01*
X981818Y479762D01*
X982151Y479512D01*
X982568Y479429D01*
X982985Y479512D01*
X983318Y479762D01*
X983485Y480137D01*
Y481929D01*
G01X985585Y479429D02*
X985668Y479971D01*
X985793Y480429D01*
X985960Y480846D01*
X986168Y481304D01*
X986501Y481929D01*
X984835D01*
G01X987726Y479429D02*
X988768Y481929D01*
X989810Y479429D01*
G01X989435Y480304D02*
X988101D01*
G01X991868Y479429D02*
Y481929D01*
X991368Y481429D01*
G01Y479429D02*
X992368D01*
G01X1002217Y548959D02*
X1001967Y549084D01*
X1001675Y549167D01*
X1001342D01*
X1000967Y549042D01*
X1000675Y548834D01*
X1000467Y548584D01*
X1000300Y548167D01*
X1000258Y547792D01*
X1000342Y547417D01*
X1000467Y547167D01*
X1000717Y546917D01*
X1001008Y546750D01*
X1001300Y546667D01*
X1001592D01*
X1001883Y546750D01*
X1002133Y546875D01*
X1002342Y547042D01*
G01X1003483D02*
X1003733Y546834D01*
X1004025Y546709D01*
X1004400Y546667D01*
X1004775Y546750D01*
X1005067Y546917D01*
X1005275Y547209D01*
X1005317Y547542D01*
X1005233Y547875D01*
X1005025Y548084D01*
X1004733Y548250D01*
X1004442Y548292D01*
X1004150Y548250D01*
X1003775Y548084D01*
X1003900Y549167D01*
X1005025D01*
G01X1006458Y546667D02*
X1007500Y549167D01*
X1008542Y546667D01*
G01X1008167Y547542D02*
X1006833D01*
G01X1009808Y548750D02*
X1010058Y549000D01*
X1010350Y549125D01*
X1010683Y549167D01*
X1011100Y549084D01*
X1011392Y548875D01*
X1011475Y548625D01*
X1011433Y548375D01*
X1011267Y548167D01*
X1010433Y547750D01*
X1010058Y547459D01*
X1009808Y547042D01*
X1009725Y546667D01*
X1011475D01*
G01X1013700Y549167D02*
X1013367Y549084D01*
X1013117Y548875D01*
X1012950Y548625D01*
X1012825Y548292D01*
X1012783Y547917D01*
X1012825Y547542D01*
X1012950Y547209D01*
X1013117Y546959D01*
X1013367Y546750D01*
X1013700Y546667D01*
X1014033Y546750D01*
X1014283Y546959D01*
X1014450Y547209D01*
X1014575Y547542D01*
X1014617Y547917D01*
X1014575Y548292D01*
X1014450Y548625D01*
X1014283Y548875D01*
X1014033Y549084D01*
X1013700Y549167D01*
G01X1023009Y554244D02*
X1023086Y554916D01*
X1023201Y555484D01*
X1023354Y556001D01*
X1023546Y556569D01*
X1023853Y557344D01*
X1022319D01*
G01X1026109Y554244D02*
X1026186Y554916D01*
X1026301Y555484D01*
X1026454Y556001D01*
X1026646Y556569D01*
X1026953Y557344D01*
X1025419D01*
G01X1023233Y585972D02*
X1023463Y586282D01*
X1023731Y586437D01*
X1024038Y586489D01*
X1024421Y586386D01*
X1024689Y586127D01*
X1024766Y585817D01*
X1024728Y585507D01*
X1024574Y585249D01*
X1023808Y584732D01*
X1023463Y584371D01*
X1023233Y583854D01*
X1023156Y583389D01*
X1024766D01*
G01X1026333Y585972D02*
X1026563Y586282D01*
X1026831Y586437D01*
X1027138Y586489D01*
X1027521Y586386D01*
X1027789Y586127D01*
X1027866Y585817D01*
X1027828Y585507D01*
X1027674Y585249D01*
X1026908Y584732D01*
X1026563Y584371D01*
X1026333Y583854D01*
X1026256Y583389D01*
X1027866D01*
G01X1030161D02*
Y586489D01*
X1029701Y585869D01*
G01Y583389D02*
X1030621D01*
G01X1023924Y546660D02*
X1024154Y546970D01*
X1024422Y547125D01*
X1024729Y547177D01*
X1025112Y547074D01*
X1025380Y546815D01*
X1025457Y546505D01*
X1025419Y546195D01*
X1025265Y545937D01*
X1024499Y545420D01*
X1024154Y545059D01*
X1023924Y544542D01*
X1023847Y544077D01*
X1025457D01*
G01X1027024Y546660D02*
X1027254Y546970D01*
X1027522Y547125D01*
X1027829Y547177D01*
X1028212Y547074D01*
X1028480Y546815D01*
X1028557Y546505D01*
X1028519Y546195D01*
X1028365Y545937D01*
X1027599Y545420D01*
X1027254Y545059D01*
X1027024Y544542D01*
X1026947Y544077D01*
X1028557D01*
G01X1030852D02*
Y547177D01*
X1030392Y546557D01*
G01Y544077D02*
X1031312D01*
G01X985517Y549158D02*
X985267Y549283D01*
X984975Y549366D01*
X984642D01*
X984267Y549241D01*
X983975Y549033D01*
X983767Y548783D01*
X983600Y548366D01*
X983558Y547991D01*
X983642Y547616D01*
X983767Y547366D01*
X984017Y547116D01*
X984308Y546949D01*
X984600Y546866D01*
X984892D01*
X985183Y546949D01*
X985433Y547074D01*
X985642Y547241D01*
G01X986783D02*
X987033Y547033D01*
X987325Y546908D01*
X987700Y546866D01*
X988075Y546949D01*
X988367Y547116D01*
X988575Y547408D01*
X988617Y547741D01*
X988533Y548074D01*
X988325Y548283D01*
X988033Y548449D01*
X987742Y548491D01*
X987450Y548449D01*
X987075Y548283D01*
X987200Y549366D01*
X988325D01*
G01X989758Y546866D02*
X990800Y549366D01*
X991842Y546866D01*
G01X991467Y547741D02*
X990133D01*
G01X993900Y546866D02*
Y549366D01*
X993400Y548866D01*
G01Y546866D02*
X994400D01*
G01X996083Y547241D02*
X996333Y547033D01*
X996625Y546908D01*
X997000Y546866D01*
X997375Y546949D01*
X997667Y547116D01*
X997875Y547408D01*
X997917Y547741D01*
X997833Y548074D01*
X997625Y548283D01*
X997333Y548449D01*
X997042Y548491D01*
X996750Y548449D01*
X996375Y548283D01*
X996500Y549366D01*
X997625D01*
G01X1029961Y591857D02*
X1030038Y592529D01*
X1030153Y593097D01*
X1030306Y593614D01*
X1030498Y594182D01*
X1030805Y594957D01*
X1029271D01*
G01X1033061Y591857D02*
X1033138Y592529D01*
X1033253Y593097D01*
X1033406Y593614D01*
X1033598Y594182D01*
X1033905Y594957D01*
X1032371D01*
G01X1015524Y624860D02*
X1015754Y625170D01*
X1016022Y625325D01*
X1016329Y625377D01*
X1016712Y625274D01*
X1016980Y625015D01*
X1017057Y624705D01*
X1017019Y624395D01*
X1016865Y624137D01*
X1016099Y623620D01*
X1015754Y623259D01*
X1015524Y622742D01*
X1015447Y622277D01*
X1017057D01*
G01X1018624Y624860D02*
X1018854Y625170D01*
X1019122Y625325D01*
X1019429Y625377D01*
X1019812Y625274D01*
X1020080Y625015D01*
X1020157Y624705D01*
X1020119Y624395D01*
X1019965Y624137D01*
X1019199Y623620D01*
X1018854Y623259D01*
X1018624Y622742D01*
X1018547Y622277D01*
X1020157D01*
G01X1022452D02*
Y625377D01*
X1021992Y624757D01*
G01Y622277D02*
X1022912D01*
G01X1041575Y-22500D02*
X1041652Y-21828D01*
X1041767Y-21260D01*
X1041920Y-20743D01*
X1042112Y-20175D01*
X1042419Y-19400D01*
X1040885D01*
G01X1044752Y-22500D02*
X1045020Y-22448D01*
X1045327Y-22293D01*
X1045519Y-22035D01*
X1045595Y-21673D01*
X1045519Y-21312D01*
X1045289Y-21002D01*
X1044944Y-20847D01*
X1044560D01*
X1044330Y-20743D01*
X1044139Y-20485D01*
X1044062Y-20123D01*
X1044177Y-19762D01*
X1044445Y-19503D01*
X1044752Y-19400D01*
X1045059Y-19503D01*
X1045327Y-19762D01*
X1045442Y-20123D01*
X1045365Y-20485D01*
X1045174Y-20743D01*
X1044944Y-20847D01*
X1044560D01*
X1044215Y-21002D01*
X1043985Y-21312D01*
X1043909Y-21673D01*
X1043985Y-22035D01*
X1044177Y-22293D01*
X1044484Y-22448D01*
X1044752Y-22500D01*
G01X1041424Y10083D02*
X1041654Y10393D01*
X1041922Y10548D01*
X1042229Y10600D01*
X1042612Y10497D01*
X1042880Y10238D01*
X1042957Y9928D01*
X1042919Y9618D01*
X1042765Y9360D01*
X1041999Y8843D01*
X1041654Y8482D01*
X1041424Y7965D01*
X1041347Y7500D01*
X1042957D01*
G01X1044524Y10083D02*
X1044754Y10393D01*
X1045022Y10548D01*
X1045329Y10600D01*
X1045712Y10497D01*
X1045980Y10238D01*
X1046057Y9928D01*
X1046019Y9618D01*
X1045865Y9360D01*
X1045099Y8843D01*
X1044754Y8482D01*
X1044524Y7965D01*
X1044447Y7500D01*
X1046057D01*
G01X1047624Y10083D02*
X1047854Y10393D01*
X1048122Y10548D01*
X1048429Y10600D01*
X1048812Y10497D01*
X1049080Y10238D01*
X1049157Y9928D01*
X1049119Y9618D01*
X1048965Y9360D01*
X1048199Y8843D01*
X1047854Y8482D01*
X1047624Y7965D01*
X1047547Y7500D01*
X1049157D01*
G01X1042075Y15000D02*
X1042152Y15672D01*
X1042267Y16240D01*
X1042420Y16757D01*
X1042612Y17325D01*
X1042919Y18100D01*
X1041385D01*
G01X1045252Y15000D02*
X1045520Y15052D01*
X1045827Y15207D01*
X1046019Y15465D01*
X1046095Y15827D01*
X1046019Y16188D01*
X1045789Y16498D01*
X1045444Y16653D01*
X1045060D01*
X1044830Y16757D01*
X1044639Y17015D01*
X1044562Y17377D01*
X1044677Y17738D01*
X1044945Y17997D01*
X1045252Y18100D01*
X1045559Y17997D01*
X1045827Y17738D01*
X1045942Y17377D01*
X1045865Y17015D01*
X1045674Y16757D01*
X1045444Y16653D01*
X1045060D01*
X1044715Y16498D01*
X1044485Y16188D01*
X1044409Y15827D01*
X1044485Y15465D01*
X1044677Y15207D01*
X1044984Y15052D01*
X1045252Y15000D01*
G01X1097217Y17958D02*
X1096967Y18083D01*
X1096675Y18166D01*
X1096342D01*
X1095967Y18041D01*
X1095675Y17833D01*
X1095467Y17583D01*
X1095300Y17166D01*
X1095258Y16791D01*
X1095342Y16416D01*
X1095467Y16166D01*
X1095717Y15916D01*
X1096008Y15749D01*
X1096300Y15666D01*
X1096592D01*
X1096883Y15749D01*
X1097133Y15874D01*
X1097342Y16041D01*
G01X1098483D02*
X1098733Y15833D01*
X1099025Y15708D01*
X1099400Y15666D01*
X1099775Y15749D01*
X1100067Y15916D01*
X1100275Y16208D01*
X1100317Y16541D01*
X1100233Y16874D01*
X1100025Y17083D01*
X1099733Y17249D01*
X1099442Y17291D01*
X1099150Y17249D01*
X1098775Y17083D01*
X1098900Y18166D01*
X1100025D01*
G01X1102750Y16916D02*
X1103583D01*
Y16166D01*
X1103333Y15916D01*
X1103042Y15749D01*
X1102625Y15666D01*
X1102208Y15749D01*
X1101917Y15916D01*
X1101667Y16166D01*
X1101500Y16458D01*
X1101417Y16791D01*
Y17083D01*
X1101500Y17333D01*
X1101667Y17624D01*
X1101917Y17874D01*
X1102167Y18041D01*
X1102500Y18166D01*
X1102792D01*
X1103125Y18083D01*
X1103375Y17916D01*
G01X1105600Y15666D02*
Y18166D01*
X1105100Y17666D01*
G01Y15666D02*
X1106100D01*
G01X1107783Y16041D02*
X1108033Y15833D01*
X1108325Y15708D01*
X1108700Y15666D01*
X1109075Y15749D01*
X1109367Y15916D01*
X1109575Y16208D01*
X1109617Y16541D01*
X1109533Y16874D01*
X1109325Y17083D01*
X1109033Y17249D01*
X1108742Y17291D01*
X1108450Y17249D01*
X1108075Y17083D01*
X1108200Y18166D01*
X1109325D01*
G01X1042075Y53000D02*
X1042152Y53672D01*
X1042267Y54240D01*
X1042420Y54757D01*
X1042612Y55325D01*
X1042919Y56100D01*
X1041385D01*
G01X1045252Y53000D02*
X1045520Y53052D01*
X1045827Y53207D01*
X1046019Y53465D01*
X1046095Y53827D01*
X1046019Y54188D01*
X1045789Y54498D01*
X1045444Y54653D01*
X1045060D01*
X1044830Y54757D01*
X1044639Y55015D01*
X1044562Y55377D01*
X1044677Y55738D01*
X1044945Y55997D01*
X1045252Y56100D01*
X1045559Y55997D01*
X1045827Y55738D01*
X1045942Y55377D01*
X1045865Y55015D01*
X1045674Y54757D01*
X1045444Y54653D01*
X1045060D01*
X1044715Y54498D01*
X1044485Y54188D01*
X1044409Y53827D01*
X1044485Y53465D01*
X1044677Y53207D01*
X1044984Y53052D01*
X1045252Y53000D01*
G01X1042424Y86083D02*
X1042654Y86393D01*
X1042922Y86548D01*
X1043229Y86600D01*
X1043612Y86497D01*
X1043880Y86238D01*
X1043957Y85928D01*
X1043919Y85618D01*
X1043765Y85360D01*
X1042999Y84843D01*
X1042654Y84482D01*
X1042424Y83965D01*
X1042347Y83500D01*
X1043957D01*
G01X1045524Y86083D02*
X1045754Y86393D01*
X1046022Y86548D01*
X1046329Y86600D01*
X1046712Y86497D01*
X1046980Y86238D01*
X1047057Y85928D01*
X1047019Y85618D01*
X1046865Y85360D01*
X1046099Y84843D01*
X1045754Y84482D01*
X1045524Y83965D01*
X1045447Y83500D01*
X1047057D01*
G01X1048624Y86083D02*
X1048854Y86393D01*
X1049122Y86548D01*
X1049429Y86600D01*
X1049812Y86497D01*
X1050080Y86238D01*
X1050157Y85928D01*
X1050119Y85618D01*
X1049965Y85360D01*
X1049199Y84843D01*
X1048854Y84482D01*
X1048624Y83965D01*
X1048547Y83500D01*
X1050157D01*
G01X1041424Y48083D02*
X1041654Y48393D01*
X1041922Y48548D01*
X1042229Y48600D01*
X1042612Y48497D01*
X1042880Y48238D01*
X1042957Y47928D01*
X1042919Y47618D01*
X1042765Y47360D01*
X1041999Y46843D01*
X1041654Y46482D01*
X1041424Y45965D01*
X1041347Y45500D01*
X1042957D01*
G01X1044524Y48083D02*
X1044754Y48393D01*
X1045022Y48548D01*
X1045329Y48600D01*
X1045712Y48497D01*
X1045980Y48238D01*
X1046057Y47928D01*
X1046019Y47618D01*
X1045865Y47360D01*
X1045099Y46843D01*
X1044754Y46482D01*
X1044524Y45965D01*
X1044447Y45500D01*
X1046057D01*
G01X1047624Y48083D02*
X1047854Y48393D01*
X1048122Y48548D01*
X1048429Y48600D01*
X1048812Y48497D01*
X1049080Y48238D01*
X1049157Y47928D01*
X1049119Y47618D01*
X1048965Y47360D01*
X1048199Y46843D01*
X1047854Y46482D01*
X1047624Y45965D01*
X1047547Y45500D01*
X1049157D01*
G01X1078080Y139307D02*
X1075580D01*
Y140348D01*
X1075705Y140682D01*
X1075872Y140890D01*
X1076205Y140973D01*
X1076538Y140890D01*
X1076747Y140640D01*
X1076872Y140348D01*
Y139307D01*
G01Y140348D02*
X1078080Y140973D01*
G01Y143240D02*
X1078038Y143532D01*
X1077913Y143865D01*
X1077705Y144073D01*
X1077413Y144157D01*
X1077122Y144073D01*
X1076872Y143823D01*
X1076747Y143448D01*
Y143032D01*
X1076663Y142782D01*
X1076455Y142573D01*
X1076163Y142490D01*
X1075872Y142615D01*
X1075663Y142907D01*
X1075580Y143240D01*
X1075663Y143573D01*
X1075872Y143865D01*
X1076163Y143990D01*
X1076455Y143907D01*
X1076663Y143698D01*
X1076747Y143448D01*
Y143032D01*
X1076872Y142657D01*
X1077122Y142407D01*
X1077413Y142323D01*
X1077705Y142407D01*
X1077913Y142615D01*
X1078038Y142948D01*
X1078080Y143240D01*
G01Y145423D02*
X1075580D01*
Y146257D01*
X1075705Y146590D01*
X1075872Y146840D01*
X1076122Y147048D01*
X1076413Y147215D01*
X1076830Y147257D01*
X1077247Y147215D01*
X1077538Y147048D01*
X1077788Y146840D01*
X1077955Y146590D01*
X1078080Y146257D01*
Y145423D01*
G01X1077705Y148523D02*
X1077913Y148773D01*
X1078038Y149065D01*
X1078080Y149440D01*
X1077997Y149815D01*
X1077830Y150107D01*
X1077538Y150315D01*
X1077205Y150357D01*
X1076872Y150273D01*
X1076663Y150065D01*
X1076497Y149773D01*
X1076455Y149482D01*
X1076497Y149190D01*
X1076663Y148815D01*
X1075580Y148940D01*
Y150065D01*
G01X1085280Y137207D02*
X1082780D01*
Y138248D01*
X1082905Y138582D01*
X1083072Y138790D01*
X1083405Y138873D01*
X1083738Y138790D01*
X1083947Y138540D01*
X1084072Y138248D01*
Y137207D01*
G01Y138248D02*
X1085280Y138873D01*
G01Y141057D02*
X1084738Y141140D01*
X1084280Y141265D01*
X1083863Y141432D01*
X1083405Y141640D01*
X1082780Y141973D01*
Y140307D01*
G01X1085280Y143323D02*
X1082780D01*
Y144157D01*
X1082905Y144490D01*
X1083072Y144740D01*
X1083322Y144948D01*
X1083613Y145115D01*
X1084030Y145157D01*
X1084447Y145115D01*
X1084738Y144948D01*
X1084988Y144740D01*
X1085155Y144490D01*
X1085280Y144157D01*
Y143323D01*
G01Y147340D02*
X1082780D01*
X1083280Y146840D01*
G01X1085280D02*
Y147840D01*
G01X1084988Y149732D02*
X1085197Y150023D01*
X1085280Y150357D01*
X1085197Y150690D01*
X1084947Y150982D01*
X1084572Y151190D01*
X1084197Y151273D01*
X1083738D01*
X1083363Y151190D01*
X1083030Y150982D01*
X1082863Y150732D01*
X1082780Y150440D01*
X1082863Y150107D01*
X1083030Y149857D01*
X1083280Y149690D01*
X1083613Y149607D01*
X1083905Y149690D01*
X1084197Y149898D01*
X1084363Y150148D01*
X1084405Y150440D01*
X1084322Y150773D01*
X1084113Y151023D01*
X1083738Y151273D01*
G01X1096380Y137207D02*
X1093880D01*
Y138248D01*
X1094005Y138582D01*
X1094172Y138790D01*
X1094505Y138873D01*
X1094838Y138790D01*
X1095047Y138540D01*
X1095172Y138248D01*
Y137207D01*
G01Y138248D02*
X1096380Y138873D01*
G01X1094297Y140348D02*
X1094047Y140598D01*
X1093922Y140890D01*
X1093880Y141223D01*
X1093963Y141640D01*
X1094172Y141932D01*
X1094422Y142015D01*
X1094672Y141973D01*
X1094880Y141807D01*
X1095297Y140973D01*
X1095588Y140598D01*
X1096005Y140348D01*
X1096380Y140265D01*
Y142015D01*
G01Y143282D02*
X1093880D01*
X1096380Y145198D01*
X1093880D01*
G01X1094297Y146548D02*
X1094047Y146798D01*
X1093922Y147090D01*
X1093880Y147423D01*
X1093963Y147840D01*
X1094172Y148132D01*
X1094422Y148215D01*
X1094672Y148173D01*
X1094880Y148007D01*
X1095297Y147173D01*
X1095588Y146798D01*
X1096005Y146548D01*
X1096380Y146465D01*
Y148215D01*
G01X1096005Y149523D02*
X1096213Y149773D01*
X1096338Y150065D01*
X1096380Y150440D01*
X1096297Y150815D01*
X1096130Y151107D01*
X1095838Y151315D01*
X1095505Y151357D01*
X1095172Y151273D01*
X1094963Y151065D01*
X1094797Y150773D01*
X1094755Y150482D01*
X1094797Y150190D01*
X1094963Y149815D01*
X1093880Y149940D01*
Y151065D01*
G01X1073058Y152571D02*
X1070558D01*
Y153612D01*
X1070683Y153946D01*
X1070850Y154154D01*
X1071183Y154237D01*
X1071516Y154154D01*
X1071725Y153904D01*
X1071850Y153612D01*
Y152571D01*
G01Y153612D02*
X1073058Y154237D01*
G01X1072558Y155587D02*
X1072850Y155837D01*
X1073016Y156171D01*
X1073058Y156546D01*
X1073016Y156879D01*
X1072808Y157212D01*
X1072558Y157421D01*
X1072308Y157462D01*
X1072016Y157379D01*
X1071808Y157087D01*
X1071725Y156796D01*
Y156421D01*
G01Y156796D02*
X1071600Y157046D01*
X1071391Y157254D01*
X1071141Y157337D01*
X1070891Y157254D01*
X1070683Y157046D01*
X1070558Y156671D01*
X1070600Y156296D01*
X1070766Y155921D01*
G01X1073058Y158771D02*
X1070558D01*
Y159771D01*
X1070683Y160104D01*
X1070975Y160354D01*
X1071308Y160437D01*
X1071641Y160354D01*
X1071891Y160146D01*
X1072016Y159771D01*
Y158771D01*
G01Y161912D02*
X1071725Y162204D01*
X1071558Y162454D01*
X1071475Y162787D01*
X1071558Y163079D01*
X1071725Y163287D01*
X1071975Y163454D01*
X1072266Y163496D01*
X1072516Y163454D01*
X1072766Y163287D01*
X1072975Y163037D01*
X1073058Y162746D01*
X1072975Y162412D01*
X1072725Y162121D01*
X1072350Y161954D01*
X1071933Y161912D01*
X1071391Y161996D01*
X1071100Y162121D01*
X1070808Y162329D01*
X1070600Y162621D01*
X1070558Y162912D01*
X1070641Y163204D01*
X1070850Y163412D01*
G01X1070975Y165012D02*
X1070725Y165262D01*
X1070600Y165554D01*
X1070558Y165887D01*
X1070641Y166304D01*
X1070850Y166596D01*
X1071100Y166679D01*
X1071350Y166637D01*
X1071558Y166471D01*
X1071975Y165637D01*
X1072266Y165262D01*
X1072683Y165012D01*
X1073058Y164929D01*
Y166679D01*
G01X1084158Y152571D02*
X1081658D01*
Y153612D01*
X1081783Y153946D01*
X1081950Y154154D01*
X1082283Y154237D01*
X1082616Y154154D01*
X1082825Y153904D01*
X1082950Y153612D01*
Y152571D01*
G01Y153612D02*
X1084158Y154237D01*
G01X1082075Y155712D02*
X1081825Y155962D01*
X1081700Y156254D01*
X1081658Y156587D01*
X1081741Y157004D01*
X1081950Y157296D01*
X1082200Y157379D01*
X1082450Y157337D01*
X1082658Y157171D01*
X1083075Y156337D01*
X1083366Y155962D01*
X1083783Y155712D01*
X1084158Y155629D01*
Y157379D01*
G01X1081658Y158687D02*
X1083450D01*
X1083825Y158854D01*
X1084075Y159187D01*
X1084158Y159604D01*
X1084075Y160021D01*
X1083825Y160354D01*
X1083450Y160521D01*
X1081658D01*
G01X1083116Y161912D02*
X1082825Y162204D01*
X1082658Y162454D01*
X1082575Y162787D01*
X1082658Y163079D01*
X1082825Y163287D01*
X1083075Y163454D01*
X1083366Y163496D01*
X1083616Y163454D01*
X1083866Y163287D01*
X1084075Y163037D01*
X1084158Y162746D01*
X1084075Y162412D01*
X1083825Y162121D01*
X1083450Y161954D01*
X1083033Y161912D01*
X1082491Y161996D01*
X1082200Y162121D01*
X1081908Y162329D01*
X1081700Y162621D01*
X1081658Y162912D01*
X1081741Y163204D01*
X1081950Y163412D01*
G01X1080458Y152571D02*
X1077958D01*
Y153612D01*
X1078083Y153946D01*
X1078250Y154154D01*
X1078583Y154237D01*
X1078916Y154154D01*
X1079125Y153904D01*
X1079250Y153612D01*
Y152571D01*
G01Y153612D02*
X1080458Y154237D01*
G01X1078375Y155712D02*
X1078125Y155962D01*
X1078000Y156254D01*
X1077958Y156587D01*
X1078041Y157004D01*
X1078250Y157296D01*
X1078500Y157379D01*
X1078750Y157337D01*
X1078958Y157171D01*
X1079375Y156337D01*
X1079666Y155962D01*
X1080083Y155712D01*
X1080458Y155629D01*
Y157379D01*
G01X1077958Y158687D02*
X1079750D01*
X1080125Y158854D01*
X1080375Y159187D01*
X1080458Y159604D01*
X1080375Y160021D01*
X1080125Y160354D01*
X1079750Y160521D01*
X1077958D01*
G01X1080166Y161996D02*
X1080375Y162287D01*
X1080458Y162621D01*
X1080375Y162954D01*
X1080125Y163246D01*
X1079750Y163454D01*
X1079375Y163537D01*
X1078916D01*
X1078541Y163454D01*
X1078208Y163246D01*
X1078041Y162996D01*
X1077958Y162704D01*
X1078041Y162371D01*
X1078208Y162121D01*
X1078458Y161954D01*
X1078791Y161871D01*
X1079083Y161954D01*
X1079375Y162162D01*
X1079541Y162412D01*
X1079583Y162704D01*
X1079500Y163037D01*
X1079291Y163287D01*
X1078916Y163537D01*
G01X1087858Y152571D02*
X1085358D01*
Y153612D01*
X1085483Y153946D01*
X1085650Y154154D01*
X1085983Y154237D01*
X1086316Y154154D01*
X1086525Y153904D01*
X1086650Y153612D01*
Y152571D01*
G01Y153612D02*
X1087858Y154237D01*
G01X1085775Y155712D02*
X1085525Y155962D01*
X1085400Y156254D01*
X1085358Y156587D01*
X1085441Y157004D01*
X1085650Y157296D01*
X1085900Y157379D01*
X1086150Y157337D01*
X1086358Y157171D01*
X1086775Y156337D01*
X1087066Y155962D01*
X1087483Y155712D01*
X1087858Y155629D01*
Y157379D01*
G01Y158646D02*
X1085358D01*
X1087858Y160562D01*
X1085358D01*
G01X1085775Y161912D02*
X1085525Y162162D01*
X1085400Y162454D01*
X1085358Y162787D01*
X1085441Y163204D01*
X1085650Y163496D01*
X1085900Y163579D01*
X1086150Y163537D01*
X1086358Y163371D01*
X1086775Y162537D01*
X1087066Y162162D01*
X1087483Y161912D01*
X1087858Y161829D01*
Y163579D01*
G01Y165721D02*
X1087316Y165804D01*
X1086858Y165929D01*
X1086441Y166096D01*
X1085983Y166304D01*
X1085358Y166637D01*
Y164971D01*
G01X1047158Y152571D02*
X1044658D01*
Y153612D01*
X1044783Y153946D01*
X1044950Y154154D01*
X1045283Y154237D01*
X1045616Y154154D01*
X1045825Y153904D01*
X1045950Y153612D01*
Y152571D01*
G01Y153612D02*
X1047158Y154237D01*
G01Y156421D02*
X1046616Y156504D01*
X1046158Y156629D01*
X1045741Y156796D01*
X1045283Y157004D01*
X1044658Y157337D01*
Y155671D01*
G01X1044866Y160521D02*
X1044741Y160271D01*
X1044658Y159979D01*
Y159646D01*
X1044783Y159271D01*
X1044991Y158979D01*
X1045241Y158771D01*
X1045658Y158604D01*
X1046033Y158562D01*
X1046408Y158646D01*
X1046658Y158771D01*
X1046908Y159021D01*
X1047075Y159312D01*
X1047158Y159604D01*
Y159896D01*
X1047075Y160187D01*
X1046950Y160437D01*
X1046783Y160646D01*
G01X1047158Y162704D02*
X1044658D01*
X1045158Y162204D01*
G01X1047158D02*
Y163204D01*
G01Y166304D02*
X1044658D01*
X1046450Y164762D01*
Y166846D01*
G01X1076758Y152571D02*
X1074258D01*
Y153612D01*
X1074383Y153946D01*
X1074550Y154154D01*
X1074883Y154237D01*
X1075216Y154154D01*
X1075425Y153904D01*
X1075550Y153612D01*
Y152571D01*
G01Y153612D02*
X1076758Y154237D01*
G01Y156504D02*
X1076716Y156796D01*
X1076591Y157129D01*
X1076383Y157337D01*
X1076091Y157421D01*
X1075800Y157337D01*
X1075550Y157087D01*
X1075425Y156712D01*
Y156296D01*
X1075341Y156046D01*
X1075133Y155837D01*
X1074841Y155754D01*
X1074550Y155879D01*
X1074341Y156171D01*
X1074258Y156504D01*
X1074341Y156837D01*
X1074550Y157129D01*
X1074841Y157254D01*
X1075133Y157171D01*
X1075341Y156962D01*
X1075425Y156712D01*
Y156296D01*
X1075550Y155921D01*
X1075800Y155671D01*
X1076091Y155587D01*
X1076383Y155671D01*
X1076591Y155879D01*
X1076716Y156212D01*
X1076758Y156504D01*
G01Y158687D02*
X1074258D01*
Y159521D01*
X1074383Y159854D01*
X1074550Y160104D01*
X1074800Y160312D01*
X1075091Y160479D01*
X1075508Y160521D01*
X1075925Y160479D01*
X1076216Y160312D01*
X1076466Y160104D01*
X1076633Y159854D01*
X1076758Y159521D01*
Y158687D01*
G01Y162704D02*
X1074258D01*
X1074758Y162204D01*
G01X1076758D02*
Y163204D01*
G01Y166304D02*
X1074258D01*
X1076050Y164762D01*
Y166846D01*
G01X1088980Y137207D02*
X1086480D01*
Y138248D01*
X1086605Y138582D01*
X1086772Y138790D01*
X1087105Y138873D01*
X1087438Y138790D01*
X1087647Y138540D01*
X1087772Y138248D01*
Y137207D01*
G01Y138248D02*
X1088980Y138873D01*
G01X1086897Y140348D02*
X1086647Y140598D01*
X1086522Y140890D01*
X1086480Y141223D01*
X1086563Y141640D01*
X1086772Y141932D01*
X1087022Y142015D01*
X1087272Y141973D01*
X1087480Y141807D01*
X1087897Y140973D01*
X1088188Y140598D01*
X1088605Y140348D01*
X1088980Y140265D01*
Y142015D01*
G01X1086480Y143323D02*
X1088272D01*
X1088647Y143490D01*
X1088897Y143823D01*
X1088980Y144240D01*
X1088897Y144657D01*
X1088647Y144990D01*
X1088272Y145157D01*
X1086480D01*
G01X1088980Y147340D02*
X1086480D01*
X1086980Y146840D01*
G01X1088980D02*
Y147840D01*
G01Y150440D02*
X1086480D01*
X1086980Y149940D01*
G01X1088980D02*
Y150940D01*
G01X1092880Y139307D02*
X1090380D01*
Y140348D01*
X1090505Y140682D01*
X1090672Y140890D01*
X1091005Y140973D01*
X1091338Y140890D01*
X1091547Y140640D01*
X1091672Y140348D01*
Y139307D01*
G01Y140348D02*
X1092880Y140973D01*
G01X1090797Y142448D02*
X1090547Y142698D01*
X1090422Y142990D01*
X1090380Y143323D01*
X1090463Y143740D01*
X1090672Y144032D01*
X1090922Y144115D01*
X1091172Y144073D01*
X1091380Y143907D01*
X1091797Y143073D01*
X1092088Y142698D01*
X1092505Y142448D01*
X1092880Y142365D01*
Y144115D01*
G01X1090380Y145423D02*
X1092172D01*
X1092547Y145590D01*
X1092797Y145923D01*
X1092880Y146340D01*
X1092797Y146757D01*
X1092547Y147090D01*
X1092172Y147257D01*
X1090380D01*
G01X1092380Y148523D02*
X1092672Y148773D01*
X1092838Y149107D01*
X1092880Y149482D01*
X1092838Y149815D01*
X1092630Y150148D01*
X1092380Y150357D01*
X1092130Y150398D01*
X1091838Y150315D01*
X1091630Y150023D01*
X1091547Y149732D01*
Y149357D01*
G01Y149732D02*
X1091422Y149982D01*
X1091213Y150190D01*
X1090963Y150273D01*
X1090713Y150190D01*
X1090505Y149982D01*
X1090380Y149607D01*
X1090422Y149232D01*
X1090588Y148857D01*
G01X1081580Y137207D02*
X1079080D01*
Y138248D01*
X1079205Y138582D01*
X1079372Y138790D01*
X1079705Y138873D01*
X1080038Y138790D01*
X1080247Y138540D01*
X1080372Y138248D01*
Y137207D01*
G01Y138248D02*
X1081580Y138873D01*
G01X1081080Y140223D02*
X1081372Y140473D01*
X1081538Y140807D01*
X1081580Y141182D01*
X1081538Y141515D01*
X1081330Y141848D01*
X1081080Y142057D01*
X1080830Y142098D01*
X1080538Y142015D01*
X1080330Y141723D01*
X1080247Y141432D01*
Y141057D01*
G01Y141432D02*
X1080122Y141682D01*
X1079913Y141890D01*
X1079663Y141973D01*
X1079413Y141890D01*
X1079205Y141682D01*
X1079080Y141307D01*
X1079122Y140932D01*
X1079288Y140557D01*
G01X1081580Y143407D02*
X1079080D01*
Y144407D01*
X1079205Y144740D01*
X1079497Y144990D01*
X1079830Y145073D01*
X1080163Y144990D01*
X1080413Y144782D01*
X1080538Y144407D01*
Y143407D01*
G01Y146548D02*
X1080247Y146840D01*
X1080080Y147090D01*
X1079997Y147423D01*
X1080080Y147715D01*
X1080247Y147923D01*
X1080497Y148090D01*
X1080788Y148132D01*
X1081038Y148090D01*
X1081288Y147923D01*
X1081497Y147673D01*
X1081580Y147382D01*
X1081497Y147048D01*
X1081247Y146757D01*
X1080872Y146590D01*
X1080455Y146548D01*
X1079913Y146632D01*
X1079622Y146757D01*
X1079330Y146965D01*
X1079122Y147257D01*
X1079080Y147548D01*
X1079163Y147840D01*
X1079372Y148048D01*
G01X1081580Y150940D02*
X1079080D01*
X1080872Y149398D01*
Y151482D01*
G01X1054558Y152571D02*
X1052058D01*
Y153612D01*
X1052183Y153946D01*
X1052350Y154154D01*
X1052683Y154237D01*
X1053016Y154154D01*
X1053225Y153904D01*
X1053350Y153612D01*
Y152571D01*
G01Y153612D02*
X1054558Y154237D01*
G01X1054058Y155587D02*
X1054350Y155837D01*
X1054516Y156171D01*
X1054558Y156546D01*
X1054516Y156879D01*
X1054308Y157212D01*
X1054058Y157421D01*
X1053808Y157462D01*
X1053516Y157379D01*
X1053308Y157087D01*
X1053225Y156796D01*
Y156421D01*
G01Y156796D02*
X1053100Y157046D01*
X1052891Y157254D01*
X1052641Y157337D01*
X1052391Y157254D01*
X1052183Y157046D01*
X1052058Y156671D01*
X1052100Y156296D01*
X1052266Y155921D01*
G01X1054558Y158771D02*
X1052058D01*
Y159771D01*
X1052183Y160104D01*
X1052475Y160354D01*
X1052808Y160437D01*
X1053141Y160354D01*
X1053391Y160146D01*
X1053516Y159771D01*
Y158771D01*
G01X1054058Y161787D02*
X1054350Y162037D01*
X1054516Y162371D01*
X1054558Y162746D01*
X1054516Y163079D01*
X1054308Y163412D01*
X1054058Y163621D01*
X1053808Y163662D01*
X1053516Y163579D01*
X1053308Y163287D01*
X1053225Y162996D01*
Y162621D01*
G01Y162996D02*
X1053100Y163246D01*
X1052891Y163454D01*
X1052641Y163537D01*
X1052391Y163454D01*
X1052183Y163246D01*
X1052058Y162871D01*
X1052100Y162496D01*
X1052266Y162121D01*
G01X1050858Y152571D02*
X1048358D01*
Y153612D01*
X1048483Y153946D01*
X1048650Y154154D01*
X1048983Y154237D01*
X1049316Y154154D01*
X1049525Y153904D01*
X1049650Y153612D01*
Y152571D01*
G01Y153612D02*
X1050858Y154237D01*
G01Y156421D02*
X1050316Y156504D01*
X1049858Y156629D01*
X1049441Y156796D01*
X1048983Y157004D01*
X1048358Y157337D01*
Y155671D01*
G01X1048566Y160521D02*
X1048441Y160271D01*
X1048358Y159979D01*
Y159646D01*
X1048483Y159271D01*
X1048691Y158979D01*
X1048941Y158771D01*
X1049358Y158604D01*
X1049733Y158562D01*
X1050108Y158646D01*
X1050358Y158771D01*
X1050608Y159021D01*
X1050775Y159312D01*
X1050858Y159604D01*
Y159896D01*
X1050775Y160187D01*
X1050650Y160437D01*
X1050483Y160646D01*
G01X1048775Y161912D02*
X1048525Y162162D01*
X1048400Y162454D01*
X1048358Y162787D01*
X1048441Y163204D01*
X1048650Y163496D01*
X1048900Y163579D01*
X1049150Y163537D01*
X1049358Y163371D01*
X1049775Y162537D01*
X1050066Y162162D01*
X1050483Y161912D01*
X1050858Y161829D01*
Y163579D01*
G01X1048358Y165804D02*
X1048441Y165471D01*
X1048650Y165221D01*
X1048900Y165054D01*
X1049233Y164929D01*
X1049608Y164887D01*
X1049983Y164929D01*
X1050316Y165054D01*
X1050566Y165221D01*
X1050775Y165471D01*
X1050858Y165804D01*
X1050775Y166137D01*
X1050566Y166387D01*
X1050316Y166554D01*
X1049983Y166679D01*
X1049608Y166721D01*
X1049233Y166679D01*
X1048900Y166554D01*
X1048650Y166387D01*
X1048441Y166137D01*
X1048358Y165804D01*
G01X1061958Y152571D02*
X1059458D01*
Y153612D01*
X1059583Y153946D01*
X1059750Y154154D01*
X1060083Y154237D01*
X1060416Y154154D01*
X1060625Y153904D01*
X1060750Y153612D01*
Y152571D01*
G01Y153612D02*
X1061958Y154237D01*
G01X1061458Y155587D02*
X1061750Y155837D01*
X1061916Y156171D01*
X1061958Y156546D01*
X1061916Y156879D01*
X1061708Y157212D01*
X1061458Y157421D01*
X1061208Y157462D01*
X1060916Y157379D01*
X1060708Y157087D01*
X1060625Y156796D01*
Y156421D01*
G01Y156796D02*
X1060500Y157046D01*
X1060291Y157254D01*
X1060041Y157337D01*
X1059791Y157254D01*
X1059583Y157046D01*
X1059458Y156671D01*
X1059500Y156296D01*
X1059666Y155921D01*
G01X1061958Y158771D02*
X1059458D01*
Y159771D01*
X1059583Y160104D01*
X1059875Y160354D01*
X1060208Y160437D01*
X1060541Y160354D01*
X1060791Y160146D01*
X1060916Y159771D01*
Y158771D01*
G01X1059875Y161912D02*
X1059625Y162162D01*
X1059500Y162454D01*
X1059458Y162787D01*
X1059541Y163204D01*
X1059750Y163496D01*
X1060000Y163579D01*
X1060250Y163537D01*
X1060458Y163371D01*
X1060875Y162537D01*
X1061166Y162162D01*
X1061583Y161912D01*
X1061958Y161829D01*
Y163579D01*
G01X1069358Y152571D02*
X1066858D01*
Y153612D01*
X1066983Y153946D01*
X1067150Y154154D01*
X1067483Y154237D01*
X1067816Y154154D01*
X1068025Y153904D01*
X1068150Y153612D01*
Y152571D01*
G01Y153612D02*
X1069358Y154237D01*
G01Y156504D02*
X1069316Y156796D01*
X1069191Y157129D01*
X1068983Y157337D01*
X1068691Y157421D01*
X1068400Y157337D01*
X1068150Y157087D01*
X1068025Y156712D01*
Y156296D01*
X1067941Y156046D01*
X1067733Y155837D01*
X1067441Y155754D01*
X1067150Y155879D01*
X1066941Y156171D01*
X1066858Y156504D01*
X1066941Y156837D01*
X1067150Y157129D01*
X1067441Y157254D01*
X1067733Y157171D01*
X1067941Y156962D01*
X1068025Y156712D01*
Y156296D01*
X1068150Y155921D01*
X1068400Y155671D01*
X1068691Y155587D01*
X1068983Y155671D01*
X1069191Y155879D01*
X1069316Y156212D01*
X1069358Y156504D01*
G01Y158687D02*
X1066858D01*
Y159521D01*
X1066983Y159854D01*
X1067150Y160104D01*
X1067400Y160312D01*
X1067691Y160479D01*
X1068108Y160521D01*
X1068525Y160479D01*
X1068816Y160312D01*
X1069066Y160104D01*
X1069233Y159854D01*
X1069358Y159521D01*
Y158687D01*
G01Y162704D02*
X1066858D01*
X1067358Y162204D01*
G01X1069358D02*
Y163204D01*
G01X1068858Y164887D02*
X1069150Y165137D01*
X1069316Y165471D01*
X1069358Y165846D01*
X1069316Y166179D01*
X1069108Y166512D01*
X1068858Y166721D01*
X1068608Y166762D01*
X1068316Y166679D01*
X1068108Y166387D01*
X1068025Y166096D01*
Y165721D01*
G01Y166096D02*
X1067900Y166346D01*
X1067691Y166554D01*
X1067441Y166637D01*
X1067191Y166554D01*
X1066983Y166346D01*
X1066858Y165971D01*
X1066900Y165596D01*
X1067066Y165221D01*
G01X1065658Y152571D02*
X1063158D01*
Y153612D01*
X1063283Y153946D01*
X1063450Y154154D01*
X1063783Y154237D01*
X1064116Y154154D01*
X1064325Y153904D01*
X1064450Y153612D01*
Y152571D01*
G01Y153612D02*
X1065658Y154237D01*
G01X1063575Y155712D02*
X1063325Y155962D01*
X1063200Y156254D01*
X1063158Y156587D01*
X1063241Y157004D01*
X1063450Y157296D01*
X1063700Y157379D01*
X1063950Y157337D01*
X1064158Y157171D01*
X1064575Y156337D01*
X1064866Y155962D01*
X1065283Y155712D01*
X1065658Y155629D01*
Y157379D01*
G01Y158771D02*
X1063158D01*
Y159771D01*
X1063283Y160104D01*
X1063575Y160354D01*
X1063908Y160437D01*
X1064241Y160354D01*
X1064491Y160146D01*
X1064616Y159771D01*
Y158771D01*
G01X1065658Y162704D02*
X1063158D01*
X1063658Y162204D01*
G01X1065658D02*
Y163204D01*
G01X1039758Y152571D02*
X1037258D01*
Y153612D01*
X1037383Y153946D01*
X1037550Y154154D01*
X1037883Y154237D01*
X1038216Y154154D01*
X1038425Y153904D01*
X1038550Y153612D01*
Y152571D01*
G01Y153612D02*
X1039758Y154237D01*
G01Y156421D02*
X1039216Y156504D01*
X1038758Y156629D01*
X1038341Y156796D01*
X1037883Y157004D01*
X1037258Y157337D01*
Y155671D01*
G01X1039758Y158687D02*
X1037258D01*
Y159521D01*
X1037383Y159854D01*
X1037550Y160104D01*
X1037800Y160312D01*
X1038091Y160479D01*
X1038508Y160521D01*
X1038925Y160479D01*
X1039216Y160312D01*
X1039466Y160104D01*
X1039633Y159854D01*
X1039758Y159521D01*
Y158687D01*
G01Y162704D02*
X1037258D01*
X1037758Y162204D01*
G01X1039758D02*
Y163204D01*
G01X1037675Y165012D02*
X1037425Y165262D01*
X1037300Y165554D01*
X1037258Y165887D01*
X1037341Y166304D01*
X1037550Y166596D01*
X1037800Y166679D01*
X1038050Y166637D01*
X1038258Y166471D01*
X1038675Y165637D01*
X1038966Y165262D01*
X1039383Y165012D01*
X1039758Y164929D01*
Y166679D01*
G01X1043458Y152571D02*
X1040958D01*
Y153612D01*
X1041083Y153946D01*
X1041250Y154154D01*
X1041583Y154237D01*
X1041916Y154154D01*
X1042125Y153904D01*
X1042250Y153612D01*
Y152571D01*
G01Y153612D02*
X1043458Y154237D01*
G01Y156504D02*
X1043416Y156796D01*
X1043291Y157129D01*
X1043083Y157337D01*
X1042791Y157421D01*
X1042500Y157337D01*
X1042250Y157087D01*
X1042125Y156712D01*
Y156296D01*
X1042041Y156046D01*
X1041833Y155837D01*
X1041541Y155754D01*
X1041250Y155879D01*
X1041041Y156171D01*
X1040958Y156504D01*
X1041041Y156837D01*
X1041250Y157129D01*
X1041541Y157254D01*
X1041833Y157171D01*
X1042041Y156962D01*
X1042125Y156712D01*
Y156296D01*
X1042250Y155921D01*
X1042500Y155671D01*
X1042791Y155587D01*
X1043083Y155671D01*
X1043291Y155879D01*
X1043416Y156212D01*
X1043458Y156504D01*
G01Y160437D02*
Y158771D01*
X1040958D01*
Y160437D01*
G01X1042166Y159771D02*
Y158771D01*
G01X1042958Y161787D02*
X1043250Y162037D01*
X1043416Y162371D01*
X1043458Y162746D01*
X1043416Y163079D01*
X1043208Y163412D01*
X1042958Y163621D01*
X1042708Y163662D01*
X1042416Y163579D01*
X1042208Y163287D01*
X1042125Y162996D01*
Y162621D01*
G01Y162996D02*
X1042000Y163246D01*
X1041791Y163454D01*
X1041541Y163537D01*
X1041291Y163454D01*
X1041083Y163246D01*
X1040958Y162871D01*
X1041000Y162496D01*
X1041166Y162121D01*
G01X1058258Y152571D02*
X1055758D01*
Y153612D01*
X1055883Y153946D01*
X1056050Y154154D01*
X1056383Y154237D01*
X1056716Y154154D01*
X1056925Y153904D01*
X1057050Y153612D01*
Y152571D01*
G01Y153612D02*
X1058258Y154237D01*
G01Y156504D02*
X1058216Y156796D01*
X1058091Y157129D01*
X1057883Y157337D01*
X1057591Y157421D01*
X1057300Y157337D01*
X1057050Y157087D01*
X1056925Y156712D01*
Y156296D01*
X1056841Y156046D01*
X1056633Y155837D01*
X1056341Y155754D01*
X1056050Y155879D01*
X1055841Y156171D01*
X1055758Y156504D01*
X1055841Y156837D01*
X1056050Y157129D01*
X1056341Y157254D01*
X1056633Y157171D01*
X1056841Y156962D01*
X1056925Y156712D01*
Y156296D01*
X1057050Y155921D01*
X1057300Y155671D01*
X1057591Y155587D01*
X1057883Y155671D01*
X1058091Y155879D01*
X1058216Y156212D01*
X1058258Y156504D01*
G01X1055966Y160521D02*
X1055841Y160271D01*
X1055758Y159979D01*
Y159646D01*
X1055883Y159271D01*
X1056091Y158979D01*
X1056341Y158771D01*
X1056758Y158604D01*
X1057133Y158562D01*
X1057508Y158646D01*
X1057758Y158771D01*
X1058008Y159021D01*
X1058175Y159312D01*
X1058258Y159604D01*
Y159896D01*
X1058175Y160187D01*
X1058050Y160437D01*
X1057883Y160646D01*
G01X1056175Y161912D02*
X1055925Y162162D01*
X1055800Y162454D01*
X1055758Y162787D01*
X1055841Y163204D01*
X1056050Y163496D01*
X1056300Y163579D01*
X1056550Y163537D01*
X1056758Y163371D01*
X1057175Y162537D01*
X1057466Y162162D01*
X1057883Y161912D01*
X1058258Y161829D01*
Y163579D01*
G01X1057216Y165012D02*
X1056925Y165304D01*
X1056758Y165554D01*
X1056675Y165887D01*
X1056758Y166179D01*
X1056925Y166387D01*
X1057175Y166554D01*
X1057466Y166596D01*
X1057716Y166554D01*
X1057966Y166387D01*
X1058175Y166137D01*
X1058258Y165846D01*
X1058175Y165512D01*
X1057925Y165221D01*
X1057550Y165054D01*
X1057133Y165012D01*
X1056591Y165096D01*
X1056300Y165221D01*
X1056008Y165429D01*
X1055800Y165721D01*
X1055758Y166012D01*
X1055841Y166304D01*
X1056050Y166512D01*
G01X1036058Y152571D02*
X1033558D01*
Y153612D01*
X1033683Y153946D01*
X1033850Y154154D01*
X1034183Y154237D01*
X1034516Y154154D01*
X1034725Y153904D01*
X1034850Y153612D01*
Y152571D01*
G01Y153612D02*
X1036058Y154237D01*
G01Y156421D02*
X1035516Y156504D01*
X1035058Y156629D01*
X1034641Y156796D01*
X1034183Y157004D01*
X1033558Y157337D01*
Y155671D01*
G01X1036058Y158687D02*
X1033558D01*
Y159521D01*
X1033683Y159854D01*
X1033850Y160104D01*
X1034100Y160312D01*
X1034391Y160479D01*
X1034808Y160521D01*
X1035225Y160479D01*
X1035516Y160312D01*
X1035766Y160104D01*
X1035933Y159854D01*
X1036058Y159521D01*
Y158687D01*
G01Y162704D02*
X1033558D01*
X1034058Y162204D01*
G01X1036058D02*
Y163204D01*
G01X1033558Y165804D02*
X1033641Y165471D01*
X1033850Y165221D01*
X1034100Y165054D01*
X1034433Y164929D01*
X1034808Y164887D01*
X1035183Y164929D01*
X1035516Y165054D01*
X1035766Y165221D01*
X1035975Y165471D01*
X1036058Y165804D01*
X1035975Y166137D01*
X1035766Y166387D01*
X1035516Y166554D01*
X1035183Y166679D01*
X1034808Y166721D01*
X1034433Y166679D01*
X1034100Y166554D01*
X1033850Y166387D01*
X1033641Y166137D01*
X1033558Y165804D01*
G01X1072775Y121114D02*
X1072650Y120864D01*
X1072567Y120572D01*
Y120239D01*
X1072692Y119864D01*
X1072900Y119572D01*
X1073150Y119364D01*
X1073567Y119197D01*
X1073942Y119155D01*
X1074317Y119239D01*
X1074567Y119364D01*
X1074817Y119614D01*
X1074984Y119905D01*
X1075067Y120197D01*
Y120489D01*
X1074984Y120780D01*
X1074859Y121030D01*
X1074692Y121239D01*
G01X1075067Y123297D02*
X1075025Y123589D01*
X1074900Y123922D01*
X1074692Y124130D01*
X1074400Y124214D01*
X1074109Y124130D01*
X1073859Y123880D01*
X1073734Y123505D01*
Y123089D01*
X1073650Y122839D01*
X1073442Y122630D01*
X1073150Y122547D01*
X1072859Y122672D01*
X1072650Y122964D01*
X1072567Y123297D01*
X1072650Y123630D01*
X1072859Y123922D01*
X1073150Y124047D01*
X1073442Y123964D01*
X1073650Y123755D01*
X1073734Y123505D01*
Y123089D01*
X1073859Y122714D01*
X1074109Y122464D01*
X1074400Y122380D01*
X1074692Y122464D01*
X1074900Y122672D01*
X1075025Y123005D01*
X1075067Y123297D01*
G01X1073817Y126647D02*
Y127480D01*
X1074567D01*
X1074817Y127230D01*
X1074984Y126939D01*
X1075067Y126522D01*
X1074984Y126105D01*
X1074817Y125814D01*
X1074567Y125564D01*
X1074275Y125397D01*
X1073942Y125314D01*
X1073650D01*
X1073400Y125397D01*
X1073109Y125564D01*
X1072859Y125814D01*
X1072692Y126064D01*
X1072567Y126397D01*
Y126689D01*
X1072650Y127022D01*
X1072817Y127272D01*
G01X1072984Y128705D02*
X1072734Y128955D01*
X1072609Y129247D01*
X1072567Y129580D01*
X1072650Y129997D01*
X1072859Y130289D01*
X1073109Y130372D01*
X1073359Y130330D01*
X1073567Y130164D01*
X1073984Y129330D01*
X1074275Y128955D01*
X1074692Y128705D01*
X1075067Y128622D01*
Y130372D01*
G01X1069275Y121114D02*
X1069150Y120864D01*
X1069067Y120572D01*
Y120239D01*
X1069192Y119864D01*
X1069400Y119572D01*
X1069650Y119364D01*
X1070067Y119197D01*
X1070442Y119155D01*
X1070817Y119239D01*
X1071067Y119364D01*
X1071317Y119614D01*
X1071484Y119905D01*
X1071567Y120197D01*
Y120489D01*
X1071484Y120780D01*
X1071359Y121030D01*
X1071192Y121239D01*
G01X1071567Y123297D02*
X1071525Y123589D01*
X1071400Y123922D01*
X1071192Y124130D01*
X1070900Y124214D01*
X1070609Y124130D01*
X1070359Y123880D01*
X1070234Y123505D01*
Y123089D01*
X1070150Y122839D01*
X1069942Y122630D01*
X1069650Y122547D01*
X1069359Y122672D01*
X1069150Y122964D01*
X1069067Y123297D01*
X1069150Y123630D01*
X1069359Y123922D01*
X1069650Y124047D01*
X1069942Y123964D01*
X1070150Y123755D01*
X1070234Y123505D01*
Y123089D01*
X1070359Y122714D01*
X1070609Y122464D01*
X1070900Y122380D01*
X1071192Y122464D01*
X1071400Y122672D01*
X1071525Y123005D01*
X1071567Y123297D01*
G01X1070317Y126647D02*
Y127480D01*
X1071067D01*
X1071317Y127230D01*
X1071484Y126939D01*
X1071567Y126522D01*
X1071484Y126105D01*
X1071317Y125814D01*
X1071067Y125564D01*
X1070775Y125397D01*
X1070442Y125314D01*
X1070150D01*
X1069900Y125397D01*
X1069609Y125564D01*
X1069359Y125814D01*
X1069192Y126064D01*
X1069067Y126397D01*
Y126689D01*
X1069150Y127022D01*
X1069317Y127272D01*
G01X1071567Y129497D02*
X1069067D01*
X1069567Y128997D01*
G01X1071567D02*
Y129997D01*
G01X1083275Y121114D02*
X1083150Y120864D01*
X1083067Y120572D01*
Y120239D01*
X1083192Y119864D01*
X1083400Y119572D01*
X1083650Y119364D01*
X1084067Y119197D01*
X1084442Y119155D01*
X1084817Y119239D01*
X1085067Y119364D01*
X1085317Y119614D01*
X1085484Y119905D01*
X1085567Y120197D01*
Y120489D01*
X1085484Y120780D01*
X1085359Y121030D01*
X1085192Y121239D01*
G01X1085567Y123297D02*
X1085525Y123589D01*
X1085400Y123922D01*
X1085192Y124130D01*
X1084900Y124214D01*
X1084609Y124130D01*
X1084359Y123880D01*
X1084234Y123505D01*
Y123089D01*
X1084150Y122839D01*
X1083942Y122630D01*
X1083650Y122547D01*
X1083359Y122672D01*
X1083150Y122964D01*
X1083067Y123297D01*
X1083150Y123630D01*
X1083359Y123922D01*
X1083650Y124047D01*
X1083942Y123964D01*
X1084150Y123755D01*
X1084234Y123505D01*
Y123089D01*
X1084359Y122714D01*
X1084609Y122464D01*
X1084900Y122380D01*
X1085192Y122464D01*
X1085400Y122672D01*
X1085525Y123005D01*
X1085567Y123297D01*
G01X1084317Y126647D02*
Y127480D01*
X1085067D01*
X1085317Y127230D01*
X1085484Y126939D01*
X1085567Y126522D01*
X1085484Y126105D01*
X1085317Y125814D01*
X1085067Y125564D01*
X1084775Y125397D01*
X1084442Y125314D01*
X1084150D01*
X1083900Y125397D01*
X1083609Y125564D01*
X1083359Y125814D01*
X1083192Y126064D01*
X1083067Y126397D01*
Y126689D01*
X1083150Y127022D01*
X1083317Y127272D01*
G01X1085192Y128580D02*
X1085400Y128830D01*
X1085525Y129122D01*
X1085567Y129497D01*
X1085484Y129872D01*
X1085317Y130164D01*
X1085025Y130372D01*
X1084692Y130414D01*
X1084359Y130330D01*
X1084150Y130122D01*
X1083984Y129830D01*
X1083942Y129539D01*
X1083984Y129247D01*
X1084150Y128872D01*
X1083067Y128997D01*
Y130122D01*
G01X1089975Y121314D02*
X1089850Y121064D01*
X1089767Y120772D01*
Y120439D01*
X1089892Y120064D01*
X1090100Y119772D01*
X1090350Y119564D01*
X1090767Y119397D01*
X1091142Y119355D01*
X1091517Y119439D01*
X1091767Y119564D01*
X1092017Y119814D01*
X1092184Y120105D01*
X1092267Y120397D01*
Y120689D01*
X1092184Y120980D01*
X1092059Y121230D01*
X1091892Y121439D01*
G01X1092267Y123497D02*
X1092225Y123789D01*
X1092100Y124122D01*
X1091892Y124330D01*
X1091600Y124414D01*
X1091309Y124330D01*
X1091059Y124080D01*
X1090934Y123705D01*
Y123289D01*
X1090850Y123039D01*
X1090642Y122830D01*
X1090350Y122747D01*
X1090059Y122872D01*
X1089850Y123164D01*
X1089767Y123497D01*
X1089850Y123830D01*
X1090059Y124122D01*
X1090350Y124247D01*
X1090642Y124164D01*
X1090850Y123955D01*
X1090934Y123705D01*
Y123289D01*
X1091059Y122914D01*
X1091309Y122664D01*
X1091600Y122580D01*
X1091892Y122664D01*
X1092100Y122872D01*
X1092225Y123205D01*
X1092267Y123497D01*
G01X1091017Y126847D02*
Y127680D01*
X1091767D01*
X1092017Y127430D01*
X1092184Y127139D01*
X1092267Y126722D01*
X1092184Y126305D01*
X1092017Y126014D01*
X1091767Y125764D01*
X1091475Y125597D01*
X1091142Y125514D01*
X1090850D01*
X1090600Y125597D01*
X1090309Y125764D01*
X1090059Y126014D01*
X1089892Y126264D01*
X1089767Y126597D01*
Y126889D01*
X1089850Y127222D01*
X1090017Y127472D01*
G01X1091225Y128905D02*
X1090934Y129197D01*
X1090767Y129447D01*
X1090684Y129780D01*
X1090767Y130072D01*
X1090934Y130280D01*
X1091184Y130447D01*
X1091475Y130489D01*
X1091725Y130447D01*
X1091975Y130280D01*
X1092184Y130030D01*
X1092267Y129739D01*
X1092184Y129405D01*
X1091934Y129114D01*
X1091559Y128947D01*
X1091142Y128905D01*
X1090600Y128989D01*
X1090309Y129114D01*
X1090017Y129322D01*
X1089809Y129614D01*
X1089767Y129905D01*
X1089850Y130197D01*
X1090059Y130405D01*
G01X1076275Y121114D02*
X1076150Y120864D01*
X1076067Y120572D01*
Y120239D01*
X1076192Y119864D01*
X1076400Y119572D01*
X1076650Y119364D01*
X1077067Y119197D01*
X1077442Y119155D01*
X1077817Y119239D01*
X1078067Y119364D01*
X1078317Y119614D01*
X1078484Y119905D01*
X1078567Y120197D01*
Y120489D01*
X1078484Y120780D01*
X1078359Y121030D01*
X1078192Y121239D01*
G01X1078567Y123297D02*
X1078525Y123589D01*
X1078400Y123922D01*
X1078192Y124130D01*
X1077900Y124214D01*
X1077609Y124130D01*
X1077359Y123880D01*
X1077234Y123505D01*
Y123089D01*
X1077150Y122839D01*
X1076942Y122630D01*
X1076650Y122547D01*
X1076359Y122672D01*
X1076150Y122964D01*
X1076067Y123297D01*
X1076150Y123630D01*
X1076359Y123922D01*
X1076650Y124047D01*
X1076942Y123964D01*
X1077150Y123755D01*
X1077234Y123505D01*
Y123089D01*
X1077359Y122714D01*
X1077609Y122464D01*
X1077900Y122380D01*
X1078192Y122464D01*
X1078400Y122672D01*
X1078525Y123005D01*
X1078567Y123297D01*
G01X1077317Y126647D02*
Y127480D01*
X1078067D01*
X1078317Y127230D01*
X1078484Y126939D01*
X1078567Y126522D01*
X1078484Y126105D01*
X1078317Y125814D01*
X1078067Y125564D01*
X1077775Y125397D01*
X1077442Y125314D01*
X1077150D01*
X1076900Y125397D01*
X1076609Y125564D01*
X1076359Y125814D01*
X1076192Y126064D01*
X1076067Y126397D01*
Y126689D01*
X1076150Y127022D01*
X1076317Y127272D01*
G01X1078067Y128580D02*
X1078359Y128830D01*
X1078525Y129164D01*
X1078567Y129539D01*
X1078525Y129872D01*
X1078317Y130205D01*
X1078067Y130414D01*
X1077817Y130455D01*
X1077525Y130372D01*
X1077317Y130080D01*
X1077234Y129789D01*
Y129414D01*
G01Y129789D02*
X1077109Y130039D01*
X1076900Y130247D01*
X1076650Y130330D01*
X1076400Y130247D01*
X1076192Y130039D01*
X1076067Y129664D01*
X1076109Y129289D01*
X1076275Y128914D01*
G01X1079775Y121114D02*
X1079650Y120864D01*
X1079567Y120572D01*
Y120239D01*
X1079692Y119864D01*
X1079900Y119572D01*
X1080150Y119364D01*
X1080567Y119197D01*
X1080942Y119155D01*
X1081317Y119239D01*
X1081567Y119364D01*
X1081817Y119614D01*
X1081984Y119905D01*
X1082067Y120197D01*
Y120489D01*
X1081984Y120780D01*
X1081859Y121030D01*
X1081692Y121239D01*
G01X1082067Y123297D02*
X1082025Y123589D01*
X1081900Y123922D01*
X1081692Y124130D01*
X1081400Y124214D01*
X1081109Y124130D01*
X1080859Y123880D01*
X1080734Y123505D01*
Y123089D01*
X1080650Y122839D01*
X1080442Y122630D01*
X1080150Y122547D01*
X1079859Y122672D01*
X1079650Y122964D01*
X1079567Y123297D01*
X1079650Y123630D01*
X1079859Y123922D01*
X1080150Y124047D01*
X1080442Y123964D01*
X1080650Y123755D01*
X1080734Y123505D01*
Y123089D01*
X1080859Y122714D01*
X1081109Y122464D01*
X1081400Y122380D01*
X1081692Y122464D01*
X1081900Y122672D01*
X1082025Y123005D01*
X1082067Y123297D01*
G01X1080817Y126647D02*
Y127480D01*
X1081567D01*
X1081817Y127230D01*
X1081984Y126939D01*
X1082067Y126522D01*
X1081984Y126105D01*
X1081817Y125814D01*
X1081567Y125564D01*
X1081275Y125397D01*
X1080942Y125314D01*
X1080650D01*
X1080400Y125397D01*
X1080109Y125564D01*
X1079859Y125814D01*
X1079692Y126064D01*
X1079567Y126397D01*
Y126689D01*
X1079650Y127022D01*
X1079817Y127272D01*
G01X1082067Y129997D02*
X1079567D01*
X1081359Y128455D01*
Y130539D01*
G01X1093475Y121314D02*
X1093350Y121064D01*
X1093267Y120772D01*
Y120439D01*
X1093392Y120064D01*
X1093600Y119772D01*
X1093850Y119564D01*
X1094267Y119397D01*
X1094642Y119355D01*
X1095017Y119439D01*
X1095267Y119564D01*
X1095517Y119814D01*
X1095684Y120105D01*
X1095767Y120397D01*
Y120689D01*
X1095684Y120980D01*
X1095559Y121230D01*
X1095392Y121439D01*
G01X1095767Y123497D02*
X1095725Y123789D01*
X1095600Y124122D01*
X1095392Y124330D01*
X1095100Y124414D01*
X1094809Y124330D01*
X1094559Y124080D01*
X1094434Y123705D01*
Y123289D01*
X1094350Y123039D01*
X1094142Y122830D01*
X1093850Y122747D01*
X1093559Y122872D01*
X1093350Y123164D01*
X1093267Y123497D01*
X1093350Y123830D01*
X1093559Y124122D01*
X1093850Y124247D01*
X1094142Y124164D01*
X1094350Y123955D01*
X1094434Y123705D01*
Y123289D01*
X1094559Y122914D01*
X1094809Y122664D01*
X1095100Y122580D01*
X1095392Y122664D01*
X1095600Y122872D01*
X1095725Y123205D01*
X1095767Y123497D01*
G01X1094517Y126847D02*
Y127680D01*
X1095267D01*
X1095517Y127430D01*
X1095684Y127139D01*
X1095767Y126722D01*
X1095684Y126305D01*
X1095517Y126014D01*
X1095267Y125764D01*
X1094975Y125597D01*
X1094642Y125514D01*
X1094350D01*
X1094100Y125597D01*
X1093809Y125764D01*
X1093559Y126014D01*
X1093392Y126264D01*
X1093267Y126597D01*
Y126889D01*
X1093350Y127222D01*
X1093517Y127472D01*
G01X1095767Y129614D02*
X1095225Y129697D01*
X1094767Y129822D01*
X1094350Y129989D01*
X1093892Y130197D01*
X1093267Y130530D01*
Y128864D01*
G01X1055275Y121114D02*
X1055150Y120864D01*
X1055067Y120572D01*
Y120239D01*
X1055192Y119864D01*
X1055400Y119572D01*
X1055650Y119364D01*
X1056067Y119197D01*
X1056442Y119155D01*
X1056817Y119239D01*
X1057067Y119364D01*
X1057317Y119614D01*
X1057484Y119905D01*
X1057567Y120197D01*
Y120489D01*
X1057484Y120780D01*
X1057359Y121030D01*
X1057192Y121239D01*
G01X1057567Y123214D02*
X1057025Y123297D01*
X1056567Y123422D01*
X1056150Y123589D01*
X1055692Y123797D01*
X1055067Y124130D01*
Y122464D01*
G01X1056317Y126647D02*
Y127480D01*
X1057067D01*
X1057317Y127230D01*
X1057484Y126939D01*
X1057567Y126522D01*
X1057484Y126105D01*
X1057317Y125814D01*
X1057067Y125564D01*
X1056775Y125397D01*
X1056442Y125314D01*
X1056150D01*
X1055900Y125397D01*
X1055609Y125564D01*
X1055359Y125814D01*
X1055192Y126064D01*
X1055067Y126397D01*
Y126689D01*
X1055150Y127022D01*
X1055317Y127272D01*
G01X1055484Y128705D02*
X1055234Y128955D01*
X1055109Y129247D01*
X1055067Y129580D01*
X1055150Y129997D01*
X1055359Y130289D01*
X1055609Y130372D01*
X1055859Y130330D01*
X1056067Y130164D01*
X1056484Y129330D01*
X1056775Y128955D01*
X1057192Y128705D01*
X1057567Y128622D01*
Y130372D01*
G01X1057067Y131680D02*
X1057359Y131930D01*
X1057525Y132264D01*
X1057567Y132639D01*
X1057525Y132972D01*
X1057317Y133305D01*
X1057067Y133514D01*
X1056817Y133555D01*
X1056525Y133472D01*
X1056317Y133180D01*
X1056234Y132889D01*
Y132514D01*
G01Y132889D02*
X1056109Y133139D01*
X1055900Y133347D01*
X1055650Y133430D01*
X1055400Y133347D01*
X1055192Y133139D01*
X1055067Y132764D01*
X1055109Y132389D01*
X1055275Y132014D01*
G01X1048275Y121114D02*
X1048150Y120864D01*
X1048067Y120572D01*
Y120239D01*
X1048192Y119864D01*
X1048400Y119572D01*
X1048650Y119364D01*
X1049067Y119197D01*
X1049442Y119155D01*
X1049817Y119239D01*
X1050067Y119364D01*
X1050317Y119614D01*
X1050484Y119905D01*
X1050567Y120197D01*
Y120489D01*
X1050484Y120780D01*
X1050359Y121030D01*
X1050192Y121239D01*
G01X1050567Y123214D02*
X1050025Y123297D01*
X1049567Y123422D01*
X1049150Y123589D01*
X1048692Y123797D01*
X1048067Y124130D01*
Y122464D01*
G01X1049317Y126647D02*
Y127480D01*
X1050067D01*
X1050317Y127230D01*
X1050484Y126939D01*
X1050567Y126522D01*
X1050484Y126105D01*
X1050317Y125814D01*
X1050067Y125564D01*
X1049775Y125397D01*
X1049442Y125314D01*
X1049150D01*
X1048900Y125397D01*
X1048609Y125564D01*
X1048359Y125814D01*
X1048192Y126064D01*
X1048067Y126397D01*
Y126689D01*
X1048150Y127022D01*
X1048317Y127272D01*
G01X1048484Y128705D02*
X1048234Y128955D01*
X1048109Y129247D01*
X1048067Y129580D01*
X1048150Y129997D01*
X1048359Y130289D01*
X1048609Y130372D01*
X1048859Y130330D01*
X1049067Y130164D01*
X1049484Y129330D01*
X1049775Y128955D01*
X1050192Y128705D01*
X1050567Y128622D01*
Y130372D01*
G01Y132597D02*
X1048067D01*
X1048567Y132097D01*
G01X1050567D02*
Y133097D01*
G01X1058775Y121114D02*
X1058650Y120864D01*
X1058567Y120572D01*
Y120239D01*
X1058692Y119864D01*
X1058900Y119572D01*
X1059150Y119364D01*
X1059567Y119197D01*
X1059942Y119155D01*
X1060317Y119239D01*
X1060567Y119364D01*
X1060817Y119614D01*
X1060984Y119905D01*
X1061067Y120197D01*
Y120489D01*
X1060984Y120780D01*
X1060859Y121030D01*
X1060692Y121239D01*
G01X1061067Y123214D02*
X1060525Y123297D01*
X1060067Y123422D01*
X1059650Y123589D01*
X1059192Y123797D01*
X1058567Y124130D01*
Y122464D01*
G01X1059817Y126647D02*
Y127480D01*
X1060567D01*
X1060817Y127230D01*
X1060984Y126939D01*
X1061067Y126522D01*
X1060984Y126105D01*
X1060817Y125814D01*
X1060567Y125564D01*
X1060275Y125397D01*
X1059942Y125314D01*
X1059650D01*
X1059400Y125397D01*
X1059109Y125564D01*
X1058859Y125814D01*
X1058692Y126064D01*
X1058567Y126397D01*
Y126689D01*
X1058650Y127022D01*
X1058817Y127272D01*
G01X1058984Y128705D02*
X1058734Y128955D01*
X1058609Y129247D01*
X1058567Y129580D01*
X1058650Y129997D01*
X1058859Y130289D01*
X1059109Y130372D01*
X1059359Y130330D01*
X1059567Y130164D01*
X1059984Y129330D01*
X1060275Y128955D01*
X1060692Y128705D01*
X1061067Y128622D01*
Y130372D01*
G01Y133097D02*
X1058567D01*
X1060359Y131555D01*
Y133639D01*
G01X1062275Y121114D02*
X1062150Y120864D01*
X1062067Y120572D01*
Y120239D01*
X1062192Y119864D01*
X1062400Y119572D01*
X1062650Y119364D01*
X1063067Y119197D01*
X1063442Y119155D01*
X1063817Y119239D01*
X1064067Y119364D01*
X1064317Y119614D01*
X1064484Y119905D01*
X1064567Y120197D01*
Y120489D01*
X1064484Y120780D01*
X1064359Y121030D01*
X1064192Y121239D01*
G01X1064567Y123214D02*
X1064025Y123297D01*
X1063567Y123422D01*
X1063150Y123589D01*
X1062692Y123797D01*
X1062067Y124130D01*
Y122464D01*
G01X1063317Y126647D02*
Y127480D01*
X1064067D01*
X1064317Y127230D01*
X1064484Y126939D01*
X1064567Y126522D01*
X1064484Y126105D01*
X1064317Y125814D01*
X1064067Y125564D01*
X1063775Y125397D01*
X1063442Y125314D01*
X1063150D01*
X1062900Y125397D01*
X1062609Y125564D01*
X1062359Y125814D01*
X1062192Y126064D01*
X1062067Y126397D01*
Y126689D01*
X1062150Y127022D01*
X1062317Y127272D01*
G01X1062484Y128705D02*
X1062234Y128955D01*
X1062109Y129247D01*
X1062067Y129580D01*
X1062150Y129997D01*
X1062359Y130289D01*
X1062609Y130372D01*
X1062859Y130330D01*
X1063067Y130164D01*
X1063484Y129330D01*
X1063775Y128955D01*
X1064192Y128705D01*
X1064567Y128622D01*
Y130372D01*
G01X1064192Y131680D02*
X1064400Y131930D01*
X1064525Y132222D01*
X1064567Y132597D01*
X1064484Y132972D01*
X1064317Y133264D01*
X1064025Y133472D01*
X1063692Y133514D01*
X1063359Y133430D01*
X1063150Y133222D01*
X1062984Y132930D01*
X1062942Y132639D01*
X1062984Y132347D01*
X1063150Y131972D01*
X1062067Y132097D01*
Y133222D01*
G01X1065775Y121114D02*
X1065650Y120864D01*
X1065567Y120572D01*
Y120239D01*
X1065692Y119864D01*
X1065900Y119572D01*
X1066150Y119364D01*
X1066567Y119197D01*
X1066942Y119155D01*
X1067317Y119239D01*
X1067567Y119364D01*
X1067817Y119614D01*
X1067984Y119905D01*
X1068067Y120197D01*
Y120489D01*
X1067984Y120780D01*
X1067859Y121030D01*
X1067692Y121239D01*
G01X1068067Y123214D02*
X1067525Y123297D01*
X1067067Y123422D01*
X1066650Y123589D01*
X1066192Y123797D01*
X1065567Y124130D01*
Y122464D01*
G01X1066817Y126647D02*
Y127480D01*
X1067567D01*
X1067817Y127230D01*
X1067984Y126939D01*
X1068067Y126522D01*
X1067984Y126105D01*
X1067817Y125814D01*
X1067567Y125564D01*
X1067275Y125397D01*
X1066942Y125314D01*
X1066650D01*
X1066400Y125397D01*
X1066109Y125564D01*
X1065859Y125814D01*
X1065692Y126064D01*
X1065567Y126397D01*
Y126689D01*
X1065650Y127022D01*
X1065817Y127272D01*
G01X1065984Y128705D02*
X1065734Y128955D01*
X1065609Y129247D01*
X1065567Y129580D01*
X1065650Y129997D01*
X1065859Y130289D01*
X1066109Y130372D01*
X1066359Y130330D01*
X1066567Y130164D01*
X1066984Y129330D01*
X1067275Y128955D01*
X1067692Y128705D01*
X1068067Y128622D01*
Y130372D01*
G01X1067025Y131805D02*
X1066734Y132097D01*
X1066567Y132347D01*
X1066484Y132680D01*
X1066567Y132972D01*
X1066734Y133180D01*
X1066984Y133347D01*
X1067275Y133389D01*
X1067525Y133347D01*
X1067775Y133180D01*
X1067984Y132930D01*
X1068067Y132639D01*
X1067984Y132305D01*
X1067734Y132014D01*
X1067359Y131847D01*
X1066942Y131805D01*
X1066400Y131889D01*
X1066109Y132014D01*
X1065817Y132222D01*
X1065609Y132514D01*
X1065567Y132805D01*
X1065650Y133097D01*
X1065859Y133305D01*
G01X1051775Y121114D02*
X1051650Y120864D01*
X1051567Y120572D01*
Y120239D01*
X1051692Y119864D01*
X1051900Y119572D01*
X1052150Y119364D01*
X1052567Y119197D01*
X1052942Y119155D01*
X1053317Y119239D01*
X1053567Y119364D01*
X1053817Y119614D01*
X1053984Y119905D01*
X1054067Y120197D01*
Y120489D01*
X1053984Y120780D01*
X1053859Y121030D01*
X1053692Y121239D01*
G01X1054067Y123214D02*
X1053525Y123297D01*
X1053067Y123422D01*
X1052650Y123589D01*
X1052192Y123797D01*
X1051567Y124130D01*
Y122464D01*
G01X1052817Y126647D02*
Y127480D01*
X1053567D01*
X1053817Y127230D01*
X1053984Y126939D01*
X1054067Y126522D01*
X1053984Y126105D01*
X1053817Y125814D01*
X1053567Y125564D01*
X1053275Y125397D01*
X1052942Y125314D01*
X1052650D01*
X1052400Y125397D01*
X1052109Y125564D01*
X1051859Y125814D01*
X1051692Y126064D01*
X1051567Y126397D01*
Y126689D01*
X1051650Y127022D01*
X1051817Y127272D01*
G01X1051984Y128705D02*
X1051734Y128955D01*
X1051609Y129247D01*
X1051567Y129580D01*
X1051650Y129997D01*
X1051859Y130289D01*
X1052109Y130372D01*
X1052359Y130330D01*
X1052567Y130164D01*
X1052984Y129330D01*
X1053275Y128955D01*
X1053692Y128705D01*
X1054067Y128622D01*
Y130372D01*
G01X1051984Y131805D02*
X1051734Y132055D01*
X1051609Y132347D01*
X1051567Y132680D01*
X1051650Y133097D01*
X1051859Y133389D01*
X1052109Y133472D01*
X1052359Y133430D01*
X1052567Y133264D01*
X1052984Y132430D01*
X1053275Y132055D01*
X1053692Y131805D01*
X1054067Y131722D01*
Y133472D01*
G01X1090765Y161294D02*
Y168294D01*
X1094232Y162461D01*
X1097699Y168294D01*
Y161294D01*
G01X1040517Y175388D02*
X1040287Y175646D01*
X1040019Y175801D01*
X1039674Y175853D01*
X1039329Y175750D01*
X1039061Y175543D01*
X1038869Y175181D01*
X1038831Y174768D01*
X1038907Y174355D01*
X1039099Y174096D01*
X1039367Y173890D01*
X1039636Y173838D01*
X1039904Y173890D01*
X1040249Y174096D01*
X1040134Y172753D01*
X1039099D01*
G01X1036574D02*
X1036881Y172856D01*
X1037111Y173115D01*
X1037264Y173425D01*
X1037379Y173838D01*
X1037417Y174303D01*
X1037379Y174768D01*
X1037264Y175181D01*
X1037111Y175491D01*
X1036881Y175750D01*
X1036574Y175853D01*
X1036267Y175750D01*
X1036037Y175491D01*
X1035884Y175181D01*
X1035769Y174768D01*
X1035731Y174303D01*
X1035769Y173838D01*
X1035884Y173425D01*
X1036037Y173115D01*
X1036267Y172856D01*
X1036574Y172753D01*
G01X1042702Y180003D02*
Y176903D01*
X1044120Y179125D01*
X1042204D01*
G01X1040714Y179641D02*
X1040445Y179900D01*
X1040139Y180003D01*
X1039832Y179900D01*
X1039564Y179590D01*
X1039372Y179125D01*
X1039295Y178660D01*
Y178091D01*
X1039372Y177626D01*
X1039564Y177213D01*
X1039794Y177006D01*
X1040062Y176903D01*
X1040369Y177006D01*
X1040599Y177213D01*
X1040752Y177523D01*
X1040829Y177936D01*
X1040752Y178298D01*
X1040560Y178660D01*
X1040330Y178866D01*
X1040062Y178918D01*
X1039755Y178815D01*
X1039525Y178556D01*
X1039295Y178091D01*
G01X1045974Y175853D02*
Y172753D01*
X1047392Y174975D01*
X1045476D01*
G01X1043334Y175853D02*
X1043066Y175801D01*
X1042759Y175646D01*
X1042567Y175388D01*
X1042491Y175026D01*
X1042567Y174665D01*
X1042797Y174355D01*
X1043142Y174200D01*
X1043526D01*
X1043756Y174096D01*
X1043947Y173838D01*
X1044024Y173476D01*
X1043909Y173115D01*
X1043641Y172856D01*
X1043334Y172753D01*
X1043027Y172856D01*
X1042759Y173115D01*
X1042644Y173476D01*
X1042721Y173838D01*
X1042912Y174096D01*
X1043142Y174200D01*
X1043526D01*
X1043871Y174355D01*
X1044101Y174665D01*
X1044177Y175026D01*
X1044101Y175388D01*
X1043909Y175646D01*
X1043602Y175801D01*
X1043334Y175853D01*
G01X1049462Y180003D02*
Y176903D01*
X1050880Y179125D01*
X1048964D01*
G01X1046899Y180003D02*
X1046822Y179331D01*
X1046707Y178763D01*
X1046554Y178246D01*
X1046362Y177678D01*
X1046055Y176903D01*
X1047589D01*
G01X1052733Y175853D02*
Y172753D01*
X1054151Y174975D01*
X1052235D01*
G01X1050821Y174561D02*
X1050553Y174200D01*
X1050323Y173993D01*
X1050016Y173890D01*
X1049748Y173993D01*
X1049556Y174200D01*
X1049403Y174510D01*
X1049365Y174871D01*
X1049403Y175181D01*
X1049556Y175491D01*
X1049786Y175750D01*
X1050055Y175853D01*
X1050361Y175750D01*
X1050630Y175440D01*
X1050783Y174975D01*
X1050821Y174458D01*
X1050745Y173786D01*
X1050630Y173425D01*
X1050438Y173063D01*
X1050170Y172805D01*
X1049901Y172753D01*
X1049633Y172856D01*
X1049441Y173115D01*
G01X1056222Y180003D02*
Y176903D01*
X1057640Y179125D01*
X1055724D01*
G01X1054425Y179538D02*
X1054195Y179796D01*
X1053927Y179951D01*
X1053582Y180003D01*
X1053237Y179900D01*
X1052969Y179693D01*
X1052777Y179331D01*
X1052739Y178918D01*
X1052815Y178505D01*
X1053007Y178246D01*
X1053275Y178040D01*
X1053544Y177988D01*
X1053812Y178040D01*
X1054157Y178246D01*
X1054042Y176903D01*
X1053007D01*
G01X1059493Y175853D02*
Y172753D01*
X1060911Y174975D01*
X1058995D01*
G01X1056393Y175853D02*
Y172753D01*
X1057811Y174975D01*
X1055895D01*
G01X1068879Y179404D02*
Y176304D01*
X1070297Y178526D01*
X1068381D01*
G01X1067082Y178784D02*
X1066852Y179146D01*
X1066546Y179352D01*
X1066201Y179404D01*
X1065894Y179352D01*
X1065587Y179094D01*
X1065396Y178784D01*
X1065357Y178474D01*
X1065434Y178112D01*
X1065702Y177854D01*
X1065971Y177751D01*
X1066316D01*
G01X1065971D02*
X1065741Y177596D01*
X1065549Y177337D01*
X1065472Y177027D01*
X1065549Y176717D01*
X1065741Y176459D01*
X1066086Y176304D01*
X1066431Y176356D01*
X1066776Y176562D01*
G01X1072324Y175701D02*
Y172601D01*
X1073742Y174823D01*
X1071826D01*
G01X1070412Y173118D02*
X1070182Y172808D01*
X1069914Y172653D01*
X1069607Y172601D01*
X1069224Y172704D01*
X1068956Y172963D01*
X1068879Y173273D01*
X1068917Y173583D01*
X1069071Y173841D01*
X1069837Y174358D01*
X1070182Y174719D01*
X1070412Y175236D01*
X1070489Y175701D01*
X1068879D01*
G01X1075639Y179404D02*
Y176304D01*
X1077057Y178526D01*
X1075141D01*
G01X1072999Y179404D02*
Y176304D01*
X1073459Y176924D01*
G01Y179404D02*
X1072539D01*
G01X1079084Y175701D02*
Y172601D01*
X1080502Y174823D01*
X1078586D01*
G01X1076444Y172601D02*
X1076751Y172704D01*
X1076981Y172963D01*
X1077134Y173273D01*
X1077249Y173686D01*
X1077287Y174151D01*
X1077249Y174616D01*
X1077134Y175029D01*
X1076981Y175339D01*
X1076751Y175598D01*
X1076444Y175701D01*
X1076137Y175598D01*
X1075907Y175339D01*
X1075754Y175029D01*
X1075639Y174616D01*
X1075601Y174151D01*
X1075639Y173686D01*
X1075754Y173273D01*
X1075907Y172963D01*
X1076137Y172704D01*
X1076444Y172601D01*
G01X1083701Y178784D02*
X1083471Y179146D01*
X1083165Y179352D01*
X1082820Y179404D01*
X1082513Y179352D01*
X1082206Y179094D01*
X1082015Y178784D01*
X1081976Y178474D01*
X1082053Y178112D01*
X1082321Y177854D01*
X1082590Y177751D01*
X1082935D01*
G01X1082590D02*
X1082360Y177596D01*
X1082168Y177337D01*
X1082091Y177027D01*
X1082168Y176717D01*
X1082360Y176459D01*
X1082705Y176304D01*
X1083050Y176356D01*
X1083395Y176562D01*
G01X1080410Y179042D02*
X1080141Y179301D01*
X1079835Y179404D01*
X1079528Y179301D01*
X1079260Y178991D01*
X1079068Y178526D01*
X1078991Y178061D01*
Y177492D01*
X1079068Y177027D01*
X1079260Y176614D01*
X1079490Y176407D01*
X1079758Y176304D01*
X1080065Y176407D01*
X1080295Y176614D01*
X1080448Y176924D01*
X1080525Y177337D01*
X1080448Y177699D01*
X1080256Y178061D01*
X1080026Y178267D01*
X1079758Y178319D01*
X1079451Y178216D01*
X1079221Y177957D01*
X1078991Y177492D01*
G01X1087147Y175081D02*
X1086917Y175443D01*
X1086611Y175649D01*
X1086266Y175701D01*
X1085959Y175649D01*
X1085652Y175391D01*
X1085461Y175081D01*
X1085422Y174771D01*
X1085499Y174409D01*
X1085767Y174151D01*
X1086036Y174048D01*
X1086381D01*
G01X1086036D02*
X1085806Y173893D01*
X1085614Y173634D01*
X1085537Y173324D01*
X1085614Y173014D01*
X1085806Y172756D01*
X1086151Y172601D01*
X1086496Y172653D01*
X1086841Y172859D01*
G01X1083204Y175701D02*
X1082936Y175649D01*
X1082629Y175494D01*
X1082437Y175236D01*
X1082361Y174874D01*
X1082437Y174513D01*
X1082667Y174203D01*
X1083012Y174048D01*
X1083396D01*
X1083626Y173944D01*
X1083817Y173686D01*
X1083894Y173324D01*
X1083779Y172963D01*
X1083511Y172704D01*
X1083204Y172601D01*
X1082897Y172704D01*
X1082629Y172963D01*
X1082514Y173324D01*
X1082591Y173686D01*
X1082782Y173944D01*
X1083012Y174048D01*
X1083396D01*
X1083741Y174203D01*
X1083971Y174513D01*
X1084047Y174874D01*
X1083971Y175236D01*
X1083779Y175494D01*
X1083472Y175649D01*
X1083204Y175701D01*
G01X1090461Y178784D02*
X1090231Y179146D01*
X1089925Y179352D01*
X1089580Y179404D01*
X1089273Y179352D01*
X1088966Y179094D01*
X1088775Y178784D01*
X1088736Y178474D01*
X1088813Y178112D01*
X1089081Y177854D01*
X1089350Y177751D01*
X1089695D01*
G01X1089350D02*
X1089120Y177596D01*
X1088928Y177337D01*
X1088851Y177027D01*
X1088928Y176717D01*
X1089120Y176459D01*
X1089465Y176304D01*
X1089810Y176356D01*
X1090155Y176562D01*
G01X1086595Y179404D02*
X1086518Y178732D01*
X1086403Y178164D01*
X1086250Y177647D01*
X1086058Y177079D01*
X1085751Y176304D01*
X1087285D01*
G01X1093906Y175081D02*
X1093676Y175443D01*
X1093370Y175649D01*
X1093025Y175701D01*
X1092718Y175649D01*
X1092411Y175391D01*
X1092220Y175081D01*
X1092181Y174771D01*
X1092258Y174409D01*
X1092526Y174151D01*
X1092795Y174048D01*
X1093140D01*
G01X1092795D02*
X1092565Y173893D01*
X1092373Y173634D01*
X1092296Y173324D01*
X1092373Y173014D01*
X1092565Y172756D01*
X1092910Y172601D01*
X1093255Y172653D01*
X1093600Y172859D01*
G01X1090691Y174409D02*
X1090423Y174048D01*
X1090193Y173841D01*
X1089886Y173738D01*
X1089618Y173841D01*
X1089426Y174048D01*
X1089273Y174358D01*
X1089235Y174719D01*
X1089273Y175029D01*
X1089426Y175339D01*
X1089656Y175598D01*
X1089925Y175701D01*
X1090231Y175598D01*
X1090500Y175288D01*
X1090653Y174823D01*
X1090691Y174306D01*
X1090615Y173634D01*
X1090500Y173273D01*
X1090308Y172911D01*
X1090040Y172653D01*
X1089771Y172601D01*
X1089503Y172704D01*
X1089311Y172963D01*
G01X1097221Y178784D02*
X1096991Y179146D01*
X1096685Y179352D01*
X1096340Y179404D01*
X1096033Y179352D01*
X1095726Y179094D01*
X1095535Y178784D01*
X1095496Y178474D01*
X1095573Y178112D01*
X1095841Y177854D01*
X1096110Y177751D01*
X1096455D01*
G01X1096110D02*
X1095880Y177596D01*
X1095688Y177337D01*
X1095611Y177027D01*
X1095688Y176717D01*
X1095880Y176459D01*
X1096225Y176304D01*
X1096570Y176356D01*
X1096915Y176562D01*
G01X1094121Y178939D02*
X1093891Y179197D01*
X1093623Y179352D01*
X1093278Y179404D01*
X1092933Y179301D01*
X1092665Y179094D01*
X1092473Y178732D01*
X1092435Y178319D01*
X1092511Y177906D01*
X1092703Y177647D01*
X1092971Y177441D01*
X1093240Y177389D01*
X1093508Y177441D01*
X1093853Y177647D01*
X1093738Y176304D01*
X1092703D01*
G01X1065356Y413582D02*
Y339764D01*
X1088427D01*
X1114372Y324173D01*
Y278582D01*
X1088427Y262992D01*
X1062994D01*
Y189173D01*
X1065356D01*
Y185236D01*
X1069293D01*
Y189173D01*
X1196852D01*
Y179134D01*
X1224411D01*
Y269882D01*
X1210632Y283661D01*
Y289567D01*
X1208663D01*
Y313189D01*
X1210632D01*
Y319094D01*
X1224411Y332874D01*
Y423622D01*
X1196852D01*
Y413582D01*
X1069293D01*
Y417519D01*
X1065356D01*
Y339764D01*
X1088427D01*
X1114372Y324173D01*
Y278582D01*
X1088427Y262992D01*
X1062994D01*
G01X1075840Y450160D02*
X1057430D01*
Y418570D01*
X1158770D01*
Y450160D01*
X1132380D01*
G01X1091099Y443645D02*
Y446145D01*
X1092140D01*
X1092474Y446020D01*
X1092682Y445853D01*
X1092765Y445520D01*
X1092682Y445187D01*
X1092432Y444978D01*
X1092140Y444853D01*
X1091099D01*
G01X1092140D02*
X1092765Y443645D01*
G01X1094240Y445728D02*
X1094490Y445978D01*
X1094782Y446103D01*
X1095115Y446145D01*
X1095532Y446062D01*
X1095824Y445853D01*
X1095907Y445603D01*
X1095865Y445353D01*
X1095699Y445145D01*
X1094865Y444728D01*
X1094490Y444437D01*
X1094240Y444020D01*
X1094157Y443645D01*
X1095907D01*
G01X1097215Y444020D02*
X1097465Y443812D01*
X1097757Y443687D01*
X1098132Y443645D01*
X1098507Y443728D01*
X1098799Y443895D01*
X1099007Y444187D01*
X1099049Y444520D01*
X1098965Y444853D01*
X1098757Y445062D01*
X1098465Y445228D01*
X1098174Y445270D01*
X1097882Y445228D01*
X1097507Y445062D01*
X1097632Y446145D01*
X1098757D01*
G01X1099982D02*
X1100565Y443645D01*
X1101232Y446145D01*
X1101899Y443645D01*
X1102482Y446145D01*
G01X1103540Y444687D02*
X1103832Y444978D01*
X1104082Y445145D01*
X1104415Y445228D01*
X1104707Y445145D01*
X1104915Y444978D01*
X1105082Y444728D01*
X1105124Y444437D01*
X1105082Y444187D01*
X1104915Y443937D01*
X1104665Y443728D01*
X1104374Y443645D01*
X1104040Y443728D01*
X1103749Y443978D01*
X1103582Y444353D01*
X1103540Y444770D01*
X1103624Y445312D01*
X1103749Y445603D01*
X1103957Y445895D01*
X1104249Y446103D01*
X1104540Y446145D01*
X1104832Y446062D01*
X1105040Y445853D01*
G01X1106640Y445728D02*
X1106890Y445978D01*
X1107182Y446103D01*
X1107515Y446145D01*
X1107932Y446062D01*
X1108224Y445853D01*
X1108307Y445603D01*
X1108265Y445353D01*
X1108099Y445145D01*
X1107265Y444728D01*
X1106890Y444437D01*
X1106640Y444020D01*
X1106557Y443645D01*
X1108307D01*
G01X1072759Y421923D02*
X1070259D01*
Y422964D01*
X1070384Y423298D01*
X1070551Y423506D01*
X1070884Y423589D01*
X1071217Y423506D01*
X1071426Y423256D01*
X1071551Y422964D01*
Y421923D01*
G01Y422964D02*
X1072759Y423589D01*
G01Y425856D02*
X1070259D01*
X1070759Y425356D01*
G01X1072759D02*
Y426356D01*
G01X1070259Y428956D02*
X1072759D01*
G01X1070259Y427998D02*
Y429914D01*
G01X1072759Y432056D02*
X1070259D01*
X1070759Y431556D01*
G01X1072759D02*
Y432556D01*
G01X1070676Y434364D02*
X1070426Y434614D01*
X1070301Y434906D01*
X1070259Y435239D01*
X1070342Y435656D01*
X1070551Y435948D01*
X1070801Y436031D01*
X1071051Y435989D01*
X1071259Y435823D01*
X1071676Y434989D01*
X1071967Y434614D01*
X1072384Y434364D01*
X1072759Y434281D01*
Y436031D01*
G01X1069059Y421923D02*
X1066559D01*
Y422964D01*
X1066684Y423298D01*
X1066851Y423506D01*
X1067184Y423589D01*
X1067517Y423506D01*
X1067726Y423256D01*
X1067851Y422964D01*
Y421923D01*
G01Y422964D02*
X1069059Y423589D01*
G01X1066976Y425064D02*
X1066726Y425314D01*
X1066601Y425606D01*
X1066559Y425939D01*
X1066642Y426356D01*
X1066851Y426648D01*
X1067101Y426731D01*
X1067351Y426689D01*
X1067559Y426523D01*
X1067976Y425689D01*
X1068267Y425314D01*
X1068684Y425064D01*
X1069059Y424981D01*
Y426731D01*
G01X1068684Y428039D02*
X1068892Y428289D01*
X1069017Y428581D01*
X1069059Y428956D01*
X1068976Y429331D01*
X1068809Y429623D01*
X1068517Y429831D01*
X1068184Y429873D01*
X1067851Y429789D01*
X1067642Y429581D01*
X1067476Y429289D01*
X1067434Y428998D01*
X1067476Y428706D01*
X1067642Y428331D01*
X1066559Y428456D01*
Y429581D01*
G01Y430806D02*
X1069059Y431389D01*
X1066559Y432056D01*
X1069059Y432723D01*
X1066559Y433306D01*
G01X1068017Y434364D02*
X1067726Y434656D01*
X1067559Y434906D01*
X1067476Y435239D01*
X1067559Y435531D01*
X1067726Y435739D01*
X1067976Y435906D01*
X1068267Y435948D01*
X1068517Y435906D01*
X1068767Y435739D01*
X1068976Y435489D01*
X1069059Y435198D01*
X1068976Y434864D01*
X1068726Y434573D01*
X1068351Y434406D01*
X1067934Y434364D01*
X1067392Y434448D01*
X1067101Y434573D01*
X1066809Y434781D01*
X1066601Y435073D01*
X1066559Y435364D01*
X1066642Y435656D01*
X1066851Y435864D01*
G01X1068017Y437464D02*
X1067726Y437756D01*
X1067559Y438006D01*
X1067476Y438339D01*
X1067559Y438631D01*
X1067726Y438839D01*
X1067976Y439006D01*
X1068267Y439048D01*
X1068517Y439006D01*
X1068767Y438839D01*
X1068976Y438589D01*
X1069059Y438298D01*
X1068976Y437964D01*
X1068726Y437673D01*
X1068351Y437506D01*
X1067934Y437464D01*
X1067392Y437548D01*
X1067101Y437673D01*
X1066809Y437881D01*
X1066601Y438173D01*
X1066559Y438464D01*
X1066642Y438756D01*
X1066851Y438964D01*
G01X1080159Y421923D02*
X1077659D01*
Y422964D01*
X1077784Y423298D01*
X1077951Y423506D01*
X1078284Y423589D01*
X1078617Y423506D01*
X1078826Y423256D01*
X1078951Y422964D01*
Y421923D01*
G01Y422964D02*
X1080159Y423589D01*
G01Y425856D02*
X1077659D01*
X1078159Y425356D01*
G01X1080159D02*
Y426356D01*
G01X1077659Y428956D02*
X1080159D01*
G01X1077659Y427998D02*
Y429914D01*
G01X1080159Y432056D02*
X1077659D01*
X1078159Y431556D01*
G01X1080159D02*
Y432556D01*
G01Y435156D02*
X1077659D01*
X1078159Y434656D01*
G01X1080159D02*
Y435656D01*
G01X1076459Y421923D02*
X1073959D01*
Y422964D01*
X1074084Y423298D01*
X1074251Y423506D01*
X1074584Y423589D01*
X1074917Y423506D01*
X1075126Y423256D01*
X1075251Y422964D01*
Y421923D01*
G01Y422964D02*
X1076459Y423589D01*
G01Y425856D02*
X1073959D01*
X1074459Y425356D01*
G01X1076459D02*
Y426356D01*
G01X1073959Y428956D02*
X1076459D01*
G01X1073959Y427998D02*
Y429914D01*
G01X1076459Y432056D02*
X1073959D01*
X1074459Y431556D01*
G01X1076459D02*
Y432556D01*
G01X1073959Y435156D02*
X1074042Y434823D01*
X1074251Y434573D01*
X1074501Y434406D01*
X1074834Y434281D01*
X1075209Y434239D01*
X1075584Y434281D01*
X1075917Y434406D01*
X1076167Y434573D01*
X1076376Y434823D01*
X1076459Y435156D01*
X1076376Y435489D01*
X1076167Y435739D01*
X1075917Y435906D01*
X1075584Y436031D01*
X1075209Y436073D01*
X1074834Y436031D01*
X1074501Y435906D01*
X1074251Y435739D01*
X1074042Y435489D01*
X1073959Y435156D01*
G01X1059099Y443645D02*
Y446145D01*
X1060140D01*
X1060474Y446020D01*
X1060682Y445853D01*
X1060765Y445520D01*
X1060682Y445187D01*
X1060432Y444978D01*
X1060140Y444853D01*
X1059099D01*
G01X1060140D02*
X1060765Y443645D01*
G01X1063032D02*
X1063324Y443687D01*
X1063657Y443812D01*
X1063865Y444020D01*
X1063949Y444312D01*
X1063865Y444603D01*
X1063615Y444853D01*
X1063240Y444978D01*
X1062824D01*
X1062574Y445062D01*
X1062365Y445270D01*
X1062282Y445562D01*
X1062407Y445853D01*
X1062699Y446062D01*
X1063032Y446145D01*
X1063365Y446062D01*
X1063657Y445853D01*
X1063782Y445562D01*
X1063699Y445270D01*
X1063490Y445062D01*
X1063240Y444978D01*
X1062824D01*
X1062449Y444853D01*
X1062199Y444603D01*
X1062115Y444312D01*
X1062199Y444020D01*
X1062407Y443812D01*
X1062740Y443687D01*
X1063032Y443645D01*
G01X1065215D02*
Y446145D01*
X1066049D01*
X1066382Y446020D01*
X1066632Y445853D01*
X1066840Y445603D01*
X1067007Y445312D01*
X1067049Y444895D01*
X1067007Y444478D01*
X1066840Y444187D01*
X1066632Y443937D01*
X1066382Y443770D01*
X1066049Y443645D01*
X1065215D01*
G01X1068440Y445728D02*
X1068690Y445978D01*
X1068982Y446103D01*
X1069315Y446145D01*
X1069732Y446062D01*
X1070024Y445853D01*
X1070107Y445603D01*
X1070065Y445353D01*
X1069899Y445145D01*
X1069065Y444728D01*
X1068690Y444437D01*
X1068440Y444020D01*
X1068357Y443645D01*
X1070107D01*
G01X1072249D02*
X1072332Y444187D01*
X1072457Y444645D01*
X1072624Y445062D01*
X1072832Y445520D01*
X1073165Y446145D01*
X1071499D01*
G01X1075099Y443645D02*
Y446145D01*
X1076140D01*
X1076474Y446020D01*
X1076682Y445853D01*
X1076765Y445520D01*
X1076682Y445187D01*
X1076432Y444978D01*
X1076140Y444853D01*
X1075099D01*
G01X1076140D02*
X1076765Y443645D01*
G01X1079032D02*
X1079324Y443687D01*
X1079657Y443812D01*
X1079865Y444020D01*
X1079949Y444312D01*
X1079865Y444603D01*
X1079615Y444853D01*
X1079240Y444978D01*
X1078824D01*
X1078574Y445062D01*
X1078365Y445270D01*
X1078282Y445562D01*
X1078407Y445853D01*
X1078699Y446062D01*
X1079032Y446145D01*
X1079365Y446062D01*
X1079657Y445853D01*
X1079782Y445562D01*
X1079699Y445270D01*
X1079490Y445062D01*
X1079240Y444978D01*
X1078824D01*
X1078449Y444853D01*
X1078199Y444603D01*
X1078115Y444312D01*
X1078199Y444020D01*
X1078407Y443812D01*
X1078740Y443687D01*
X1079032Y443645D01*
G01X1081215D02*
Y446145D01*
X1082049D01*
X1082382Y446020D01*
X1082632Y445853D01*
X1082840Y445603D01*
X1083007Y445312D01*
X1083049Y444895D01*
X1083007Y444478D01*
X1082840Y444187D01*
X1082632Y443937D01*
X1082382Y443770D01*
X1082049Y443645D01*
X1081215D01*
G01X1084440Y445728D02*
X1084690Y445978D01*
X1084982Y446103D01*
X1085315Y446145D01*
X1085732Y446062D01*
X1086024Y445853D01*
X1086107Y445603D01*
X1086065Y445353D01*
X1085899Y445145D01*
X1085065Y444728D01*
X1084690Y444437D01*
X1084440Y444020D01*
X1084357Y443645D01*
X1086107D01*
G01X1088332D02*
X1088624Y443687D01*
X1088957Y443812D01*
X1089165Y444020D01*
X1089249Y444312D01*
X1089165Y444603D01*
X1088915Y444853D01*
X1088540Y444978D01*
X1088124D01*
X1087874Y445062D01*
X1087665Y445270D01*
X1087582Y445562D01*
X1087707Y445853D01*
X1087999Y446062D01*
X1088332Y446145D01*
X1088665Y446062D01*
X1088957Y445853D01*
X1089082Y445562D01*
X1088999Y445270D01*
X1088790Y445062D01*
X1088540Y444978D01*
X1088124D01*
X1087749Y444853D01*
X1087499Y444603D01*
X1087415Y444312D01*
X1087499Y444020D01*
X1087707Y443812D01*
X1088040Y443687D01*
X1088332Y443645D01*
G01X1035018Y427213D02*
Y429713D01*
X1036059D01*
X1036393Y429588D01*
X1036601Y429421D01*
X1036684Y429088D01*
X1036601Y428755D01*
X1036351Y428546D01*
X1036059Y428421D01*
X1035018D01*
G01X1036059D02*
X1036684Y427213D01*
G01X1038951D02*
X1039243Y427255D01*
X1039576Y427380D01*
X1039784Y427588D01*
X1039868Y427880D01*
X1039784Y428171D01*
X1039534Y428421D01*
X1039159Y428546D01*
X1038743D01*
X1038493Y428630D01*
X1038284Y428838D01*
X1038201Y429130D01*
X1038326Y429421D01*
X1038618Y429630D01*
X1038951Y429713D01*
X1039284Y429630D01*
X1039576Y429421D01*
X1039701Y429130D01*
X1039618Y428838D01*
X1039409Y428630D01*
X1039159Y428546D01*
X1038743D01*
X1038368Y428421D01*
X1038118Y428171D01*
X1038034Y427880D01*
X1038118Y427588D01*
X1038326Y427380D01*
X1038659Y427255D01*
X1038951Y427213D01*
G01X1042301Y428463D02*
X1043134D01*
Y427713D01*
X1042884Y427463D01*
X1042593Y427296D01*
X1042176Y427213D01*
X1041759Y427296D01*
X1041468Y427463D01*
X1041218Y427713D01*
X1041051Y428005D01*
X1040968Y428338D01*
Y428630D01*
X1041051Y428880D01*
X1041218Y429171D01*
X1041468Y429421D01*
X1041718Y429588D01*
X1042051Y429713D01*
X1042343D01*
X1042676Y429630D01*
X1042926Y429463D01*
G01X1045151Y427213D02*
Y429713D01*
X1044651Y429213D01*
G01Y427213D02*
X1045651D01*
G01X1048251D02*
X1048543Y427255D01*
X1048876Y427380D01*
X1049084Y427588D01*
X1049168Y427880D01*
X1049084Y428171D01*
X1048834Y428421D01*
X1048459Y428546D01*
X1048043D01*
X1047793Y428630D01*
X1047584Y428838D01*
X1047501Y429130D01*
X1047626Y429421D01*
X1047918Y429630D01*
X1048251Y429713D01*
X1048584Y429630D01*
X1048876Y429421D01*
X1049001Y429130D01*
X1048918Y428838D01*
X1048709Y428630D01*
X1048459Y428546D01*
X1048043D01*
X1047668Y428421D01*
X1047418Y428171D01*
X1047334Y427880D01*
X1047418Y427588D01*
X1047626Y427380D01*
X1047959Y427255D01*
X1048251Y427213D01*
G01X1035018Y435513D02*
Y438013D01*
X1036059D01*
X1036393Y437888D01*
X1036601Y437721D01*
X1036684Y437388D01*
X1036601Y437055D01*
X1036351Y436846D01*
X1036059Y436721D01*
X1035018D01*
G01X1036059D02*
X1036684Y435513D01*
G01X1038868D02*
X1038951Y436055D01*
X1039076Y436513D01*
X1039243Y436930D01*
X1039451Y437388D01*
X1039784Y438013D01*
X1038118D01*
G01X1042301Y436763D02*
X1043134D01*
Y436013D01*
X1042884Y435763D01*
X1042593Y435596D01*
X1042176Y435513D01*
X1041759Y435596D01*
X1041468Y435763D01*
X1041218Y436013D01*
X1041051Y436305D01*
X1040968Y436638D01*
Y436930D01*
X1041051Y437180D01*
X1041218Y437471D01*
X1041468Y437721D01*
X1041718Y437888D01*
X1042051Y438013D01*
X1042343D01*
X1042676Y437930D01*
X1042926Y437763D01*
G01X1045151Y435513D02*
Y438013D01*
X1044651Y437513D01*
G01Y435513D02*
X1045651D01*
G01X1048751D02*
Y438013D01*
X1047209Y436221D01*
X1049293D01*
G01X1061659Y420923D02*
X1059159D01*
Y421964D01*
X1059284Y422298D01*
X1059451Y422506D01*
X1059784Y422589D01*
X1060117Y422506D01*
X1060326Y422256D01*
X1060451Y421964D01*
Y420923D01*
G01Y421964D02*
X1061659Y422589D01*
G01X1059576Y424064D02*
X1059326Y424314D01*
X1059201Y424606D01*
X1059159Y424939D01*
X1059242Y425356D01*
X1059451Y425648D01*
X1059701Y425731D01*
X1059951Y425689D01*
X1060159Y425523D01*
X1060576Y424689D01*
X1060867Y424314D01*
X1061284Y424064D01*
X1061659Y423981D01*
Y425731D01*
G01X1059159Y427956D02*
X1061659D01*
G01X1059159Y426998D02*
Y428914D01*
G01X1060617Y430264D02*
X1060326Y430556D01*
X1060159Y430806D01*
X1060076Y431139D01*
X1060159Y431431D01*
X1060326Y431639D01*
X1060576Y431806D01*
X1060867Y431848D01*
X1061117Y431806D01*
X1061367Y431639D01*
X1061576Y431389D01*
X1061659Y431098D01*
X1061576Y430764D01*
X1061326Y430473D01*
X1060951Y430306D01*
X1060534Y430264D01*
X1059992Y430348D01*
X1059701Y430473D01*
X1059409Y430681D01*
X1059201Y430973D01*
X1059159Y431264D01*
X1059242Y431556D01*
X1059451Y431764D01*
G01X1061159Y433239D02*
X1061451Y433489D01*
X1061617Y433823D01*
X1061659Y434198D01*
X1061617Y434531D01*
X1061409Y434864D01*
X1061159Y435073D01*
X1060909Y435114D01*
X1060617Y435031D01*
X1060409Y434739D01*
X1060326Y434448D01*
Y434073D01*
G01Y434448D02*
X1060201Y434698D01*
X1059992Y434906D01*
X1059742Y434989D01*
X1059492Y434906D01*
X1059284Y434698D01*
X1059159Y434323D01*
X1059201Y433948D01*
X1059367Y433573D01*
G01X1065359Y420923D02*
X1062859D01*
Y421964D01*
X1062984Y422298D01*
X1063151Y422506D01*
X1063484Y422589D01*
X1063817Y422506D01*
X1064026Y422256D01*
X1064151Y421964D01*
Y420923D01*
G01Y421964D02*
X1065359Y422589D01*
G01X1063276Y424064D02*
X1063026Y424314D01*
X1062901Y424606D01*
X1062859Y424939D01*
X1062942Y425356D01*
X1063151Y425648D01*
X1063401Y425731D01*
X1063651Y425689D01*
X1063859Y425523D01*
X1064276Y424689D01*
X1064567Y424314D01*
X1064984Y424064D01*
X1065359Y423981D01*
Y425731D01*
G01X1062859Y427956D02*
X1065359D01*
G01X1062859Y426998D02*
Y428914D01*
G01X1064317Y430264D02*
X1064026Y430556D01*
X1063859Y430806D01*
X1063776Y431139D01*
X1063859Y431431D01*
X1064026Y431639D01*
X1064276Y431806D01*
X1064567Y431848D01*
X1064817Y431806D01*
X1065067Y431639D01*
X1065276Y431389D01*
X1065359Y431098D01*
X1065276Y430764D01*
X1065026Y430473D01*
X1064651Y430306D01*
X1064234Y430264D01*
X1063692Y430348D01*
X1063401Y430473D01*
X1063109Y430681D01*
X1062901Y430973D01*
X1062859Y431264D01*
X1062942Y431556D01*
X1063151Y431764D01*
G01X1065359Y434656D02*
X1062859D01*
X1064651Y433114D01*
Y435198D01*
G01X1083707Y421745D02*
X1081207D01*
Y422786D01*
X1081332Y423120D01*
X1081499Y423328D01*
X1081832Y423411D01*
X1082165Y423328D01*
X1082374Y423078D01*
X1082499Y422786D01*
Y421745D01*
G01Y422786D02*
X1083707Y423411D01*
G01X1081624Y424886D02*
X1081374Y425136D01*
X1081249Y425428D01*
X1081207Y425761D01*
X1081290Y426178D01*
X1081499Y426470D01*
X1081749Y426553D01*
X1081999Y426511D01*
X1082207Y426345D01*
X1082624Y425511D01*
X1082915Y425136D01*
X1083332Y424886D01*
X1083707Y424803D01*
Y426553D01*
G01X1083332Y427861D02*
X1083540Y428111D01*
X1083665Y428403D01*
X1083707Y428778D01*
X1083624Y429153D01*
X1083457Y429445D01*
X1083165Y429653D01*
X1082832Y429695D01*
X1082499Y429611D01*
X1082290Y429403D01*
X1082124Y429111D01*
X1082082Y428820D01*
X1082124Y428528D01*
X1082290Y428153D01*
X1081207Y428278D01*
Y429403D01*
G01Y430628D02*
X1083707Y431211D01*
X1081207Y431878D01*
X1083707Y432545D01*
X1081207Y433128D01*
G01X1082665Y434186D02*
X1082374Y434478D01*
X1082207Y434728D01*
X1082124Y435061D01*
X1082207Y435353D01*
X1082374Y435561D01*
X1082624Y435728D01*
X1082915Y435770D01*
X1083165Y435728D01*
X1083415Y435561D01*
X1083624Y435311D01*
X1083707Y435020D01*
X1083624Y434686D01*
X1083374Y434395D01*
X1082999Y434228D01*
X1082582Y434186D01*
X1082040Y434270D01*
X1081749Y434395D01*
X1081457Y434603D01*
X1081249Y434895D01*
X1081207Y435186D01*
X1081290Y435478D01*
X1081499Y435686D01*
G01X1083707Y438078D02*
X1081207D01*
X1081707Y437578D01*
G01X1083707D02*
Y438578D01*
G01X1087407Y421745D02*
X1084907D01*
Y422786D01*
X1085032Y423120D01*
X1085199Y423328D01*
X1085532Y423411D01*
X1085865Y423328D01*
X1086074Y423078D01*
X1086199Y422786D01*
Y421745D01*
G01Y422786D02*
X1087407Y423411D01*
G01X1085324Y424886D02*
X1085074Y425136D01*
X1084949Y425428D01*
X1084907Y425761D01*
X1084990Y426178D01*
X1085199Y426470D01*
X1085449Y426553D01*
X1085699Y426511D01*
X1085907Y426345D01*
X1086324Y425511D01*
X1086615Y425136D01*
X1087032Y424886D01*
X1087407Y424803D01*
Y426553D01*
G01X1087032Y427861D02*
X1087240Y428111D01*
X1087365Y428403D01*
X1087407Y428778D01*
X1087324Y429153D01*
X1087157Y429445D01*
X1086865Y429653D01*
X1086532Y429695D01*
X1086199Y429611D01*
X1085990Y429403D01*
X1085824Y429111D01*
X1085782Y428820D01*
X1085824Y428528D01*
X1085990Y428153D01*
X1084907Y428278D01*
Y429403D01*
G01Y430628D02*
X1087407Y431211D01*
X1084907Y431878D01*
X1087407Y432545D01*
X1084907Y433128D01*
G01X1086365Y434186D02*
X1086074Y434478D01*
X1085907Y434728D01*
X1085824Y435061D01*
X1085907Y435353D01*
X1086074Y435561D01*
X1086324Y435728D01*
X1086615Y435770D01*
X1086865Y435728D01*
X1087115Y435561D01*
X1087324Y435311D01*
X1087407Y435020D01*
X1087324Y434686D01*
X1087074Y434395D01*
X1086699Y434228D01*
X1086282Y434186D01*
X1085740Y434270D01*
X1085449Y434395D01*
X1085157Y434603D01*
X1084949Y434895D01*
X1084907Y435186D01*
X1084990Y435478D01*
X1085199Y435686D01*
G01X1084907Y438078D02*
X1084990Y437745D01*
X1085199Y437495D01*
X1085449Y437328D01*
X1085782Y437203D01*
X1086157Y437161D01*
X1086532Y437203D01*
X1086865Y437328D01*
X1087115Y437495D01*
X1087324Y437745D01*
X1087407Y438078D01*
X1087324Y438411D01*
X1087115Y438661D01*
X1086865Y438828D01*
X1086532Y438953D01*
X1086157Y438995D01*
X1085782Y438953D01*
X1085449Y438828D01*
X1085199Y438661D01*
X1084990Y438411D01*
X1084907Y438078D01*
G01X1090987Y421840D02*
X1088487D01*
Y422881D01*
X1088612Y423215D01*
X1088779Y423423D01*
X1089112Y423506D01*
X1089445Y423423D01*
X1089654Y423173D01*
X1089779Y422881D01*
Y421840D01*
G01Y422881D02*
X1090987Y423506D01*
G01X1088904Y424981D02*
X1088654Y425231D01*
X1088529Y425523D01*
X1088487Y425856D01*
X1088570Y426273D01*
X1088779Y426565D01*
X1089029Y426648D01*
X1089279Y426606D01*
X1089487Y426440D01*
X1089904Y425606D01*
X1090195Y425231D01*
X1090612Y424981D01*
X1090987Y424898D01*
Y426648D01*
G01X1090612Y427956D02*
X1090820Y428206D01*
X1090945Y428498D01*
X1090987Y428873D01*
X1090904Y429248D01*
X1090737Y429540D01*
X1090445Y429748D01*
X1090112Y429790D01*
X1089779Y429706D01*
X1089570Y429498D01*
X1089404Y429206D01*
X1089362Y428915D01*
X1089404Y428623D01*
X1089570Y428248D01*
X1088487Y428373D01*
Y429498D01*
G01Y430723D02*
X1090987Y431306D01*
X1088487Y431973D01*
X1090987Y432640D01*
X1088487Y433223D01*
G01X1090987Y435073D02*
X1088487D01*
X1088987Y434573D01*
G01X1090987D02*
Y435573D01*
G01Y438673D02*
X1088487D01*
X1090279Y437131D01*
Y439215D01*
G01X1090987Y441273D02*
X1088487D01*
X1088987Y440773D01*
G01X1090987D02*
Y441773D01*
G01X1035018Y431513D02*
Y434013D01*
X1036059D01*
X1036393Y433888D01*
X1036601Y433721D01*
X1036684Y433388D01*
X1036601Y433055D01*
X1036351Y432846D01*
X1036059Y432721D01*
X1035018D01*
G01X1036059D02*
X1036684Y431513D01*
G01X1038868D02*
X1038951Y432055D01*
X1039076Y432513D01*
X1039243Y432930D01*
X1039451Y433388D01*
X1039784Y434013D01*
X1038118D01*
G01X1042301Y432763D02*
X1043134D01*
Y432013D01*
X1042884Y431763D01*
X1042593Y431596D01*
X1042176Y431513D01*
X1041759Y431596D01*
X1041468Y431763D01*
X1041218Y432013D01*
X1041051Y432305D01*
X1040968Y432638D01*
Y432930D01*
X1041051Y433180D01*
X1041218Y433471D01*
X1041468Y433721D01*
X1041718Y433888D01*
X1042051Y434013D01*
X1042343D01*
X1042676Y433930D01*
X1042926Y433763D01*
G01X1045151Y431513D02*
Y434013D01*
X1044651Y433513D01*
G01Y431513D02*
X1045651D01*
G01X1048251D02*
Y434013D01*
X1047751Y433513D01*
G01Y431513D02*
X1048751D01*
G01X1051851D02*
Y434013D01*
X1050309Y432221D01*
X1052393D01*
G01X1092667Y423673D02*
X1092542Y423423D01*
X1092459Y423131D01*
Y422798D01*
X1092584Y422423D01*
X1092792Y422131D01*
X1093042Y421923D01*
X1093459Y421756D01*
X1093834Y421714D01*
X1094209Y421798D01*
X1094459Y421923D01*
X1094709Y422173D01*
X1094876Y422464D01*
X1094959Y422756D01*
Y423048D01*
X1094876Y423339D01*
X1094751Y423589D01*
X1094584Y423798D01*
G01X1092876Y425064D02*
X1092626Y425314D01*
X1092501Y425606D01*
X1092459Y425939D01*
X1092542Y426356D01*
X1092751Y426648D01*
X1093001Y426731D01*
X1093251Y426689D01*
X1093459Y426523D01*
X1093876Y425689D01*
X1094167Y425314D01*
X1094584Y425064D01*
X1094959Y424981D01*
Y426731D01*
G01X1094584Y428039D02*
X1094792Y428289D01*
X1094917Y428581D01*
X1094959Y428956D01*
X1094876Y429331D01*
X1094709Y429623D01*
X1094417Y429831D01*
X1094084Y429873D01*
X1093751Y429789D01*
X1093542Y429581D01*
X1093376Y429289D01*
X1093334Y428998D01*
X1093376Y428706D01*
X1093542Y428331D01*
X1092459Y428456D01*
Y429581D01*
G01Y430806D02*
X1094959Y431389D01*
X1092459Y432056D01*
X1094959Y432723D01*
X1092459Y433306D01*
G01X1092876Y434364D02*
X1092626Y434614D01*
X1092501Y434906D01*
X1092459Y435239D01*
X1092542Y435656D01*
X1092751Y435948D01*
X1093001Y436031D01*
X1093251Y435989D01*
X1093459Y435823D01*
X1093876Y434989D01*
X1094167Y434614D01*
X1094584Y434364D01*
X1094959Y434281D01*
Y436031D01*
G01Y438256D02*
X1092459D01*
X1092959Y437756D01*
G01X1094959D02*
Y438756D01*
G01X1050935Y478529D02*
Y485529D01*
X1056001D01*
G01X1054135Y482146D02*
X1050935D01*
G01X1158717Y468704D02*
Y468700D01*
X1075841D01*
X1075840Y468699D01*
G01X1063917Y504600D02*
Y507100D01*
X1064958D01*
X1065292Y506975D01*
X1065500Y506808D01*
X1065583Y506475D01*
X1065500Y506142D01*
X1065250Y505933D01*
X1064958Y505808D01*
X1063917D01*
G01X1064958D02*
X1065583Y504600D01*
G01X1067850Y507100D02*
Y504600D01*
G01X1066892Y507100D02*
X1068808D01*
G01X1071450Y504600D02*
Y507100D01*
X1069908Y505308D01*
X1071992D01*
G01X1074550Y504600D02*
Y507100D01*
X1073008Y505308D01*
X1075092D01*
G01X1090585Y502629D02*
Y505129D01*
X1091626D01*
X1091960Y505004D01*
X1092168Y504837D01*
X1092251Y504504D01*
X1092168Y504171D01*
X1091918Y503962D01*
X1091626Y503837D01*
X1090585D01*
G01X1091626D02*
X1092251Y502629D01*
G01X1094518Y505129D02*
Y502629D01*
G01X1093560Y505129D02*
X1095476D01*
G01X1098118Y502629D02*
Y505129D01*
X1096576Y503337D01*
X1098660D01*
G01X1099926Y503671D02*
X1100218Y503962D01*
X1100468Y504129D01*
X1100801Y504212D01*
X1101093Y504129D01*
X1101301Y503962D01*
X1101468Y503712D01*
X1101510Y503421D01*
X1101468Y503171D01*
X1101301Y502921D01*
X1101051Y502712D01*
X1100760Y502629D01*
X1100426Y502712D01*
X1100135Y502962D01*
X1099968Y503337D01*
X1099926Y503754D01*
X1100010Y504296D01*
X1100135Y504587D01*
X1100343Y504879D01*
X1100635Y505087D01*
X1100926Y505129D01*
X1101218Y505046D01*
X1101426Y504837D01*
G01X1096035Y493621D02*
X1095785Y493746D01*
X1095493Y493829D01*
X1095160D01*
X1094785Y493704D01*
X1094493Y493496D01*
X1094285Y493246D01*
X1094118Y492829D01*
X1094076Y492454D01*
X1094160Y492079D01*
X1094285Y491829D01*
X1094535Y491579D01*
X1094826Y491412D01*
X1095118Y491329D01*
X1095410D01*
X1095701Y491412D01*
X1095951Y491537D01*
X1096160Y491704D01*
G01X1098135Y491329D02*
X1098218Y491871D01*
X1098343Y492329D01*
X1098510Y492746D01*
X1098718Y493204D01*
X1099051Y493829D01*
X1097385D01*
G01X1100276Y491329D02*
X1101318Y493829D01*
X1102360Y491329D01*
G01X1101985Y492204D02*
X1100651D01*
G01X1103710Y491621D02*
X1104001Y491412D01*
X1104335Y491329D01*
X1104668Y491412D01*
X1104960Y491662D01*
X1105168Y492037D01*
X1105251Y492412D01*
Y492871D01*
X1105168Y493246D01*
X1104960Y493579D01*
X1104710Y493746D01*
X1104418Y493829D01*
X1104085Y493746D01*
X1103835Y493579D01*
X1103668Y493329D01*
X1103585Y492996D01*
X1103668Y492704D01*
X1103876Y492412D01*
X1104126Y492246D01*
X1104418Y492204D01*
X1104751Y492287D01*
X1105001Y492496D01*
X1105251Y492871D01*
G01X1071803Y474508D02*
X1071678Y474258D01*
X1071595Y473966D01*
Y473633D01*
X1071720Y473258D01*
X1071928Y472966D01*
X1072178Y472758D01*
X1072595Y472591D01*
X1072970Y472549D01*
X1073345Y472633D01*
X1073595Y472758D01*
X1073845Y473008D01*
X1074012Y473299D01*
X1074095Y473591D01*
Y473883D01*
X1074012Y474174D01*
X1073887Y474424D01*
X1073720Y474633D01*
G01X1074095Y476608D02*
X1073553Y476691D01*
X1073095Y476816D01*
X1072678Y476983D01*
X1072220Y477191D01*
X1071595Y477524D01*
Y475858D01*
G01X1074095Y478749D02*
X1071595Y479791D01*
X1074095Y480833D01*
G01X1073220Y480458D02*
Y479124D01*
G01X1074095Y483391D02*
X1071595D01*
X1073387Y481849D01*
Y483933D01*
G01X1074095Y485991D02*
X1071595D01*
X1072095Y485491D01*
G01X1074095D02*
Y486491D01*
G01X1037465Y475958D02*
X1037340Y475708D01*
X1037257Y475416D01*
Y475083D01*
X1037382Y474708D01*
X1037590Y474416D01*
X1037840Y474208D01*
X1038257Y474041D01*
X1038632Y473999D01*
X1039007Y474083D01*
X1039257Y474208D01*
X1039507Y474458D01*
X1039674Y474749D01*
X1039757Y475041D01*
Y475333D01*
X1039674Y475624D01*
X1039549Y475874D01*
X1039382Y476083D01*
G01X1039757Y478058D02*
X1039215Y478141D01*
X1038757Y478266D01*
X1038340Y478433D01*
X1037882Y478641D01*
X1037257Y478974D01*
Y477308D01*
G01X1039757Y480199D02*
X1037257Y481241D01*
X1039757Y482283D01*
G01X1038882Y481908D02*
Y480574D01*
G01X1038715Y483549D02*
X1038424Y483841D01*
X1038257Y484091D01*
X1038174Y484424D01*
X1038257Y484716D01*
X1038424Y484924D01*
X1038674Y485091D01*
X1038965Y485133D01*
X1039215Y485091D01*
X1039465Y484924D01*
X1039674Y484674D01*
X1039757Y484383D01*
X1039674Y484049D01*
X1039424Y483758D01*
X1039049Y483591D01*
X1038632Y483549D01*
X1038090Y483633D01*
X1037799Y483758D01*
X1037507Y483966D01*
X1037299Y484258D01*
X1037257Y484549D01*
X1037340Y484841D01*
X1037549Y485049D01*
G01X1076908Y494417D02*
X1076783Y494167D01*
X1076700Y493875D01*
Y493542D01*
X1076825Y493167D01*
X1077033Y492875D01*
X1077283Y492667D01*
X1077700Y492500D01*
X1078075Y492458D01*
X1078450Y492542D01*
X1078700Y492667D01*
X1078950Y492917D01*
X1079117Y493208D01*
X1079200Y493500D01*
Y493792D01*
X1079117Y494083D01*
X1078992Y494333D01*
X1078825Y494542D01*
G01X1079200Y496517D02*
X1078658Y496600D01*
X1078200Y496725D01*
X1077783Y496892D01*
X1077325Y497100D01*
X1076700Y497433D01*
Y495767D01*
G01X1079200Y498658D02*
X1076700Y499700D01*
X1079200Y500742D01*
G01X1078325Y500367D02*
Y499033D01*
G01X1079200Y503300D02*
X1076700D01*
X1078492Y501758D01*
Y503842D01*
G01X1078700Y504983D02*
X1078992Y505233D01*
X1079158Y505567D01*
X1079200Y505942D01*
X1079158Y506275D01*
X1078950Y506608D01*
X1078700Y506817D01*
X1078450Y506858D01*
X1078158Y506775D01*
X1077950Y506483D01*
X1077867Y506192D01*
Y505817D01*
G01Y506192D02*
X1077742Y506442D01*
X1077533Y506650D01*
X1077283Y506733D01*
X1077033Y506650D01*
X1076825Y506442D01*
X1076700Y506067D01*
X1076742Y505692D01*
X1076908Y505317D01*
G01X1067785Y490521D02*
X1067535Y490646D01*
X1067243Y490729D01*
X1066910D01*
X1066535Y490604D01*
X1066243Y490396D01*
X1066035Y490146D01*
X1065868Y489729D01*
X1065826Y489354D01*
X1065910Y488979D01*
X1066035Y488729D01*
X1066285Y488479D01*
X1066576Y488312D01*
X1066868Y488229D01*
X1067160D01*
X1067451Y488312D01*
X1067701Y488437D01*
X1067910Y488604D01*
G01X1069885Y488229D02*
X1069968Y488771D01*
X1070093Y489229D01*
X1070260Y489646D01*
X1070468Y490104D01*
X1070801Y490729D01*
X1069135D01*
G01X1072026Y488229D02*
X1073068Y490729D01*
X1074110Y488229D01*
G01X1073735Y489104D02*
X1072401D01*
G01X1076168Y488229D02*
Y490729D01*
X1075668Y490229D01*
G01Y488229D02*
X1076668D01*
G01X1079268Y490729D02*
X1078935Y490646D01*
X1078685Y490437D01*
X1078518Y490187D01*
X1078393Y489854D01*
X1078351Y489479D01*
X1078393Y489104D01*
X1078518Y488771D01*
X1078685Y488521D01*
X1078935Y488312D01*
X1079268Y488229D01*
X1079601Y488312D01*
X1079851Y488521D01*
X1080018Y488771D01*
X1080143Y489104D01*
X1080185Y489479D01*
X1080143Y489854D01*
X1080018Y490187D01*
X1079851Y490437D01*
X1079601Y490646D01*
X1079268Y490729D01*
G01X1080909Y494429D02*
X1080784Y494179D01*
X1080701Y493887D01*
Y493554D01*
X1080826Y493179D01*
X1081034Y492887D01*
X1081284Y492679D01*
X1081701Y492512D01*
X1082076Y492470D01*
X1082451Y492554D01*
X1082701Y492679D01*
X1082951Y492929D01*
X1083118Y493220D01*
X1083201Y493512D01*
Y493804D01*
X1083118Y494095D01*
X1082993Y494345D01*
X1082826Y494554D01*
G01X1080701Y496612D02*
X1083201D01*
G01X1080701Y495654D02*
Y497570D01*
G01X1082159Y498920D02*
X1081868Y499212D01*
X1081701Y499462D01*
X1081618Y499795D01*
X1081701Y500087D01*
X1081868Y500295D01*
X1082118Y500462D01*
X1082409Y500504D01*
X1082659Y500462D01*
X1082909Y500295D01*
X1083118Y500045D01*
X1083201Y499754D01*
X1083118Y499420D01*
X1082868Y499129D01*
X1082493Y498962D01*
X1082076Y498920D01*
X1081534Y499004D01*
X1081243Y499129D01*
X1080951Y499337D01*
X1080743Y499629D01*
X1080701Y499920D01*
X1080784Y500212D01*
X1080993Y500420D01*
G01X1083201Y502729D02*
X1082659Y502812D01*
X1082201Y502937D01*
X1081784Y503104D01*
X1081326Y503312D01*
X1080701Y503645D01*
Y501979D01*
G01X1045735Y496121D02*
X1045485Y496246D01*
X1045193Y496329D01*
X1044860D01*
X1044485Y496204D01*
X1044193Y495996D01*
X1043985Y495746D01*
X1043818Y495329D01*
X1043776Y494954D01*
X1043860Y494579D01*
X1043985Y494329D01*
X1044235Y494079D01*
X1044526Y493912D01*
X1044818Y493829D01*
X1045110D01*
X1045401Y493912D01*
X1045651Y494037D01*
X1045860Y494204D01*
G01X1047918Y496329D02*
Y493829D01*
G01X1046960Y496329D02*
X1048876D01*
G01X1050226Y494871D02*
X1050518Y495162D01*
X1050768Y495329D01*
X1051101Y495412D01*
X1051393Y495329D01*
X1051601Y495162D01*
X1051768Y494912D01*
X1051810Y494621D01*
X1051768Y494371D01*
X1051601Y494121D01*
X1051351Y493912D01*
X1051060Y493829D01*
X1050726Y493912D01*
X1050435Y494162D01*
X1050268Y494537D01*
X1050226Y494954D01*
X1050310Y495496D01*
X1050435Y495787D01*
X1050643Y496079D01*
X1050935Y496287D01*
X1051226Y496329D01*
X1051518Y496246D01*
X1051726Y496037D01*
G01X1054618Y493829D02*
Y496329D01*
X1053076Y494537D01*
X1055160D01*
G01X1065564Y474708D02*
X1065439Y474458D01*
X1065356Y474166D01*
Y473833D01*
X1065481Y473458D01*
X1065689Y473166D01*
X1065939Y472958D01*
X1066356Y472791D01*
X1066731Y472749D01*
X1067106Y472833D01*
X1067356Y472958D01*
X1067606Y473208D01*
X1067773Y473499D01*
X1067856Y473791D01*
Y474083D01*
X1067773Y474374D01*
X1067648Y474624D01*
X1067481Y474833D01*
G01X1067856Y476808D02*
X1067314Y476891D01*
X1066856Y477016D01*
X1066439Y477183D01*
X1065981Y477391D01*
X1065356Y477724D01*
Y476058D01*
G01X1067856Y478949D02*
X1065356Y479991D01*
X1067856Y481033D01*
G01X1066981Y480658D02*
Y479324D01*
G01X1067356Y482174D02*
X1067648Y482424D01*
X1067814Y482758D01*
X1067856Y483133D01*
X1067814Y483466D01*
X1067606Y483799D01*
X1067356Y484008D01*
X1067106Y484049D01*
X1066814Y483966D01*
X1066606Y483674D01*
X1066523Y483383D01*
Y483008D01*
G01Y483383D02*
X1066398Y483633D01*
X1066189Y483841D01*
X1065939Y483924D01*
X1065689Y483841D01*
X1065481Y483633D01*
X1065356Y483258D01*
X1065398Y482883D01*
X1065564Y482508D01*
G01X1067564Y485483D02*
X1067773Y485774D01*
X1067856Y486108D01*
X1067773Y486441D01*
X1067523Y486733D01*
X1067148Y486941D01*
X1066773Y487024D01*
X1066314D01*
X1065939Y486941D01*
X1065606Y486733D01*
X1065439Y486483D01*
X1065356Y486191D01*
X1065439Y485858D01*
X1065606Y485608D01*
X1065856Y485441D01*
X1066189Y485358D01*
X1066481Y485441D01*
X1066773Y485649D01*
X1066939Y485899D01*
X1066981Y486191D01*
X1066898Y486524D01*
X1066689Y486774D01*
X1066314Y487024D01*
G01X1061103Y475258D02*
X1060978Y475008D01*
X1060895Y474716D01*
Y474383D01*
X1061020Y474008D01*
X1061228Y473716D01*
X1061478Y473508D01*
X1061895Y473341D01*
X1062270Y473299D01*
X1062645Y473383D01*
X1062895Y473508D01*
X1063145Y473758D01*
X1063312Y474049D01*
X1063395Y474341D01*
Y474633D01*
X1063312Y474924D01*
X1063187Y475174D01*
X1063020Y475383D01*
G01X1063395Y477358D02*
X1062853Y477441D01*
X1062395Y477566D01*
X1061978Y477733D01*
X1061520Y477941D01*
X1060895Y478274D01*
Y476608D01*
G01X1063395Y479499D02*
X1060895Y480541D01*
X1063395Y481583D01*
G01X1062520Y481208D02*
Y479874D01*
G01X1063395Y483558D02*
X1062853Y483641D01*
X1062395Y483766D01*
X1061978Y483933D01*
X1061520Y484141D01*
X1060895Y484474D01*
Y482808D01*
G01X1090510Y484379D02*
X1090385Y484129D01*
X1090302Y483837D01*
Y483504D01*
X1090427Y483129D01*
X1090635Y482837D01*
X1090885Y482629D01*
X1091302Y482462D01*
X1091677Y482420D01*
X1092052Y482504D01*
X1092302Y482629D01*
X1092552Y482879D01*
X1092719Y483170D01*
X1092802Y483462D01*
Y483754D01*
X1092719Y484045D01*
X1092594Y484295D01*
X1092427Y484504D01*
G01X1092802Y486479D02*
X1092260Y486562D01*
X1091802Y486687D01*
X1091385Y486854D01*
X1090927Y487062D01*
X1090302Y487395D01*
Y485729D01*
G01X1092802Y488620D02*
X1090302Y489662D01*
X1092802Y490704D01*
G01X1091927Y490329D02*
Y488995D01*
G01X1092802Y493262D02*
X1090302D01*
X1092094Y491720D01*
Y493804D01*
G01X1090302Y495862D02*
X1090385Y495529D01*
X1090594Y495279D01*
X1090844Y495112D01*
X1091177Y494987D01*
X1091552Y494945D01*
X1091927Y494987D01*
X1092260Y495112D01*
X1092510Y495279D01*
X1092719Y495529D01*
X1092802Y495862D01*
X1092719Y496195D01*
X1092510Y496445D01*
X1092260Y496612D01*
X1091927Y496737D01*
X1091552Y496779D01*
X1091177Y496737D01*
X1090844Y496612D01*
X1090594Y496445D01*
X1090385Y496195D01*
X1090302Y495862D01*
G01X1042740Y515636D02*
X1042817Y516308D01*
X1042932Y516876D01*
X1043085Y517393D01*
X1043277Y517961D01*
X1043584Y518736D01*
X1042050D01*
G01X1045917Y515636D02*
X1046185Y515688D01*
X1046492Y515843D01*
X1046684Y516101D01*
X1046760Y516463D01*
X1046684Y516824D01*
X1046454Y517134D01*
X1046109Y517289D01*
X1045725D01*
X1045495Y517393D01*
X1045304Y517651D01*
X1045227Y518013D01*
X1045342Y518374D01*
X1045610Y518633D01*
X1045917Y518736D01*
X1046224Y518633D01*
X1046492Y518374D01*
X1046607Y518013D01*
X1046530Y517651D01*
X1046339Y517393D01*
X1046109Y517289D01*
X1045725D01*
X1045380Y517134D01*
X1045150Y516824D01*
X1045074Y516463D01*
X1045150Y516101D01*
X1045342Y515843D01*
X1045649Y515688D01*
X1045917Y515636D01*
G01X1033755Y475629D02*
X1033630Y475379D01*
X1033547Y475087D01*
Y474754D01*
X1033672Y474379D01*
X1033880Y474087D01*
X1034130Y473879D01*
X1034547Y473712D01*
X1034922Y473670D01*
X1035297Y473754D01*
X1035547Y473879D01*
X1035797Y474129D01*
X1035964Y474420D01*
X1036047Y474712D01*
Y475004D01*
X1035964Y475295D01*
X1035839Y475545D01*
X1035672Y475754D01*
G01X1036047Y477729D02*
X1035505Y477812D01*
X1035047Y477937D01*
X1034630Y478104D01*
X1034172Y478312D01*
X1033547Y478645D01*
Y476979D01*
G01X1036047Y479870D02*
X1033547Y480912D01*
X1036047Y481954D01*
G01X1035172Y481579D02*
Y480245D01*
G01X1036047Y484012D02*
X1033547D01*
X1034047Y483512D01*
G01X1036047D02*
Y484512D01*
G01Y487612D02*
X1033547D01*
X1035339Y486070D01*
Y488154D01*
G01X1043901Y489029D02*
X1042235D01*
Y491529D01*
X1043901D01*
G01X1043235Y490321D02*
X1042235D01*
G01X1045251Y491529D02*
Y489737D01*
X1045418Y489362D01*
X1045751Y489112D01*
X1046168Y489029D01*
X1046585Y489112D01*
X1046918Y489362D01*
X1047085Y489737D01*
Y491529D01*
G01X1049185Y489029D02*
X1049268Y489571D01*
X1049393Y490029D01*
X1049560Y490446D01*
X1049768Y490904D01*
X1050101Y491529D01*
X1048435D01*
G01X1051326Y489029D02*
X1052368Y491529D01*
X1053410Y489029D01*
G01X1053035Y489904D02*
X1051701D01*
G01X1054551Y489529D02*
X1054801Y489237D01*
X1055135Y489071D01*
X1055510Y489029D01*
X1055843Y489071D01*
X1056176Y489279D01*
X1056385Y489529D01*
X1056426Y489779D01*
X1056343Y490071D01*
X1056051Y490279D01*
X1055760Y490362D01*
X1055385D01*
G01X1055760D02*
X1056010Y490487D01*
X1056218Y490696D01*
X1056301Y490946D01*
X1056218Y491196D01*
X1056010Y491404D01*
X1055635Y491529D01*
X1055260Y491487D01*
X1054885Y491321D01*
G01X1087802Y484295D02*
Y482629D01*
X1085302D01*
Y484295D01*
G01X1086510Y483629D02*
Y482629D01*
G01X1085302Y485645D02*
X1087094D01*
X1087469Y485812D01*
X1087719Y486145D01*
X1087802Y486562D01*
X1087719Y486979D01*
X1087469Y487312D01*
X1087094Y487479D01*
X1085302D01*
G01X1087802Y489579D02*
X1087260Y489662D01*
X1086802Y489787D01*
X1086385Y489954D01*
X1085927Y490162D01*
X1085302Y490495D01*
Y488829D01*
G01X1087802Y491720D02*
X1085302Y492762D01*
X1087802Y493804D01*
G01X1086927Y493429D02*
Y492095D01*
G01X1085719Y495070D02*
X1085469Y495320D01*
X1085344Y495612D01*
X1085302Y495945D01*
X1085385Y496362D01*
X1085594Y496654D01*
X1085844Y496737D01*
X1086094Y496695D01*
X1086302Y496529D01*
X1086719Y495695D01*
X1087010Y495320D01*
X1087427Y495070D01*
X1087802Y494987D01*
Y496737D01*
G01X1042157Y554232D02*
X1042234Y554904D01*
X1042349Y555472D01*
X1042502Y555989D01*
X1042694Y556557D01*
X1043001Y557332D01*
X1041467D01*
G01X1045334Y554232D02*
X1045602Y554284D01*
X1045909Y554439D01*
X1046101Y554697D01*
X1046177Y555059D01*
X1046101Y555420D01*
X1045871Y555730D01*
X1045526Y555885D01*
X1045142D01*
X1044912Y555989D01*
X1044721Y556247D01*
X1044644Y556609D01*
X1044759Y556970D01*
X1045027Y557229D01*
X1045334Y557332D01*
X1045641Y557229D01*
X1045909Y556970D01*
X1046024Y556609D01*
X1045947Y556247D01*
X1045756Y555989D01*
X1045526Y555885D01*
X1045142D01*
X1044797Y555730D01*
X1044567Y555420D01*
X1044491Y555059D01*
X1044567Y554697D01*
X1044759Y554439D01*
X1045066Y554284D01*
X1045334Y554232D01*
G01X1042122Y586733D02*
X1042352Y587043D01*
X1042620Y587198D01*
X1042927Y587250D01*
X1043310Y587147D01*
X1043578Y586888D01*
X1043655Y586578D01*
X1043617Y586268D01*
X1043463Y586010D01*
X1042697Y585493D01*
X1042352Y585132D01*
X1042122Y584615D01*
X1042045Y584150D01*
X1043655D01*
G01X1045222Y586733D02*
X1045452Y587043D01*
X1045720Y587198D01*
X1046027Y587250D01*
X1046410Y587147D01*
X1046678Y586888D01*
X1046755Y586578D01*
X1046717Y586268D01*
X1046563Y586010D01*
X1045797Y585493D01*
X1045452Y585132D01*
X1045222Y584615D01*
X1045145Y584150D01*
X1046755D01*
G01X1048322Y586733D02*
X1048552Y587043D01*
X1048820Y587198D01*
X1049127Y587250D01*
X1049510Y587147D01*
X1049778Y586888D01*
X1049855Y586578D01*
X1049817Y586268D01*
X1049663Y586010D01*
X1048897Y585493D01*
X1048552Y585132D01*
X1048322Y584615D01*
X1048245Y584150D01*
X1049855D01*
G01X1041922Y548883D02*
X1042152Y549193D01*
X1042420Y549348D01*
X1042727Y549400D01*
X1043110Y549297D01*
X1043378Y549038D01*
X1043455Y548728D01*
X1043417Y548418D01*
X1043263Y548160D01*
X1042497Y547643D01*
X1042152Y547282D01*
X1041922Y546765D01*
X1041845Y546300D01*
X1043455D01*
G01X1045022Y548883D02*
X1045252Y549193D01*
X1045520Y549348D01*
X1045827Y549400D01*
X1046210Y549297D01*
X1046478Y549038D01*
X1046555Y548728D01*
X1046517Y548418D01*
X1046363Y548160D01*
X1045597Y547643D01*
X1045252Y547282D01*
X1045022Y546765D01*
X1044945Y546300D01*
X1046555D01*
G01X1048122Y548883D02*
X1048352Y549193D01*
X1048620Y549348D01*
X1048927Y549400D01*
X1049310Y549297D01*
X1049578Y549038D01*
X1049655Y548728D01*
X1049617Y548418D01*
X1049463Y548160D01*
X1048697Y547643D01*
X1048352Y547282D01*
X1048122Y546765D01*
X1048045Y546300D01*
X1049655D01*
G01X1042385Y591440D02*
X1042462Y592112D01*
X1042577Y592680D01*
X1042730Y593197D01*
X1042922Y593765D01*
X1043229Y594540D01*
X1041695D01*
G01X1045562Y591440D02*
X1045830Y591492D01*
X1046137Y591647D01*
X1046329Y591905D01*
X1046405Y592267D01*
X1046329Y592628D01*
X1046099Y592938D01*
X1045754Y593093D01*
X1045370D01*
X1045140Y593197D01*
X1044949Y593455D01*
X1044872Y593817D01*
X1044987Y594178D01*
X1045255Y594437D01*
X1045562Y594540D01*
X1045869Y594437D01*
X1046137Y594178D01*
X1046252Y593817D01*
X1046175Y593455D01*
X1045984Y593197D01*
X1045754Y593093D01*
X1045370D01*
X1045025Y592938D01*
X1044795Y592628D01*
X1044719Y592267D01*
X1044795Y591905D01*
X1044987Y591647D01*
X1045294Y591492D01*
X1045562Y591440D01*
G01X1037522Y624733D02*
X1037752Y625043D01*
X1038020Y625198D01*
X1038327Y625250D01*
X1038710Y625147D01*
X1038978Y624888D01*
X1039055Y624578D01*
X1039017Y624268D01*
X1038863Y624010D01*
X1038097Y623493D01*
X1037752Y623132D01*
X1037522Y622615D01*
X1037445Y622150D01*
X1039055D01*
G01X1040622Y624733D02*
X1040852Y625043D01*
X1041120Y625198D01*
X1041427Y625250D01*
X1041810Y625147D01*
X1042078Y624888D01*
X1042155Y624578D01*
X1042117Y624268D01*
X1041963Y624010D01*
X1041197Y623493D01*
X1040852Y623132D01*
X1040622Y622615D01*
X1040545Y622150D01*
X1042155D01*
G01X1043722Y624733D02*
X1043952Y625043D01*
X1044220Y625198D01*
X1044527Y625250D01*
X1044910Y625147D01*
X1045178Y624888D01*
X1045255Y624578D01*
X1045217Y624268D01*
X1045063Y624010D01*
X1044297Y623493D01*
X1043952Y623132D01*
X1043722Y622615D01*
X1043645Y622150D01*
X1045255D01*
G01X1097302Y594395D02*
X1097052Y594520D01*
X1096760Y594603D01*
X1096427D01*
X1096052Y594478D01*
X1095760Y594270D01*
X1095552Y594020D01*
X1095385Y593603D01*
X1095343Y593228D01*
X1095427Y592853D01*
X1095552Y592603D01*
X1095802Y592353D01*
X1096093Y592186D01*
X1096385Y592103D01*
X1096677D01*
X1096968Y592186D01*
X1097218Y592311D01*
X1097427Y592478D01*
G01X1098568D02*
X1098818Y592270D01*
X1099110Y592145D01*
X1099485Y592103D01*
X1099860Y592186D01*
X1100152Y592353D01*
X1100360Y592645D01*
X1100402Y592978D01*
X1100318Y593311D01*
X1100110Y593520D01*
X1099818Y593686D01*
X1099527Y593728D01*
X1099235Y593686D01*
X1098860Y593520D01*
X1098985Y594603D01*
X1100110D01*
G01X1101543Y592103D02*
X1102585Y594603D01*
X1103627Y592103D01*
G01X1103252Y592978D02*
X1101918D01*
G01X1104893Y593145D02*
X1105185Y593436D01*
X1105435Y593603D01*
X1105768Y593686D01*
X1106060Y593603D01*
X1106268Y593436D01*
X1106435Y593186D01*
X1106477Y592895D01*
X1106435Y592645D01*
X1106268Y592395D01*
X1106018Y592186D01*
X1105727Y592103D01*
X1105393Y592186D01*
X1105102Y592436D01*
X1104935Y592811D01*
X1104893Y593228D01*
X1104977Y593770D01*
X1105102Y594061D01*
X1105310Y594353D01*
X1105602Y594561D01*
X1105893Y594603D01*
X1106185Y594520D01*
X1106393Y594311D01*
G01X1060600Y657200D02*
Y660200D01*
X1061600D01*
X1062000Y660050D01*
X1062300Y659850D01*
X1062550Y659550D01*
X1062750Y659200D01*
X1062800Y658700D01*
X1062750Y658200D01*
X1062550Y657850D01*
X1062300Y657550D01*
X1062000Y657350D01*
X1061600Y657200D01*
X1060600D01*
G01X1064550Y658550D02*
X1066150D01*
X1066000Y658900D01*
X1065750Y659100D01*
X1065400Y659200D01*
X1065050Y659150D01*
X1064750Y659000D01*
X1064550Y658650D01*
X1064450Y658350D01*
Y658050D01*
X1064550Y657750D01*
X1064800Y657450D01*
X1065100Y657250D01*
X1065450Y657200D01*
X1065800Y657300D01*
X1066150Y657600D01*
G01X1068900Y657200D02*
Y660200D01*
G01X1072500D02*
Y657200D01*
G01X1071800Y659200D02*
X1073200D01*
G01X1077000Y657200D02*
Y659200D01*
G01Y658850D02*
X1076800Y659050D01*
X1076500Y659150D01*
X1076150Y659200D01*
X1075800Y659100D01*
X1075500Y658900D01*
X1075300Y658600D01*
X1075200Y658200D01*
X1075300Y657800D01*
X1075500Y657500D01*
X1075800Y657300D01*
X1076150Y657200D01*
X1076500Y657250D01*
X1076800Y657400D01*
X1077000Y657600D01*
G01X1078200Y656200D02*
X1081200D01*
G01X1082300Y660200D02*
Y657200D01*
X1084300D01*
G01X1086900D02*
Y660200D01*
X1086300Y659600D01*
G01Y657200D02*
X1087500D01*
G01X1089550Y659700D02*
X1089850Y660000D01*
X1090200Y660150D01*
X1090600Y660200D01*
X1091100Y660100D01*
X1091450Y659850D01*
X1091550Y659550D01*
X1091500Y659250D01*
X1091300Y659000D01*
X1090300Y658500D01*
X1089850Y658150D01*
X1089550Y657650D01*
X1089450Y657200D01*
X1091550D01*
G01X1092600Y656200D02*
X1095600D01*
G01X1097700Y657200D02*
Y660200D01*
X1097100Y659600D01*
G01Y657200D02*
X1098300D01*
G01X1101300Y660200D02*
X1100900Y660100D01*
X1100600Y659850D01*
X1100400Y659550D01*
X1100250Y659150D01*
X1100200Y658700D01*
X1100250Y658250D01*
X1100400Y657850D01*
X1100600Y657550D01*
X1100900Y657300D01*
X1101300Y657200D01*
X1101700Y657300D01*
X1102000Y657550D01*
X1102200Y657850D01*
X1102350Y658250D01*
X1102400Y658700D01*
X1102350Y659150D01*
X1102200Y659550D01*
X1102000Y659850D01*
X1101700Y660100D01*
X1101300Y660200D01*
G01X1104900Y659200D02*
Y657200D01*
G01Y660000D02*
X1104800Y660050D01*
Y660150D01*
X1104900Y660200D01*
X1105000Y660150D01*
Y660050D01*
X1104900Y660000D01*
G01X1107650Y657200D02*
Y659200D01*
G01Y658700D02*
X1107850Y658950D01*
X1108150Y659150D01*
X1108550Y659200D01*
X1108900Y659150D01*
X1109200Y658950D01*
X1109350Y658600D01*
Y657200D01*
G01X1112900Y658950D02*
X1112550Y659150D01*
X1112250Y659200D01*
X1111850Y659100D01*
X1111550Y658900D01*
X1111350Y658550D01*
X1111300Y658200D01*
X1111350Y657850D01*
X1111550Y657550D01*
X1111850Y657300D01*
X1112250Y657200D01*
X1112600Y657300D01*
X1112900Y657500D01*
G01X1114850Y657200D02*
Y660200D01*
G01Y658750D02*
X1115100Y659000D01*
X1115350Y659150D01*
X1115750Y659200D01*
X1116050Y659150D01*
X1116400Y658950D01*
X1116550Y658650D01*
Y657200D01*
G01X1139583Y-38285D02*
X1121583D01*
Y-56285D01*
X1139583D01*
Y-38285D01*
G01X1159583D02*
X1141583D01*
Y-56285D01*
X1159583D01*
Y-38285D01*
G01X1122217Y13958D02*
X1121967Y14083D01*
X1121675Y14166D01*
X1121342D01*
X1120967Y14041D01*
X1120675Y13833D01*
X1120467Y13583D01*
X1120300Y13166D01*
X1120258Y12791D01*
X1120342Y12416D01*
X1120467Y12166D01*
X1120717Y11916D01*
X1121008Y11749D01*
X1121300Y11666D01*
X1121592D01*
X1121883Y11749D01*
X1122133Y11874D01*
X1122342Y12041D01*
G01X1123483D02*
X1123733Y11833D01*
X1124025Y11708D01*
X1124400Y11666D01*
X1124775Y11749D01*
X1125067Y11916D01*
X1125275Y12208D01*
X1125317Y12541D01*
X1125233Y12874D01*
X1125025Y13083D01*
X1124733Y13249D01*
X1124442Y13291D01*
X1124150Y13249D01*
X1123775Y13083D01*
X1123900Y14166D01*
X1125025D01*
G01X1127750Y12916D02*
X1128583D01*
Y12166D01*
X1128333Y11916D01*
X1128042Y11749D01*
X1127625Y11666D01*
X1127208Y11749D01*
X1126917Y11916D01*
X1126667Y12166D01*
X1126500Y12458D01*
X1126417Y12791D01*
Y13083D01*
X1126500Y13333D01*
X1126667Y13624D01*
X1126917Y13874D01*
X1127167Y14041D01*
X1127500Y14166D01*
X1127792D01*
X1128125Y14083D01*
X1128375Y13916D01*
G01X1130600Y11666D02*
Y14166D01*
X1130100Y13666D01*
G01Y11666D02*
X1131100D01*
G01X1133700D02*
X1133992Y11708D01*
X1134325Y11833D01*
X1134533Y12041D01*
X1134617Y12333D01*
X1134533Y12624D01*
X1134283Y12874D01*
X1133908Y12999D01*
X1133492D01*
X1133242Y13083D01*
X1133033Y13291D01*
X1132950Y13583D01*
X1133075Y13874D01*
X1133367Y14083D01*
X1133700Y14166D01*
X1134033Y14083D01*
X1134325Y13874D01*
X1134450Y13583D01*
X1134367Y13291D01*
X1134158Y13083D01*
X1133908Y12999D01*
X1133492D01*
X1133117Y12874D01*
X1132867Y12624D01*
X1132783Y12333D01*
X1132867Y12041D01*
X1133075Y11833D01*
X1133408Y11708D01*
X1133700Y11666D01*
G01X1117717Y17958D02*
X1117467Y18083D01*
X1117175Y18166D01*
X1116842D01*
X1116467Y18041D01*
X1116175Y17833D01*
X1115967Y17583D01*
X1115800Y17166D01*
X1115758Y16791D01*
X1115842Y16416D01*
X1115967Y16166D01*
X1116217Y15916D01*
X1116508Y15749D01*
X1116800Y15666D01*
X1117092D01*
X1117383Y15749D01*
X1117633Y15874D01*
X1117842Y16041D01*
G01X1118983D02*
X1119233Y15833D01*
X1119525Y15708D01*
X1119900Y15666D01*
X1120275Y15749D01*
X1120567Y15916D01*
X1120775Y16208D01*
X1120817Y16541D01*
X1120733Y16874D01*
X1120525Y17083D01*
X1120233Y17249D01*
X1119942Y17291D01*
X1119650Y17249D01*
X1119275Y17083D01*
X1119400Y18166D01*
X1120525D01*
G01X1123250Y16916D02*
X1124083D01*
Y16166D01*
X1123833Y15916D01*
X1123542Y15749D01*
X1123125Y15666D01*
X1122708Y15749D01*
X1122417Y15916D01*
X1122167Y16166D01*
X1122000Y16458D01*
X1121917Y16791D01*
Y17083D01*
X1122000Y17333D01*
X1122167Y17624D01*
X1122417Y17874D01*
X1122667Y18041D01*
X1123000Y18166D01*
X1123292D01*
X1123625Y18083D01*
X1123875Y17916D01*
G01X1126100Y15666D02*
Y18166D01*
X1125600Y17666D01*
G01Y15666D02*
X1126600D01*
G01X1129117D02*
X1129200Y16208D01*
X1129325Y16666D01*
X1129492Y17083D01*
X1129700Y17541D01*
X1130033Y18166D01*
X1128367D01*
G01X1102217Y13458D02*
X1101967Y13583D01*
X1101675Y13666D01*
X1101342D01*
X1100967Y13541D01*
X1100675Y13333D01*
X1100467Y13083D01*
X1100300Y12666D01*
X1100258Y12291D01*
X1100342Y11916D01*
X1100467Y11666D01*
X1100717Y11416D01*
X1101008Y11249D01*
X1101300Y11166D01*
X1101592D01*
X1101883Y11249D01*
X1102133Y11374D01*
X1102342Y11541D01*
G01X1103483D02*
X1103733Y11333D01*
X1104025Y11208D01*
X1104400Y11166D01*
X1104775Y11249D01*
X1105067Y11416D01*
X1105275Y11708D01*
X1105317Y12041D01*
X1105233Y12374D01*
X1105025Y12583D01*
X1104733Y12749D01*
X1104442Y12791D01*
X1104150Y12749D01*
X1103775Y12583D01*
X1103900Y13666D01*
X1105025D01*
G01X1107750Y12416D02*
X1108583D01*
Y11666D01*
X1108333Y11416D01*
X1108042Y11249D01*
X1107625Y11166D01*
X1107208Y11249D01*
X1106917Y11416D01*
X1106667Y11666D01*
X1106500Y11958D01*
X1106417Y12291D01*
Y12583D01*
X1106500Y12833D01*
X1106667Y13124D01*
X1106917Y13374D01*
X1107167Y13541D01*
X1107500Y13666D01*
X1107792D01*
X1108125Y13583D01*
X1108375Y13416D01*
G01X1110600Y11166D02*
Y13666D01*
X1110100Y13166D01*
G01Y11166D02*
X1111100D01*
G01X1112908Y12208D02*
X1113200Y12499D01*
X1113450Y12666D01*
X1113783Y12749D01*
X1114075Y12666D01*
X1114283Y12499D01*
X1114450Y12249D01*
X1114492Y11958D01*
X1114450Y11708D01*
X1114283Y11458D01*
X1114033Y11249D01*
X1113742Y11166D01*
X1113408Y11249D01*
X1113117Y11499D01*
X1112950Y11874D01*
X1112908Y12291D01*
X1112992Y12833D01*
X1113117Y13124D01*
X1113325Y13416D01*
X1113617Y13624D01*
X1113908Y13666D01*
X1114200Y13583D01*
X1114408Y13374D01*
G01X1108042Y47267D02*
X1107917Y47017D01*
X1107834Y46725D01*
Y46392D01*
X1107959Y46017D01*
X1108167Y45725D01*
X1108417Y45517D01*
X1108834Y45350D01*
X1109209Y45308D01*
X1109584Y45392D01*
X1109834Y45517D01*
X1110084Y45767D01*
X1110251Y46058D01*
X1110334Y46350D01*
Y46642D01*
X1110251Y46933D01*
X1110126Y47183D01*
X1109959Y47392D01*
G01Y48533D02*
X1110167Y48783D01*
X1110292Y49075D01*
X1110334Y49450D01*
X1110251Y49825D01*
X1110084Y50117D01*
X1109792Y50325D01*
X1109459Y50367D01*
X1109126Y50283D01*
X1108917Y50075D01*
X1108751Y49783D01*
X1108709Y49492D01*
X1108751Y49200D01*
X1108917Y48825D01*
X1107834Y48950D01*
Y50075D01*
G01X1109084Y52800D02*
Y53633D01*
X1109834D01*
X1110084Y53383D01*
X1110251Y53092D01*
X1110334Y52675D01*
X1110251Y52258D01*
X1110084Y51967D01*
X1109834Y51717D01*
X1109542Y51550D01*
X1109209Y51467D01*
X1108917D01*
X1108667Y51550D01*
X1108376Y51717D01*
X1108126Y51967D01*
X1107959Y52217D01*
X1107834Y52550D01*
Y52842D01*
X1107917Y53175D01*
X1108084Y53425D01*
G01X1110334Y55650D02*
X1110292Y55942D01*
X1110167Y56275D01*
X1109959Y56483D01*
X1109667Y56567D01*
X1109376Y56483D01*
X1109126Y56233D01*
X1109001Y55858D01*
Y55442D01*
X1108917Y55192D01*
X1108709Y54983D01*
X1108417Y54900D01*
X1108126Y55025D01*
X1107917Y55317D01*
X1107834Y55650D01*
X1107917Y55983D01*
X1108126Y56275D01*
X1108417Y56400D01*
X1108709Y56317D01*
X1108917Y56108D01*
X1109001Y55858D01*
Y55442D01*
X1109126Y55067D01*
X1109376Y54817D01*
X1109667Y54733D01*
X1109959Y54817D01*
X1110167Y55025D01*
X1110292Y55358D01*
X1110334Y55650D01*
G01X1104042Y47267D02*
X1103917Y47017D01*
X1103834Y46725D01*
Y46392D01*
X1103959Y46017D01*
X1104167Y45725D01*
X1104417Y45517D01*
X1104834Y45350D01*
X1105209Y45308D01*
X1105584Y45392D01*
X1105834Y45517D01*
X1106084Y45767D01*
X1106251Y46058D01*
X1106334Y46350D01*
Y46642D01*
X1106251Y46933D01*
X1106126Y47183D01*
X1105959Y47392D01*
G01Y48533D02*
X1106167Y48783D01*
X1106292Y49075D01*
X1106334Y49450D01*
X1106251Y49825D01*
X1106084Y50117D01*
X1105792Y50325D01*
X1105459Y50367D01*
X1105126Y50283D01*
X1104917Y50075D01*
X1104751Y49783D01*
X1104709Y49492D01*
X1104751Y49200D01*
X1104917Y48825D01*
X1103834Y48950D01*
Y50075D01*
G01X1105084Y52800D02*
Y53633D01*
X1105834D01*
X1106084Y53383D01*
X1106251Y53092D01*
X1106334Y52675D01*
X1106251Y52258D01*
X1106084Y51967D01*
X1105834Y51717D01*
X1105542Y51550D01*
X1105209Y51467D01*
X1104917D01*
X1104667Y51550D01*
X1104376Y51717D01*
X1104126Y51967D01*
X1103959Y52217D01*
X1103834Y52550D01*
Y52842D01*
X1103917Y53175D01*
X1104084Y53425D01*
G01X1106334Y55567D02*
X1105792Y55650D01*
X1105334Y55775D01*
X1104917Y55942D01*
X1104459Y56150D01*
X1103834Y56483D01*
Y54817D01*
G01X1099542Y47267D02*
X1099417Y47017D01*
X1099334Y46725D01*
Y46392D01*
X1099459Y46017D01*
X1099667Y45725D01*
X1099917Y45517D01*
X1100334Y45350D01*
X1100709Y45308D01*
X1101084Y45392D01*
X1101334Y45517D01*
X1101584Y45767D01*
X1101751Y46058D01*
X1101834Y46350D01*
Y46642D01*
X1101751Y46933D01*
X1101626Y47183D01*
X1101459Y47392D01*
G01Y48533D02*
X1101667Y48783D01*
X1101792Y49075D01*
X1101834Y49450D01*
X1101751Y49825D01*
X1101584Y50117D01*
X1101292Y50325D01*
X1100959Y50367D01*
X1100626Y50283D01*
X1100417Y50075D01*
X1100251Y49783D01*
X1100209Y49492D01*
X1100251Y49200D01*
X1100417Y48825D01*
X1099334Y48950D01*
Y50075D01*
G01X1100584Y52800D02*
Y53633D01*
X1101334D01*
X1101584Y53383D01*
X1101751Y53092D01*
X1101834Y52675D01*
X1101751Y52258D01*
X1101584Y51967D01*
X1101334Y51717D01*
X1101042Y51550D01*
X1100709Y51467D01*
X1100417D01*
X1100167Y51550D01*
X1099876Y51717D01*
X1099626Y51967D01*
X1099459Y52217D01*
X1099334Y52550D01*
Y52842D01*
X1099417Y53175D01*
X1099584Y53425D01*
G01X1100792Y54858D02*
X1100501Y55150D01*
X1100334Y55400D01*
X1100251Y55733D01*
X1100334Y56025D01*
X1100501Y56233D01*
X1100751Y56400D01*
X1101042Y56442D01*
X1101292Y56400D01*
X1101542Y56233D01*
X1101751Y55983D01*
X1101834Y55692D01*
X1101751Y55358D01*
X1101501Y55067D01*
X1101126Y54900D01*
X1100709Y54858D01*
X1100167Y54942D01*
X1099876Y55067D01*
X1099584Y55275D01*
X1099376Y55567D01*
X1099334Y55858D01*
X1099417Y56150D01*
X1099626Y56358D01*
G01X1095542Y47267D02*
X1095417Y47017D01*
X1095334Y46725D01*
Y46392D01*
X1095459Y46017D01*
X1095667Y45725D01*
X1095917Y45517D01*
X1096334Y45350D01*
X1096709Y45308D01*
X1097084Y45392D01*
X1097334Y45517D01*
X1097584Y45767D01*
X1097751Y46058D01*
X1097834Y46350D01*
Y46642D01*
X1097751Y46933D01*
X1097626Y47183D01*
X1097459Y47392D01*
G01Y48533D02*
X1097667Y48783D01*
X1097792Y49075D01*
X1097834Y49450D01*
X1097751Y49825D01*
X1097584Y50117D01*
X1097292Y50325D01*
X1096959Y50367D01*
X1096626Y50283D01*
X1096417Y50075D01*
X1096251Y49783D01*
X1096209Y49492D01*
X1096251Y49200D01*
X1096417Y48825D01*
X1095334Y48950D01*
Y50075D01*
G01X1096584Y52800D02*
Y53633D01*
X1097334D01*
X1097584Y53383D01*
X1097751Y53092D01*
X1097834Y52675D01*
X1097751Y52258D01*
X1097584Y51967D01*
X1097334Y51717D01*
X1097042Y51550D01*
X1096709Y51467D01*
X1096417D01*
X1096167Y51550D01*
X1095876Y51717D01*
X1095626Y51967D01*
X1095459Y52217D01*
X1095334Y52550D01*
Y52842D01*
X1095417Y53175D01*
X1095584Y53425D01*
G01X1097459Y54733D02*
X1097667Y54983D01*
X1097792Y55275D01*
X1097834Y55650D01*
X1097751Y56025D01*
X1097584Y56317D01*
X1097292Y56525D01*
X1096959Y56567D01*
X1096626Y56483D01*
X1096417Y56275D01*
X1096251Y55983D01*
X1096209Y55692D01*
X1096251Y55400D01*
X1096417Y55025D01*
X1095334Y55150D01*
Y56275D01*
G01X1130354Y103500D02*
X1107500D01*
Y149500D01*
X1168500D01*
G01X1241500Y207000D02*
X1233500D01*
Y194500D01*
X1225500D01*
Y177365D01*
X1213255D01*
Y168443D01*
X1168967D01*
Y136180D01*
X1176532D01*
Y127581D01*
X1174980D01*
Y121001D01*
X1174979Y121000D01*
X1154000D01*
Y103500D01*
X1132391D01*
G01X1140398Y122298D02*
X1137898D01*
Y123339D01*
X1138023Y123673D01*
X1138190Y123881D01*
X1138523Y123964D01*
X1138856Y123881D01*
X1139065Y123631D01*
X1139190Y123339D01*
Y122298D01*
G01Y123339D02*
X1140398Y123964D01*
G01X1138315Y125439D02*
X1138065Y125689D01*
X1137940Y125981D01*
X1137898Y126314D01*
X1137981Y126731D01*
X1138190Y127023D01*
X1138440Y127106D01*
X1138690Y127064D01*
X1138898Y126898D01*
X1139315Y126064D01*
X1139606Y125689D01*
X1140023Y125439D01*
X1140398Y125356D01*
Y127106D01*
G01X1140023Y128414D02*
X1140231Y128664D01*
X1140356Y128956D01*
X1140398Y129331D01*
X1140315Y129706D01*
X1140148Y129998D01*
X1139856Y130206D01*
X1139523Y130248D01*
X1139190Y130164D01*
X1138981Y129956D01*
X1138815Y129664D01*
X1138773Y129373D01*
X1138815Y129081D01*
X1138981Y128706D01*
X1137898Y128831D01*
Y129956D01*
G01Y131181D02*
X1140398Y131764D01*
X1137898Y132431D01*
X1140398Y133098D01*
X1137898Y133681D01*
G01X1140398Y135531D02*
X1137898D01*
X1138398Y135031D01*
G01X1140398D02*
Y136031D01*
G01Y139131D02*
X1137898D01*
X1139690Y137589D01*
Y139673D01*
G01X1139898Y140814D02*
X1140190Y141064D01*
X1140356Y141398D01*
X1140398Y141773D01*
X1140356Y142106D01*
X1140148Y142439D01*
X1139898Y142648D01*
X1139648Y142689D01*
X1139356Y142606D01*
X1139148Y142314D01*
X1139065Y142023D01*
Y141648D01*
G01Y142023D02*
X1138940Y142273D01*
X1138731Y142481D01*
X1138481Y142564D01*
X1138231Y142481D01*
X1138023Y142273D01*
X1137898Y141898D01*
X1137940Y141523D01*
X1138106Y141148D01*
G01X1156254Y122603D02*
X1153754D01*
Y123644D01*
X1153879Y123978D01*
X1154046Y124186D01*
X1154379Y124269D01*
X1154712Y124186D01*
X1154921Y123936D01*
X1155046Y123644D01*
Y122603D01*
G01Y123644D02*
X1156254Y124269D01*
G01X1154171Y125744D02*
X1153921Y125994D01*
X1153796Y126286D01*
X1153754Y126619D01*
X1153837Y127036D01*
X1154046Y127328D01*
X1154296Y127411D01*
X1154546Y127369D01*
X1154754Y127203D01*
X1155171Y126369D01*
X1155462Y125994D01*
X1155879Y125744D01*
X1156254Y125661D01*
Y127411D01*
G01X1155879Y128719D02*
X1156087Y128969D01*
X1156212Y129261D01*
X1156254Y129636D01*
X1156171Y130011D01*
X1156004Y130303D01*
X1155712Y130511D01*
X1155379Y130553D01*
X1155046Y130469D01*
X1154837Y130261D01*
X1154671Y129969D01*
X1154629Y129678D01*
X1154671Y129386D01*
X1154837Y129011D01*
X1153754Y129136D01*
Y130261D01*
G01Y131486D02*
X1156254Y132069D01*
X1153754Y132736D01*
X1156254Y133403D01*
X1153754Y133986D01*
G01X1156254Y135836D02*
X1153754D01*
X1154254Y135336D01*
G01X1156254D02*
Y136336D01*
G01Y138936D02*
X1153754D01*
X1154254Y138436D01*
G01X1156254D02*
Y139436D01*
G01X1155212Y141244D02*
X1154921Y141536D01*
X1154754Y141786D01*
X1154671Y142119D01*
X1154754Y142411D01*
X1154921Y142619D01*
X1155171Y142786D01*
X1155462Y142828D01*
X1155712Y142786D01*
X1155962Y142619D01*
X1156171Y142369D01*
X1156254Y142078D01*
X1156171Y141744D01*
X1155921Y141453D01*
X1155546Y141286D01*
X1155129Y141244D01*
X1154587Y141328D01*
X1154296Y141453D01*
X1154004Y141661D01*
X1153796Y141953D01*
X1153754Y142244D01*
X1153837Y142536D01*
X1154046Y142744D01*
G01X1152554Y122653D02*
X1150054D01*
Y123694D01*
X1150179Y124028D01*
X1150346Y124236D01*
X1150679Y124319D01*
X1151012Y124236D01*
X1151221Y123986D01*
X1151346Y123694D01*
Y122653D01*
G01Y123694D02*
X1152554Y124319D01*
G01X1150471Y125794D02*
X1150221Y126044D01*
X1150096Y126336D01*
X1150054Y126669D01*
X1150137Y127086D01*
X1150346Y127378D01*
X1150596Y127461D01*
X1150846Y127419D01*
X1151054Y127253D01*
X1151471Y126419D01*
X1151762Y126044D01*
X1152179Y125794D01*
X1152554Y125711D01*
Y127461D01*
G01X1152179Y128769D02*
X1152387Y129019D01*
X1152512Y129311D01*
X1152554Y129686D01*
X1152471Y130061D01*
X1152304Y130353D01*
X1152012Y130561D01*
X1151679Y130603D01*
X1151346Y130519D01*
X1151137Y130311D01*
X1150971Y130019D01*
X1150929Y129728D01*
X1150971Y129436D01*
X1151137Y129061D01*
X1150054Y129186D01*
Y130311D01*
G01Y131536D02*
X1152554Y132119D01*
X1150054Y132786D01*
X1152554Y133453D01*
X1150054Y134036D01*
G01X1152179Y134969D02*
X1152387Y135219D01*
X1152512Y135511D01*
X1152554Y135886D01*
X1152471Y136261D01*
X1152304Y136553D01*
X1152012Y136761D01*
X1151679Y136803D01*
X1151346Y136719D01*
X1151137Y136511D01*
X1150971Y136219D01*
X1150929Y135928D01*
X1150971Y135636D01*
X1151137Y135261D01*
X1150054Y135386D01*
Y136511D01*
G01X1152554Y138903D02*
X1152012Y138986D01*
X1151554Y139111D01*
X1151137Y139278D01*
X1150679Y139486D01*
X1150054Y139819D01*
Y138153D01*
G01X1133498Y122598D02*
X1130998D01*
Y123639D01*
X1131123Y123973D01*
X1131290Y124181D01*
X1131623Y124264D01*
X1131956Y124181D01*
X1132165Y123931D01*
X1132290Y123639D01*
Y122598D01*
G01Y123639D02*
X1133498Y124264D01*
G01X1131415Y125739D02*
X1131165Y125989D01*
X1131040Y126281D01*
X1130998Y126614D01*
X1131081Y127031D01*
X1131290Y127323D01*
X1131540Y127406D01*
X1131790Y127364D01*
X1131998Y127198D01*
X1132415Y126364D01*
X1132706Y125989D01*
X1133123Y125739D01*
X1133498Y125656D01*
Y127406D01*
G01X1133123Y128714D02*
X1133331Y128964D01*
X1133456Y129256D01*
X1133498Y129631D01*
X1133415Y130006D01*
X1133248Y130298D01*
X1132956Y130506D01*
X1132623Y130548D01*
X1132290Y130464D01*
X1132081Y130256D01*
X1131915Y129964D01*
X1131873Y129673D01*
X1131915Y129381D01*
X1132081Y129006D01*
X1130998Y129131D01*
Y130256D01*
G01Y131481D02*
X1133498Y132064D01*
X1130998Y132731D01*
X1133498Y133398D01*
X1130998Y133981D01*
G01X1133498Y135748D02*
X1132956Y135831D01*
X1132498Y135956D01*
X1132081Y136123D01*
X1131623Y136331D01*
X1130998Y136664D01*
Y134998D01*
G01X1133206Y138223D02*
X1133415Y138514D01*
X1133498Y138848D01*
X1133415Y139181D01*
X1133165Y139473D01*
X1132790Y139681D01*
X1132415Y139764D01*
X1131956D01*
X1131581Y139681D01*
X1131248Y139473D01*
X1131081Y139223D01*
X1130998Y138931D01*
X1131081Y138598D01*
X1131248Y138348D01*
X1131498Y138181D01*
X1131831Y138098D01*
X1132123Y138181D01*
X1132415Y138389D01*
X1132581Y138639D01*
X1132623Y138931D01*
X1132540Y139264D01*
X1132331Y139514D01*
X1131956Y139764D01*
G01X1136998Y122598D02*
X1134498D01*
Y123639D01*
X1134623Y123973D01*
X1134790Y124181D01*
X1135123Y124264D01*
X1135456Y124181D01*
X1135665Y123931D01*
X1135790Y123639D01*
Y122598D01*
G01Y123639D02*
X1136998Y124264D01*
G01X1134915Y125739D02*
X1134665Y125989D01*
X1134540Y126281D01*
X1134498Y126614D01*
X1134581Y127031D01*
X1134790Y127323D01*
X1135040Y127406D01*
X1135290Y127364D01*
X1135498Y127198D01*
X1135915Y126364D01*
X1136206Y125989D01*
X1136623Y125739D01*
X1136998Y125656D01*
Y127406D01*
G01X1136623Y128714D02*
X1136831Y128964D01*
X1136956Y129256D01*
X1136998Y129631D01*
X1136915Y130006D01*
X1136748Y130298D01*
X1136456Y130506D01*
X1136123Y130548D01*
X1135790Y130464D01*
X1135581Y130256D01*
X1135415Y129964D01*
X1135373Y129673D01*
X1135415Y129381D01*
X1135581Y129006D01*
X1134498Y129131D01*
Y130256D01*
G01Y131481D02*
X1136998Y132064D01*
X1134498Y132731D01*
X1136998Y133398D01*
X1134498Y133981D01*
G01X1136998Y135831D02*
X1136956Y136123D01*
X1136831Y136456D01*
X1136623Y136664D01*
X1136331Y136748D01*
X1136040Y136664D01*
X1135790Y136414D01*
X1135665Y136039D01*
Y135623D01*
X1135581Y135373D01*
X1135373Y135164D01*
X1135081Y135081D01*
X1134790Y135206D01*
X1134581Y135498D01*
X1134498Y135831D01*
X1134581Y136164D01*
X1134790Y136456D01*
X1135081Y136581D01*
X1135373Y136498D01*
X1135581Y136289D01*
X1135665Y136039D01*
Y135623D01*
X1135790Y135248D01*
X1136040Y134998D01*
X1136331Y134914D01*
X1136623Y134998D01*
X1136831Y135206D01*
X1136956Y135539D01*
X1136998Y135831D01*
G01Y138931D02*
X1136956Y139223D01*
X1136831Y139556D01*
X1136623Y139764D01*
X1136331Y139848D01*
X1136040Y139764D01*
X1135790Y139514D01*
X1135665Y139139D01*
Y138723D01*
X1135581Y138473D01*
X1135373Y138264D01*
X1135081Y138181D01*
X1134790Y138306D01*
X1134581Y138598D01*
X1134498Y138931D01*
X1134581Y139264D01*
X1134790Y139556D01*
X1135081Y139681D01*
X1135373Y139598D01*
X1135581Y139389D01*
X1135665Y139139D01*
Y138723D01*
X1135790Y138348D01*
X1136040Y138098D01*
X1136331Y138014D01*
X1136623Y138098D01*
X1136831Y138306D01*
X1136956Y138639D01*
X1136998Y138931D01*
G01X1121547Y144851D02*
Y147351D01*
X1122588D01*
X1122922Y147226D01*
X1123130Y147059D01*
X1123213Y146726D01*
X1123130Y146393D01*
X1122880Y146184D01*
X1122588Y146059D01*
X1121547D01*
G01X1122588D02*
X1123213Y144851D01*
G01X1124688Y146934D02*
X1124938Y147184D01*
X1125230Y147309D01*
X1125563Y147351D01*
X1125980Y147268D01*
X1126272Y147059D01*
X1126355Y146809D01*
X1126313Y146559D01*
X1126147Y146351D01*
X1125313Y145934D01*
X1124938Y145643D01*
X1124688Y145226D01*
X1124605Y144851D01*
X1126355D01*
G01X1127663Y145226D02*
X1127913Y145018D01*
X1128205Y144893D01*
X1128580Y144851D01*
X1128955Y144934D01*
X1129247Y145101D01*
X1129455Y145393D01*
X1129497Y145726D01*
X1129413Y146059D01*
X1129205Y146268D01*
X1128913Y146434D01*
X1128622Y146476D01*
X1128330Y146434D01*
X1127955Y146268D01*
X1128080Y147351D01*
X1129205D01*
G01X1130430D02*
X1131013Y144851D01*
X1131680Y147351D01*
X1132347Y144851D01*
X1132930Y147351D01*
G01X1134780Y144851D02*
X1135072Y144893D01*
X1135405Y145018D01*
X1135613Y145226D01*
X1135697Y145518D01*
X1135613Y145809D01*
X1135363Y146059D01*
X1134988Y146184D01*
X1134572D01*
X1134322Y146268D01*
X1134113Y146476D01*
X1134030Y146768D01*
X1134155Y147059D01*
X1134447Y147268D01*
X1134780Y147351D01*
X1135113Y147268D01*
X1135405Y147059D01*
X1135530Y146768D01*
X1135447Y146476D01*
X1135238Y146268D01*
X1134988Y146184D01*
X1134572D01*
X1134197Y146059D01*
X1133947Y145809D01*
X1133863Y145518D01*
X1133947Y145226D01*
X1134155Y145018D01*
X1134488Y144893D01*
X1134780Y144851D01*
G01X1137880Y147351D02*
X1137547Y147268D01*
X1137297Y147059D01*
X1137130Y146809D01*
X1137005Y146476D01*
X1136963Y146101D01*
X1137005Y145726D01*
X1137130Y145393D01*
X1137297Y145143D01*
X1137547Y144934D01*
X1137880Y144851D01*
X1138213Y144934D01*
X1138463Y145143D01*
X1138630Y145393D01*
X1138755Y145726D01*
X1138797Y146101D01*
X1138755Y146476D01*
X1138630Y146809D01*
X1138463Y147059D01*
X1138213Y147268D01*
X1137880Y147351D01*
G01X1129998Y122598D02*
X1127498D01*
Y123639D01*
X1127623Y123973D01*
X1127790Y124181D01*
X1128123Y124264D01*
X1128456Y124181D01*
X1128665Y123931D01*
X1128790Y123639D01*
Y122598D01*
G01Y123639D02*
X1129998Y124264D01*
G01X1127915Y125739D02*
X1127665Y125989D01*
X1127540Y126281D01*
X1127498Y126614D01*
X1127581Y127031D01*
X1127790Y127323D01*
X1128040Y127406D01*
X1128290Y127364D01*
X1128498Y127198D01*
X1128915Y126364D01*
X1129206Y125989D01*
X1129623Y125739D01*
X1129998Y125656D01*
Y127406D01*
G01X1129623Y128714D02*
X1129831Y128964D01*
X1129956Y129256D01*
X1129998Y129631D01*
X1129915Y130006D01*
X1129748Y130298D01*
X1129456Y130506D01*
X1129123Y130548D01*
X1128790Y130464D01*
X1128581Y130256D01*
X1128415Y129964D01*
X1128373Y129673D01*
X1128415Y129381D01*
X1128581Y129006D01*
X1127498Y129131D01*
Y130256D01*
G01Y131481D02*
X1129998Y132064D01*
X1127498Y132731D01*
X1129998Y133398D01*
X1127498Y133981D01*
G01X1129998Y135831D02*
X1129956Y136123D01*
X1129831Y136456D01*
X1129623Y136664D01*
X1129331Y136748D01*
X1129040Y136664D01*
X1128790Y136414D01*
X1128665Y136039D01*
Y135623D01*
X1128581Y135373D01*
X1128373Y135164D01*
X1128081Y135081D01*
X1127790Y135206D01*
X1127581Y135498D01*
X1127498Y135831D01*
X1127581Y136164D01*
X1127790Y136456D01*
X1128081Y136581D01*
X1128373Y136498D01*
X1128581Y136289D01*
X1128665Y136039D01*
Y135623D01*
X1128790Y135248D01*
X1129040Y134998D01*
X1129331Y134914D01*
X1129623Y134998D01*
X1129831Y135206D01*
X1129956Y135539D01*
X1129998Y135831D01*
G01X1129706Y138223D02*
X1129915Y138514D01*
X1129998Y138848D01*
X1129915Y139181D01*
X1129665Y139473D01*
X1129290Y139681D01*
X1128915Y139764D01*
X1128456D01*
X1128081Y139681D01*
X1127748Y139473D01*
X1127581Y139223D01*
X1127498Y138931D01*
X1127581Y138598D01*
X1127748Y138348D01*
X1127998Y138181D01*
X1128331Y138098D01*
X1128623Y138181D01*
X1128915Y138389D01*
X1129081Y138639D01*
X1129123Y138931D01*
X1129040Y139264D01*
X1128831Y139514D01*
X1128456Y139764D01*
G01X1118714Y122009D02*
X1116214D01*
Y123050D01*
X1116339Y123384D01*
X1116506Y123592D01*
X1116839Y123675D01*
X1117172Y123592D01*
X1117381Y123342D01*
X1117506Y123050D01*
Y122009D01*
G01Y123050D02*
X1118714Y123675D01*
G01X1116631Y125150D02*
X1116381Y125400D01*
X1116256Y125692D01*
X1116214Y126025D01*
X1116297Y126442D01*
X1116506Y126734D01*
X1116756Y126817D01*
X1117006Y126775D01*
X1117214Y126609D01*
X1117631Y125775D01*
X1117922Y125400D01*
X1118339Y125150D01*
X1118714Y125067D01*
Y126817D01*
G01X1118339Y128125D02*
X1118547Y128375D01*
X1118672Y128667D01*
X1118714Y129042D01*
X1118631Y129417D01*
X1118464Y129709D01*
X1118172Y129917D01*
X1117839Y129959D01*
X1117506Y129875D01*
X1117297Y129667D01*
X1117131Y129375D01*
X1117089Y129084D01*
X1117131Y128792D01*
X1117297Y128417D01*
X1116214Y128542D01*
Y129667D01*
G01Y130892D02*
X1118714Y131475D01*
X1116214Y132142D01*
X1118714Y132809D01*
X1116214Y133392D01*
G01X1118422Y134534D02*
X1118631Y134825D01*
X1118714Y135159D01*
X1118631Y135492D01*
X1118381Y135784D01*
X1118006Y135992D01*
X1117631Y136075D01*
X1117172D01*
X1116797Y135992D01*
X1116464Y135784D01*
X1116297Y135534D01*
X1116214Y135242D01*
X1116297Y134909D01*
X1116464Y134659D01*
X1116714Y134492D01*
X1117047Y134409D01*
X1117339Y134492D01*
X1117631Y134700D01*
X1117797Y134950D01*
X1117839Y135242D01*
X1117756Y135575D01*
X1117547Y135825D01*
X1117172Y136075D01*
G01X1116214Y138342D02*
X1116297Y138009D01*
X1116506Y137759D01*
X1116756Y137592D01*
X1117089Y137467D01*
X1117464Y137425D01*
X1117839Y137467D01*
X1118172Y137592D01*
X1118422Y137759D01*
X1118631Y138009D01*
X1118714Y138342D01*
X1118631Y138675D01*
X1118422Y138925D01*
X1118172Y139092D01*
X1117839Y139217D01*
X1117464Y139259D01*
X1117089Y139217D01*
X1116756Y139092D01*
X1116506Y138925D01*
X1116297Y138675D01*
X1116214Y138342D01*
G01X1115084Y127627D02*
X1112584D01*
Y128668D01*
X1112709Y129002D01*
X1112876Y129210D01*
X1113209Y129293D01*
X1113542Y129210D01*
X1113751Y128960D01*
X1113876Y128668D01*
Y127627D01*
G01Y128668D02*
X1115084Y129293D01*
G01X1113001Y130768D02*
X1112751Y131018D01*
X1112626Y131310D01*
X1112584Y131643D01*
X1112667Y132060D01*
X1112876Y132352D01*
X1113126Y132435D01*
X1113376Y132393D01*
X1113584Y132227D01*
X1114001Y131393D01*
X1114292Y131018D01*
X1114709Y130768D01*
X1115084Y130685D01*
Y132435D01*
G01X1114709Y133743D02*
X1114917Y133993D01*
X1115042Y134285D01*
X1115084Y134660D01*
X1115001Y135035D01*
X1114834Y135327D01*
X1114542Y135535D01*
X1114209Y135577D01*
X1113876Y135493D01*
X1113667Y135285D01*
X1113501Y134993D01*
X1113459Y134702D01*
X1113501Y134410D01*
X1113667Y134035D01*
X1112584Y134160D01*
Y135285D01*
G01Y136510D02*
X1115084Y137093D01*
X1112584Y137760D01*
X1115084Y138427D01*
X1112584Y139010D01*
G01X1115084Y140860D02*
X1112584D01*
X1113084Y140360D01*
G01X1115084D02*
Y141360D01*
G01Y143960D02*
X1112584D01*
X1113084Y143460D01*
G01X1115084D02*
Y144460D01*
G01X1114584Y146143D02*
X1114876Y146393D01*
X1115042Y146727D01*
X1115084Y147102D01*
X1115042Y147435D01*
X1114834Y147768D01*
X1114584Y147977D01*
X1114334Y148018D01*
X1114042Y147935D01*
X1113834Y147643D01*
X1113751Y147352D01*
Y146977D01*
G01Y147352D02*
X1113626Y147602D01*
X1113417Y147810D01*
X1113167Y147893D01*
X1112917Y147810D01*
X1112709Y147602D01*
X1112584Y147227D01*
X1112626Y146852D01*
X1112792Y146477D01*
G01X1126214Y119509D02*
X1123714D01*
Y120550D01*
X1123839Y120884D01*
X1124006Y121092D01*
X1124339Y121175D01*
X1124672Y121092D01*
X1124881Y120842D01*
X1125006Y120550D01*
Y119509D01*
G01Y120550D02*
X1126214Y121175D01*
G01X1124131Y122650D02*
X1123881Y122900D01*
X1123756Y123192D01*
X1123714Y123525D01*
X1123797Y123942D01*
X1124006Y124234D01*
X1124256Y124317D01*
X1124506Y124275D01*
X1124714Y124109D01*
X1125131Y123275D01*
X1125422Y122900D01*
X1125839Y122650D01*
X1126214Y122567D01*
Y124317D01*
G01X1125839Y125625D02*
X1126047Y125875D01*
X1126172Y126167D01*
X1126214Y126542D01*
X1126131Y126917D01*
X1125964Y127209D01*
X1125672Y127417D01*
X1125339Y127459D01*
X1125006Y127375D01*
X1124797Y127167D01*
X1124631Y126875D01*
X1124589Y126584D01*
X1124631Y126292D01*
X1124797Y125917D01*
X1123714Y126042D01*
Y127167D01*
G01Y128392D02*
X1126214Y128975D01*
X1123714Y129642D01*
X1126214Y130309D01*
X1123714Y130892D01*
G01X1126214Y132742D02*
X1123714D01*
X1124214Y132242D01*
G01X1126214D02*
Y133242D01*
G01Y135842D02*
X1123714D01*
X1124214Y135342D01*
G01X1126214D02*
Y136342D01*
G01X1124131Y138150D02*
X1123881Y138400D01*
X1123756Y138692D01*
X1123714Y139025D01*
X1123797Y139442D01*
X1124006Y139734D01*
X1124256Y139817D01*
X1124506Y139775D01*
X1124714Y139609D01*
X1125131Y138775D01*
X1125422Y138400D01*
X1125839Y138150D01*
X1126214Y138067D01*
Y139817D01*
G01X1122314Y119809D02*
X1119814D01*
Y120850D01*
X1119939Y121184D01*
X1120106Y121392D01*
X1120439Y121475D01*
X1120772Y121392D01*
X1120981Y121142D01*
X1121106Y120850D01*
Y119809D01*
G01Y120850D02*
X1122314Y121475D01*
G01X1120231Y122950D02*
X1119981Y123200D01*
X1119856Y123492D01*
X1119814Y123825D01*
X1119897Y124242D01*
X1120106Y124534D01*
X1120356Y124617D01*
X1120606Y124575D01*
X1120814Y124409D01*
X1121231Y123575D01*
X1121522Y123200D01*
X1121939Y122950D01*
X1122314Y122867D01*
Y124617D01*
G01X1121939Y125925D02*
X1122147Y126175D01*
X1122272Y126467D01*
X1122314Y126842D01*
X1122231Y127217D01*
X1122064Y127509D01*
X1121772Y127717D01*
X1121439Y127759D01*
X1121106Y127675D01*
X1120897Y127467D01*
X1120731Y127175D01*
X1120689Y126884D01*
X1120731Y126592D01*
X1120897Y126217D01*
X1119814Y126342D01*
Y127467D01*
G01Y128692D02*
X1122314Y129275D01*
X1119814Y129942D01*
X1122314Y130609D01*
X1119814Y131192D01*
G01X1122314Y133042D02*
X1119814D01*
X1120314Y132542D01*
G01X1122314D02*
Y133542D01*
G01X1121939Y135225D02*
X1122147Y135475D01*
X1122272Y135767D01*
X1122314Y136142D01*
X1122231Y136517D01*
X1122064Y136809D01*
X1121772Y137017D01*
X1121439Y137059D01*
X1121106Y136975D01*
X1120897Y136767D01*
X1120731Y136475D01*
X1120689Y136184D01*
X1120731Y135892D01*
X1120897Y135517D01*
X1119814Y135642D01*
Y136767D01*
G01Y139242D02*
X1119897Y138909D01*
X1120106Y138659D01*
X1120356Y138492D01*
X1120689Y138367D01*
X1121064Y138325D01*
X1121439Y138367D01*
X1121772Y138492D01*
X1122022Y138659D01*
X1122231Y138909D01*
X1122314Y139242D01*
X1122231Y139575D01*
X1122022Y139825D01*
X1121772Y139992D01*
X1121439Y140117D01*
X1121064Y140159D01*
X1120689Y140117D01*
X1120356Y139992D01*
X1120106Y139825D01*
X1119897Y139575D01*
X1119814Y139242D01*
G01X1111684Y127927D02*
X1109184D01*
Y128968D01*
X1109309Y129302D01*
X1109476Y129510D01*
X1109809Y129593D01*
X1110142Y129510D01*
X1110351Y129260D01*
X1110476Y128968D01*
Y127927D01*
G01Y128968D02*
X1111684Y129593D01*
G01X1109601Y131068D02*
X1109351Y131318D01*
X1109226Y131610D01*
X1109184Y131943D01*
X1109267Y132360D01*
X1109476Y132652D01*
X1109726Y132735D01*
X1109976Y132693D01*
X1110184Y132527D01*
X1110601Y131693D01*
X1110892Y131318D01*
X1111309Y131068D01*
X1111684Y130985D01*
Y132735D01*
G01X1111309Y134043D02*
X1111517Y134293D01*
X1111642Y134585D01*
X1111684Y134960D01*
X1111601Y135335D01*
X1111434Y135627D01*
X1111142Y135835D01*
X1110809Y135877D01*
X1110476Y135793D01*
X1110267Y135585D01*
X1110101Y135293D01*
X1110059Y135002D01*
X1110101Y134710D01*
X1110267Y134335D01*
X1109184Y134460D01*
Y135585D01*
G01Y136810D02*
X1111684Y137393D01*
X1109184Y138060D01*
X1111684Y138727D01*
X1109184Y139310D01*
G01X1111684Y141160D02*
X1109184D01*
X1109684Y140660D01*
G01X1111684D02*
Y141660D01*
G01X1111309Y143343D02*
X1111517Y143593D01*
X1111642Y143885D01*
X1111684Y144260D01*
X1111601Y144635D01*
X1111434Y144927D01*
X1111142Y145135D01*
X1110809Y145177D01*
X1110476Y145093D01*
X1110267Y144885D01*
X1110101Y144593D01*
X1110059Y144302D01*
X1110101Y144010D01*
X1110267Y143635D01*
X1109184Y143760D01*
Y144885D01*
G01X1111684Y147360D02*
X1109184D01*
X1109684Y146860D01*
G01X1111684D02*
Y147860D01*
G01X1146162Y123903D02*
X1146037Y123653D01*
X1145954Y123361D01*
Y123028D01*
X1146079Y122653D01*
X1146287Y122361D01*
X1146537Y122153D01*
X1146954Y121986D01*
X1147329Y121944D01*
X1147704Y122028D01*
X1147954Y122153D01*
X1148204Y122403D01*
X1148371Y122694D01*
X1148454Y122986D01*
Y123278D01*
X1148371Y123569D01*
X1148246Y123819D01*
X1148079Y124028D01*
G01X1146371Y125294D02*
X1146121Y125544D01*
X1145996Y125836D01*
X1145954Y126169D01*
X1146037Y126586D01*
X1146246Y126878D01*
X1146496Y126961D01*
X1146746Y126919D01*
X1146954Y126753D01*
X1147371Y125919D01*
X1147662Y125544D01*
X1148079Y125294D01*
X1148454Y125211D01*
Y126961D01*
G01X1148079Y128269D02*
X1148287Y128519D01*
X1148412Y128811D01*
X1148454Y129186D01*
X1148371Y129561D01*
X1148204Y129853D01*
X1147912Y130061D01*
X1147579Y130103D01*
X1147246Y130019D01*
X1147037Y129811D01*
X1146871Y129519D01*
X1146829Y129228D01*
X1146871Y128936D01*
X1147037Y128561D01*
X1145954Y128686D01*
Y129811D01*
G01Y131036D02*
X1148454Y131619D01*
X1145954Y132286D01*
X1148454Y132953D01*
X1145954Y133536D01*
G01X1148454Y135386D02*
X1148412Y135678D01*
X1148287Y136011D01*
X1148079Y136219D01*
X1147787Y136303D01*
X1147496Y136219D01*
X1147246Y135969D01*
X1147121Y135594D01*
Y135178D01*
X1147037Y134928D01*
X1146829Y134719D01*
X1146537Y134636D01*
X1146246Y134761D01*
X1146037Y135053D01*
X1145954Y135386D01*
X1146037Y135719D01*
X1146246Y136011D01*
X1146537Y136136D01*
X1146829Y136053D01*
X1147037Y135844D01*
X1147121Y135594D01*
Y135178D01*
X1147246Y134803D01*
X1147496Y134553D01*
X1147787Y134469D01*
X1148079Y134553D01*
X1148287Y134761D01*
X1148412Y135094D01*
X1148454Y135386D01*
G01X1142606Y124048D02*
X1142481Y123798D01*
X1142398Y123506D01*
Y123173D01*
X1142523Y122798D01*
X1142731Y122506D01*
X1142981Y122298D01*
X1143398Y122131D01*
X1143773Y122089D01*
X1144148Y122173D01*
X1144398Y122298D01*
X1144648Y122548D01*
X1144815Y122839D01*
X1144898Y123131D01*
Y123423D01*
X1144815Y123714D01*
X1144690Y123964D01*
X1144523Y124173D01*
G01X1142815Y125439D02*
X1142565Y125689D01*
X1142440Y125981D01*
X1142398Y126314D01*
X1142481Y126731D01*
X1142690Y127023D01*
X1142940Y127106D01*
X1143190Y127064D01*
X1143398Y126898D01*
X1143815Y126064D01*
X1144106Y125689D01*
X1144523Y125439D01*
X1144898Y125356D01*
Y127106D01*
G01X1144523Y128414D02*
X1144731Y128664D01*
X1144856Y128956D01*
X1144898Y129331D01*
X1144815Y129706D01*
X1144648Y129998D01*
X1144356Y130206D01*
X1144023Y130248D01*
X1143690Y130164D01*
X1143481Y129956D01*
X1143315Y129664D01*
X1143273Y129373D01*
X1143315Y129081D01*
X1143481Y128706D01*
X1142398Y128831D01*
Y129956D01*
G01Y131181D02*
X1144898Y131764D01*
X1142398Y132431D01*
X1144898Y133098D01*
X1142398Y133681D01*
G01X1144898Y135448D02*
X1144356Y135531D01*
X1143898Y135656D01*
X1143481Y135823D01*
X1143023Y136031D01*
X1142398Y136364D01*
Y134698D01*
G01X1127551Y107134D02*
X1127426Y106884D01*
X1127343Y106592D01*
Y106259D01*
X1127468Y105884D01*
X1127676Y105592D01*
X1127926Y105384D01*
X1128343Y105217D01*
X1128718Y105175D01*
X1129093Y105259D01*
X1129343Y105384D01*
X1129593Y105634D01*
X1129760Y105925D01*
X1129843Y106217D01*
Y106509D01*
X1129760Y106800D01*
X1129635Y107050D01*
X1129468Y107259D01*
G01X1129843Y109317D02*
X1127343D01*
X1127843Y108817D01*
G01X1129843D02*
Y109817D01*
G01X1127343Y111500D02*
X1129135D01*
X1129510Y111667D01*
X1129760Y112000D01*
X1129843Y112417D01*
X1129760Y112834D01*
X1129510Y113167D01*
X1129135Y113334D01*
X1127343D01*
G01X1127760Y114725D02*
X1127510Y114975D01*
X1127385Y115267D01*
X1127343Y115600D01*
X1127426Y116017D01*
X1127635Y116309D01*
X1127885Y116392D01*
X1128135Y116350D01*
X1128343Y116184D01*
X1128760Y115350D01*
X1129051Y114975D01*
X1129468Y114725D01*
X1129843Y114642D01*
Y116392D01*
G01Y118617D02*
X1127343D01*
X1127843Y118117D01*
G01X1129843D02*
Y119117D01*
G01X1103975Y121314D02*
X1103850Y121064D01*
X1103767Y120772D01*
Y120439D01*
X1103892Y120064D01*
X1104100Y119772D01*
X1104350Y119564D01*
X1104767Y119397D01*
X1105142Y119355D01*
X1105517Y119439D01*
X1105767Y119564D01*
X1106017Y119814D01*
X1106184Y120105D01*
X1106267Y120397D01*
Y120689D01*
X1106184Y120980D01*
X1106059Y121230D01*
X1105892Y121439D01*
G01X1106267Y123497D02*
X1106225Y123789D01*
X1106100Y124122D01*
X1105892Y124330D01*
X1105600Y124414D01*
X1105309Y124330D01*
X1105059Y124080D01*
X1104934Y123705D01*
Y123289D01*
X1104850Y123039D01*
X1104642Y122830D01*
X1104350Y122747D01*
X1104059Y122872D01*
X1103850Y123164D01*
X1103767Y123497D01*
X1103850Y123830D01*
X1104059Y124122D01*
X1104350Y124247D01*
X1104642Y124164D01*
X1104850Y123955D01*
X1104934Y123705D01*
Y123289D01*
X1105059Y122914D01*
X1105309Y122664D01*
X1105600Y122580D01*
X1105892Y122664D01*
X1106100Y122872D01*
X1106225Y123205D01*
X1106267Y123497D01*
G01X1105017Y126847D02*
Y127680D01*
X1105767D01*
X1106017Y127430D01*
X1106184Y127139D01*
X1106267Y126722D01*
X1106184Y126305D01*
X1106017Y126014D01*
X1105767Y125764D01*
X1105475Y125597D01*
X1105142Y125514D01*
X1104850D01*
X1104600Y125597D01*
X1104309Y125764D01*
X1104059Y126014D01*
X1103892Y126264D01*
X1103767Y126597D01*
Y126889D01*
X1103850Y127222D01*
X1104017Y127472D01*
G01X1106267Y129697D02*
X1103767D01*
X1104267Y129197D01*
G01X1106267D02*
Y130197D01*
G01X1103767Y132797D02*
X1103850Y132464D01*
X1104059Y132214D01*
X1104309Y132047D01*
X1104642Y131922D01*
X1105017Y131880D01*
X1105392Y131922D01*
X1105725Y132047D01*
X1105975Y132214D01*
X1106184Y132464D01*
X1106267Y132797D01*
X1106184Y133130D01*
X1105975Y133380D01*
X1105725Y133547D01*
X1105392Y133672D01*
X1105017Y133714D01*
X1104642Y133672D01*
X1104309Y133547D01*
X1104059Y133380D01*
X1103850Y133130D01*
X1103767Y132797D01*
G01X1100475Y121314D02*
X1100350Y121064D01*
X1100267Y120772D01*
Y120439D01*
X1100392Y120064D01*
X1100600Y119772D01*
X1100850Y119564D01*
X1101267Y119397D01*
X1101642Y119355D01*
X1102017Y119439D01*
X1102267Y119564D01*
X1102517Y119814D01*
X1102684Y120105D01*
X1102767Y120397D01*
Y120689D01*
X1102684Y120980D01*
X1102559Y121230D01*
X1102392Y121439D01*
G01X1102767Y123497D02*
X1102725Y123789D01*
X1102600Y124122D01*
X1102392Y124330D01*
X1102100Y124414D01*
X1101809Y124330D01*
X1101559Y124080D01*
X1101434Y123705D01*
Y123289D01*
X1101350Y123039D01*
X1101142Y122830D01*
X1100850Y122747D01*
X1100559Y122872D01*
X1100350Y123164D01*
X1100267Y123497D01*
X1100350Y123830D01*
X1100559Y124122D01*
X1100850Y124247D01*
X1101142Y124164D01*
X1101350Y123955D01*
X1101434Y123705D01*
Y123289D01*
X1101559Y122914D01*
X1101809Y122664D01*
X1102100Y122580D01*
X1102392Y122664D01*
X1102600Y122872D01*
X1102725Y123205D01*
X1102767Y123497D01*
G01X1101517Y126847D02*
Y127680D01*
X1102267D01*
X1102517Y127430D01*
X1102684Y127139D01*
X1102767Y126722D01*
X1102684Y126305D01*
X1102517Y126014D01*
X1102267Y125764D01*
X1101975Y125597D01*
X1101642Y125514D01*
X1101350D01*
X1101100Y125597D01*
X1100809Y125764D01*
X1100559Y126014D01*
X1100392Y126264D01*
X1100267Y126597D01*
Y126889D01*
X1100350Y127222D01*
X1100517Y127472D01*
G01X1102475Y128989D02*
X1102684Y129280D01*
X1102767Y129614D01*
X1102684Y129947D01*
X1102434Y130239D01*
X1102059Y130447D01*
X1101684Y130530D01*
X1101225D01*
X1100850Y130447D01*
X1100517Y130239D01*
X1100350Y129989D01*
X1100267Y129697D01*
X1100350Y129364D01*
X1100517Y129114D01*
X1100767Y128947D01*
X1101100Y128864D01*
X1101392Y128947D01*
X1101684Y129155D01*
X1101850Y129405D01*
X1101892Y129697D01*
X1101809Y130030D01*
X1101600Y130280D01*
X1101225Y130530D01*
G01X1096975Y121314D02*
X1096850Y121064D01*
X1096767Y120772D01*
Y120439D01*
X1096892Y120064D01*
X1097100Y119772D01*
X1097350Y119564D01*
X1097767Y119397D01*
X1098142Y119355D01*
X1098517Y119439D01*
X1098767Y119564D01*
X1099017Y119814D01*
X1099184Y120105D01*
X1099267Y120397D01*
Y120689D01*
X1099184Y120980D01*
X1099059Y121230D01*
X1098892Y121439D01*
G01X1099267Y123497D02*
X1099225Y123789D01*
X1099100Y124122D01*
X1098892Y124330D01*
X1098600Y124414D01*
X1098309Y124330D01*
X1098059Y124080D01*
X1097934Y123705D01*
Y123289D01*
X1097850Y123039D01*
X1097642Y122830D01*
X1097350Y122747D01*
X1097059Y122872D01*
X1096850Y123164D01*
X1096767Y123497D01*
X1096850Y123830D01*
X1097059Y124122D01*
X1097350Y124247D01*
X1097642Y124164D01*
X1097850Y123955D01*
X1097934Y123705D01*
Y123289D01*
X1098059Y122914D01*
X1098309Y122664D01*
X1098600Y122580D01*
X1098892Y122664D01*
X1099100Y122872D01*
X1099225Y123205D01*
X1099267Y123497D01*
G01X1098017Y126847D02*
Y127680D01*
X1098767D01*
X1099017Y127430D01*
X1099184Y127139D01*
X1099267Y126722D01*
X1099184Y126305D01*
X1099017Y126014D01*
X1098767Y125764D01*
X1098475Y125597D01*
X1098142Y125514D01*
X1097850D01*
X1097600Y125597D01*
X1097309Y125764D01*
X1097059Y126014D01*
X1096892Y126264D01*
X1096767Y126597D01*
Y126889D01*
X1096850Y127222D01*
X1097017Y127472D01*
G01X1099267Y129697D02*
X1099225Y129989D01*
X1099100Y130322D01*
X1098892Y130530D01*
X1098600Y130614D01*
X1098309Y130530D01*
X1098059Y130280D01*
X1097934Y129905D01*
Y129489D01*
X1097850Y129239D01*
X1097642Y129030D01*
X1097350Y128947D01*
X1097059Y129072D01*
X1096850Y129364D01*
X1096767Y129697D01*
X1096850Y130030D01*
X1097059Y130322D01*
X1097350Y130447D01*
X1097642Y130364D01*
X1097850Y130155D01*
X1097934Y129905D01*
Y129489D01*
X1098059Y129114D01*
X1098309Y128864D01*
X1098600Y128780D01*
X1098892Y128864D01*
X1099100Y129072D01*
X1099225Y129405D01*
X1099267Y129697D01*
G01X1144686Y147240D02*
X1144436Y147365D01*
X1144144Y147448D01*
X1143811D01*
X1143436Y147323D01*
X1143144Y147115D01*
X1142936Y146865D01*
X1142769Y146448D01*
X1142727Y146073D01*
X1142811Y145698D01*
X1142936Y145448D01*
X1143186Y145198D01*
X1143477Y145031D01*
X1143769Y144948D01*
X1144061D01*
X1144352Y145031D01*
X1144602Y145156D01*
X1144811Y145323D01*
G01X1146077Y147031D02*
X1146327Y147281D01*
X1146619Y147406D01*
X1146952Y147448D01*
X1147369Y147365D01*
X1147661Y147156D01*
X1147744Y146906D01*
X1147702Y146656D01*
X1147536Y146448D01*
X1146702Y146031D01*
X1146327Y145740D01*
X1146077Y145323D01*
X1145994Y144948D01*
X1147744D01*
G01X1149052Y145323D02*
X1149302Y145115D01*
X1149594Y144990D01*
X1149969Y144948D01*
X1150344Y145031D01*
X1150636Y145198D01*
X1150844Y145490D01*
X1150886Y145823D01*
X1150802Y146156D01*
X1150594Y146365D01*
X1150302Y146531D01*
X1150011Y146573D01*
X1149719Y146531D01*
X1149344Y146365D01*
X1149469Y147448D01*
X1150594D01*
G01X1151819D02*
X1152402Y144948D01*
X1153069Y147448D01*
X1153736Y144948D01*
X1154319Y147448D01*
G01X1155461Y145240D02*
X1155752Y145031D01*
X1156086Y144948D01*
X1156419Y145031D01*
X1156711Y145281D01*
X1156919Y145656D01*
X1157002Y146031D01*
Y146490D01*
X1156919Y146865D01*
X1156711Y147198D01*
X1156461Y147365D01*
X1156169Y147448D01*
X1155836Y147365D01*
X1155586Y147198D01*
X1155419Y146948D01*
X1155336Y146615D01*
X1155419Y146323D01*
X1155627Y146031D01*
X1155877Y145865D01*
X1156169Y145823D01*
X1156502Y145906D01*
X1156752Y146115D01*
X1157002Y146490D01*
G01X1136332Y105289D02*
X1133832D01*
Y106873D01*
G01X1135040Y106289D02*
Y105289D01*
G01X1134999Y109514D02*
X1134874Y109681D01*
X1134665Y109806D01*
X1134374Y109889D01*
X1134124Y109806D01*
X1133957Y109639D01*
X1133832Y109348D01*
Y108223D01*
X1136332D01*
Y109598D01*
X1136165Y109889D01*
X1135915Y110056D01*
X1135624Y110139D01*
X1135332Y110056D01*
X1135082Y109806D01*
X1134999Y109514D01*
Y108223D01*
G01X1136332Y112281D02*
X1133832D01*
X1134332Y111781D01*
G01X1136332D02*
Y112781D01*
G01X1133832Y114464D02*
X1135624D01*
X1135999Y114631D01*
X1136249Y114964D01*
X1136332Y115381D01*
X1136249Y115798D01*
X1135999Y116131D01*
X1135624Y116298D01*
X1133832D01*
G01X1135832Y117564D02*
X1136124Y117814D01*
X1136290Y118148D01*
X1136332Y118523D01*
X1136290Y118856D01*
X1136082Y119189D01*
X1135832Y119398D01*
X1135582Y119439D01*
X1135290Y119356D01*
X1135082Y119064D01*
X1134999Y118773D01*
Y118398D01*
G01Y118773D02*
X1134874Y119023D01*
X1134665Y119231D01*
X1134415Y119314D01*
X1134165Y119231D01*
X1133957Y119023D01*
X1133832Y118648D01*
X1133874Y118273D01*
X1134040Y117898D01*
G01X1100666Y175081D02*
X1100436Y175443D01*
X1100130Y175649D01*
X1099785Y175701D01*
X1099478Y175649D01*
X1099171Y175391D01*
X1098980Y175081D01*
X1098941Y174771D01*
X1099018Y174409D01*
X1099286Y174151D01*
X1099555Y174048D01*
X1099900D01*
G01X1099555D02*
X1099325Y173893D01*
X1099133Y173634D01*
X1099056Y173324D01*
X1099133Y173014D01*
X1099325Y172756D01*
X1099670Y172601D01*
X1100015Y172653D01*
X1100360Y172859D01*
G01X1096263Y175701D02*
Y172601D01*
X1097681Y174823D01*
X1095765D01*
G01X1103981Y178784D02*
X1103751Y179146D01*
X1103445Y179352D01*
X1103100Y179404D01*
X1102793Y179352D01*
X1102486Y179094D01*
X1102295Y178784D01*
X1102256Y178474D01*
X1102333Y178112D01*
X1102601Y177854D01*
X1102870Y177751D01*
X1103215D01*
G01X1102870D02*
X1102640Y177596D01*
X1102448Y177337D01*
X1102371Y177027D01*
X1102448Y176717D01*
X1102640Y176459D01*
X1102985Y176304D01*
X1103330Y176356D01*
X1103675Y176562D01*
G01X1100881Y178784D02*
X1100651Y179146D01*
X1100345Y179352D01*
X1100000Y179404D01*
X1099693Y179352D01*
X1099386Y179094D01*
X1099195Y178784D01*
X1099156Y178474D01*
X1099233Y178112D01*
X1099501Y177854D01*
X1099770Y177751D01*
X1100115D01*
G01X1099770D02*
X1099540Y177596D01*
X1099348Y177337D01*
X1099271Y177027D01*
X1099348Y176717D01*
X1099540Y176459D01*
X1099885Y176304D01*
X1100230Y176356D01*
X1100575Y176562D01*
G01X1107426Y175081D02*
X1107196Y175443D01*
X1106890Y175649D01*
X1106545Y175701D01*
X1106238Y175649D01*
X1105931Y175391D01*
X1105740Y175081D01*
X1105701Y174771D01*
X1105778Y174409D01*
X1106046Y174151D01*
X1106315Y174048D01*
X1106660D01*
G01X1106315D02*
X1106085Y173893D01*
X1105893Y173634D01*
X1105816Y173324D01*
X1105893Y173014D01*
X1106085Y172756D01*
X1106430Y172601D01*
X1106775Y172653D01*
X1107120Y172859D01*
G01X1104211Y173118D02*
X1103981Y172808D01*
X1103713Y172653D01*
X1103406Y172601D01*
X1103023Y172704D01*
X1102755Y172963D01*
X1102678Y173273D01*
X1102716Y173583D01*
X1102870Y173841D01*
X1103636Y174358D01*
X1103981Y174719D01*
X1104211Y175236D01*
X1104288Y175701D01*
X1102678D01*
G01X1110741Y178784D02*
X1110511Y179146D01*
X1110205Y179352D01*
X1109860Y179404D01*
X1109553Y179352D01*
X1109246Y179094D01*
X1109055Y178784D01*
X1109016Y178474D01*
X1109093Y178112D01*
X1109361Y177854D01*
X1109630Y177751D01*
X1109975D01*
G01X1109630D02*
X1109400Y177596D01*
X1109208Y177337D01*
X1109131Y177027D01*
X1109208Y176717D01*
X1109400Y176459D01*
X1109745Y176304D01*
X1110090Y176356D01*
X1110435Y176562D01*
G01X1106798Y179404D02*
Y176304D01*
X1107258Y176924D01*
G01Y179404D02*
X1106338D01*
G01X1114186Y175081D02*
X1113956Y175443D01*
X1113650Y175649D01*
X1113305Y175701D01*
X1112998Y175649D01*
X1112691Y175391D01*
X1112500Y175081D01*
X1112461Y174771D01*
X1112538Y174409D01*
X1112806Y174151D01*
X1113075Y174048D01*
X1113420D01*
G01X1113075D02*
X1112845Y173893D01*
X1112653Y173634D01*
X1112576Y173324D01*
X1112653Y173014D01*
X1112845Y172756D01*
X1113190Y172601D01*
X1113535Y172653D01*
X1113880Y172859D01*
G01X1110243Y172601D02*
X1110550Y172704D01*
X1110780Y172963D01*
X1110933Y173273D01*
X1111048Y173686D01*
X1111086Y174151D01*
X1111048Y174616D01*
X1110933Y175029D01*
X1110780Y175339D01*
X1110550Y175598D01*
X1110243Y175701D01*
X1109936Y175598D01*
X1109706Y175339D01*
X1109553Y175029D01*
X1109438Y174616D01*
X1109400Y174151D01*
X1109438Y173686D01*
X1109553Y173273D01*
X1109706Y172963D01*
X1109936Y172704D01*
X1110243Y172601D01*
G01X1117386Y176821D02*
X1117156Y176511D01*
X1116888Y176356D01*
X1116581Y176304D01*
X1116198Y176407D01*
X1115930Y176666D01*
X1115853Y176976D01*
X1115891Y177286D01*
X1116045Y177544D01*
X1116811Y178061D01*
X1117156Y178422D01*
X1117386Y178939D01*
X1117463Y179404D01*
X1115853D01*
G01X1114210Y179042D02*
X1113941Y179301D01*
X1113635Y179404D01*
X1113328Y179301D01*
X1113060Y178991D01*
X1112868Y178526D01*
X1112791Y178061D01*
Y177492D01*
X1112868Y177027D01*
X1113060Y176614D01*
X1113290Y176407D01*
X1113558Y176304D01*
X1113865Y176407D01*
X1114095Y176614D01*
X1114248Y176924D01*
X1114325Y177337D01*
X1114248Y177699D01*
X1114056Y178061D01*
X1113826Y178267D01*
X1113558Y178319D01*
X1113251Y178216D01*
X1113021Y177957D01*
X1112791Y177492D01*
G01X1120831Y173118D02*
X1120601Y172808D01*
X1120333Y172653D01*
X1120026Y172601D01*
X1119643Y172704D01*
X1119375Y172963D01*
X1119298Y173273D01*
X1119336Y173583D01*
X1119490Y173841D01*
X1120256Y174358D01*
X1120601Y174719D01*
X1120831Y175236D01*
X1120908Y175701D01*
X1119298D01*
G01X1117003D02*
X1116735Y175649D01*
X1116428Y175494D01*
X1116236Y175236D01*
X1116160Y174874D01*
X1116236Y174513D01*
X1116466Y174203D01*
X1116811Y174048D01*
X1117195D01*
X1117425Y173944D01*
X1117616Y173686D01*
X1117693Y173324D01*
X1117578Y172963D01*
X1117310Y172704D01*
X1117003Y172601D01*
X1116696Y172704D01*
X1116428Y172963D01*
X1116313Y173324D01*
X1116390Y173686D01*
X1116581Y173944D01*
X1116811Y174048D01*
X1117195D01*
X1117540Y174203D01*
X1117770Y174513D01*
X1117846Y174874D01*
X1117770Y175236D01*
X1117578Y175494D01*
X1117271Y175649D01*
X1117003Y175701D01*
G01X1124145Y176821D02*
X1123915Y176511D01*
X1123647Y176356D01*
X1123340Y176304D01*
X1122957Y176407D01*
X1122689Y176666D01*
X1122612Y176976D01*
X1122650Y177286D01*
X1122804Y177544D01*
X1123570Y178061D01*
X1123915Y178422D01*
X1124145Y178939D01*
X1124222Y179404D01*
X1122612D01*
G01X1120394D02*
X1120317Y178732D01*
X1120202Y178164D01*
X1120049Y177647D01*
X1119857Y177079D01*
X1119550Y176304D01*
X1121084D01*
G01X1127591Y173118D02*
X1127361Y172808D01*
X1127093Y172653D01*
X1126786Y172601D01*
X1126403Y172704D01*
X1126135Y172963D01*
X1126058Y173273D01*
X1126096Y173583D01*
X1126250Y173841D01*
X1127016Y174358D01*
X1127361Y174719D01*
X1127591Y175236D01*
X1127668Y175701D01*
X1126058D01*
G01X1124491Y174409D02*
X1124223Y174048D01*
X1123993Y173841D01*
X1123686Y173738D01*
X1123418Y173841D01*
X1123226Y174048D01*
X1123073Y174358D01*
X1123035Y174719D01*
X1123073Y175029D01*
X1123226Y175339D01*
X1123456Y175598D01*
X1123725Y175701D01*
X1124031Y175598D01*
X1124300Y175288D01*
X1124453Y174823D01*
X1124491Y174306D01*
X1124415Y173634D01*
X1124300Y173273D01*
X1124108Y172911D01*
X1123840Y172653D01*
X1123571Y172601D01*
X1123303Y172704D01*
X1123111Y172963D01*
G01X1130905Y176821D02*
X1130675Y176511D01*
X1130407Y176356D01*
X1130100Y176304D01*
X1129717Y176407D01*
X1129449Y176666D01*
X1129372Y176976D01*
X1129410Y177286D01*
X1129564Y177544D01*
X1130330Y178061D01*
X1130675Y178422D01*
X1130905Y178939D01*
X1130982Y179404D01*
X1129372D01*
G01X1127920Y178939D02*
X1127690Y179197D01*
X1127422Y179352D01*
X1127077Y179404D01*
X1126732Y179301D01*
X1126464Y179094D01*
X1126272Y178732D01*
X1126234Y178319D01*
X1126310Y177906D01*
X1126502Y177647D01*
X1126770Y177441D01*
X1127039Y177389D01*
X1127307Y177441D01*
X1127652Y177647D01*
X1127537Y176304D01*
X1126502D01*
G01X1134351Y173118D02*
X1134121Y172808D01*
X1133853Y172653D01*
X1133546Y172601D01*
X1133163Y172704D01*
X1132895Y172963D01*
X1132818Y173273D01*
X1132856Y173583D01*
X1133010Y173841D01*
X1133776Y174358D01*
X1134121Y174719D01*
X1134351Y175236D01*
X1134428Y175701D01*
X1132818D01*
G01X1130063D02*
Y172601D01*
X1131481Y174823D01*
X1129565D01*
G01X1137665Y176821D02*
X1137435Y176511D01*
X1137167Y176356D01*
X1136860Y176304D01*
X1136477Y176407D01*
X1136209Y176666D01*
X1136132Y176976D01*
X1136170Y177286D01*
X1136324Y177544D01*
X1137090Y178061D01*
X1137435Y178422D01*
X1137665Y178939D01*
X1137742Y179404D01*
X1136132D01*
G01X1134680Y178784D02*
X1134450Y179146D01*
X1134144Y179352D01*
X1133799Y179404D01*
X1133492Y179352D01*
X1133185Y179094D01*
X1132994Y178784D01*
X1132955Y178474D01*
X1133032Y178112D01*
X1133300Y177854D01*
X1133569Y177751D01*
X1133914D01*
G01X1133569D02*
X1133339Y177596D01*
X1133147Y177337D01*
X1133070Y177027D01*
X1133147Y176717D01*
X1133339Y176459D01*
X1133684Y176304D01*
X1134029Y176356D01*
X1134374Y176562D01*
G01X1141110Y173118D02*
X1140880Y172808D01*
X1140612Y172653D01*
X1140305Y172601D01*
X1139922Y172704D01*
X1139654Y172963D01*
X1139577Y173273D01*
X1139615Y173583D01*
X1139769Y173841D01*
X1140535Y174358D01*
X1140880Y174719D01*
X1141110Y175236D01*
X1141187Y175701D01*
X1139577D01*
G01X1138010Y173118D02*
X1137780Y172808D01*
X1137512Y172653D01*
X1137205Y172601D01*
X1136822Y172704D01*
X1136554Y172963D01*
X1136477Y173273D01*
X1136515Y173583D01*
X1136669Y173841D01*
X1137435Y174358D01*
X1137780Y174719D01*
X1138010Y175236D01*
X1138087Y175701D01*
X1136477D01*
G01X1144425Y176821D02*
X1144195Y176511D01*
X1143927Y176356D01*
X1143620Y176304D01*
X1143237Y176407D01*
X1142969Y176666D01*
X1142892Y176976D01*
X1142930Y177286D01*
X1143084Y177544D01*
X1143850Y178061D01*
X1144195Y178422D01*
X1144425Y178939D01*
X1144502Y179404D01*
X1142892D01*
G01X1140597D02*
Y176304D01*
X1141057Y176924D01*
G01Y179404D02*
X1140137D01*
G01X1147870Y173118D02*
X1147640Y172808D01*
X1147372Y172653D01*
X1147065Y172601D01*
X1146682Y172704D01*
X1146414Y172963D01*
X1146337Y173273D01*
X1146375Y173583D01*
X1146529Y173841D01*
X1147295Y174358D01*
X1147640Y174719D01*
X1147870Y175236D01*
X1147947Y175701D01*
X1146337D01*
G01X1144042Y172601D02*
X1144349Y172704D01*
X1144579Y172963D01*
X1144732Y173273D01*
X1144847Y173686D01*
X1144885Y174151D01*
X1144847Y174616D01*
X1144732Y175029D01*
X1144579Y175339D01*
X1144349Y175598D01*
X1144042Y175701D01*
X1143735Y175598D01*
X1143505Y175339D01*
X1143352Y175029D01*
X1143237Y174616D01*
X1143199Y174151D01*
X1143237Y173686D01*
X1143352Y173273D01*
X1143505Y172963D01*
X1143735Y172704D01*
X1144042Y172601D01*
G01X1150457Y179404D02*
Y176304D01*
X1150917Y176924D01*
G01Y179404D02*
X1149997D01*
G01X1148009Y179042D02*
X1147740Y179301D01*
X1147434Y179404D01*
X1147127Y179301D01*
X1146859Y178991D01*
X1146667Y178526D01*
X1146590Y178061D01*
Y177492D01*
X1146667Y177027D01*
X1146859Y176614D01*
X1147089Y176407D01*
X1147357Y176304D01*
X1147664Y176407D01*
X1147894Y176614D01*
X1148047Y176924D01*
X1148124Y177337D01*
X1148047Y177699D01*
X1147855Y178061D01*
X1147625Y178267D01*
X1147357Y178319D01*
X1147050Y178216D01*
X1146820Y177957D01*
X1146590Y177492D01*
G01X1153902Y175701D02*
Y172601D01*
X1154362Y173221D01*
G01Y175701D02*
X1153442D01*
G01X1150802D02*
X1150534Y175649D01*
X1150227Y175494D01*
X1150035Y175236D01*
X1149959Y174874D01*
X1150035Y174513D01*
X1150265Y174203D01*
X1150610Y174048D01*
X1150994D01*
X1151224Y173944D01*
X1151415Y173686D01*
X1151492Y173324D01*
X1151377Y172963D01*
X1151109Y172704D01*
X1150802Y172601D01*
X1150495Y172704D01*
X1150227Y172963D01*
X1150112Y173324D01*
X1150189Y173686D01*
X1150380Y173944D01*
X1150610Y174048D01*
X1150994D01*
X1151339Y174203D01*
X1151569Y174513D01*
X1151645Y174874D01*
X1151569Y175236D01*
X1151377Y175494D01*
X1151070Y175649D01*
X1150802Y175701D01*
G01X1157217Y179404D02*
Y176304D01*
X1157677Y176924D01*
G01Y179404D02*
X1156757D01*
G01X1154194D02*
X1154117Y178732D01*
X1154002Y178164D01*
X1153849Y177647D01*
X1153657Y177079D01*
X1153350Y176304D01*
X1154884D01*
G01X1160662Y175701D02*
Y172601D01*
X1161122Y173221D01*
G01Y175701D02*
X1160202D01*
G01X1158290Y174409D02*
X1158022Y174048D01*
X1157792Y173841D01*
X1157485Y173738D01*
X1157217Y173841D01*
X1157025Y174048D01*
X1156872Y174358D01*
X1156834Y174719D01*
X1156872Y175029D01*
X1157025Y175339D01*
X1157255Y175598D01*
X1157524Y175701D01*
X1157830Y175598D01*
X1158099Y175288D01*
X1158252Y174823D01*
X1158290Y174306D01*
X1158214Y173634D01*
X1158099Y173273D01*
X1157907Y172911D01*
X1157639Y172653D01*
X1157370Y172601D01*
X1157102Y172704D01*
X1156910Y172963D01*
G01X1145550Y420610D02*
X1144483Y420727D01*
X1143550Y421193D01*
X1142750Y421893D01*
X1142217Y422710D01*
X1141950Y423643D01*
Y424577D01*
X1142217Y425510D01*
X1142750Y426327D01*
X1143550Y427027D01*
X1144483Y427493D01*
X1145550Y427610D01*
X1146617Y427493D01*
X1147550Y427027D01*
X1148350Y426327D01*
X1148883Y425510D01*
X1149150Y424577D01*
Y423643D01*
X1148883Y422710D01*
X1148350Y421893D01*
X1147550Y421193D01*
X1146617Y420727D01*
X1145550Y420610D01*
G01X1146617Y422477D02*
X1148217Y420610D01*
G01X1135359Y421923D02*
X1132859D01*
Y422964D01*
X1132984Y423298D01*
X1133151Y423506D01*
X1133484Y423589D01*
X1133817Y423506D01*
X1134026Y423256D01*
X1134151Y422964D01*
Y421923D01*
G01Y422964D02*
X1135359Y423589D01*
G01X1133276Y425064D02*
X1133026Y425314D01*
X1132901Y425606D01*
X1132859Y425939D01*
X1132942Y426356D01*
X1133151Y426648D01*
X1133401Y426731D01*
X1133651Y426689D01*
X1133859Y426523D01*
X1134276Y425689D01*
X1134567Y425314D01*
X1134984Y425064D01*
X1135359Y424981D01*
Y426731D01*
G01X1134984Y428039D02*
X1135192Y428289D01*
X1135317Y428581D01*
X1135359Y428956D01*
X1135276Y429331D01*
X1135109Y429623D01*
X1134817Y429831D01*
X1134484Y429873D01*
X1134151Y429789D01*
X1133942Y429581D01*
X1133776Y429289D01*
X1133734Y428998D01*
X1133776Y428706D01*
X1133942Y428331D01*
X1132859Y428456D01*
Y429581D01*
G01Y430806D02*
X1135359Y431389D01*
X1132859Y432056D01*
X1135359Y432723D01*
X1132859Y433306D01*
G01X1135359Y435156D02*
X1132859D01*
X1133359Y434656D01*
G01X1135359D02*
Y435656D01*
G01X1132859Y438256D02*
X1132942Y437923D01*
X1133151Y437673D01*
X1133401Y437506D01*
X1133734Y437381D01*
X1134109Y437339D01*
X1134484Y437381D01*
X1134817Y437506D01*
X1135067Y437673D01*
X1135276Y437923D01*
X1135359Y438256D01*
X1135276Y438589D01*
X1135067Y438839D01*
X1134817Y439006D01*
X1134484Y439131D01*
X1134109Y439173D01*
X1133734Y439131D01*
X1133401Y439006D01*
X1133151Y438839D01*
X1132942Y438589D01*
X1132859Y438256D01*
G01Y441356D02*
X1132942Y441023D01*
X1133151Y440773D01*
X1133401Y440606D01*
X1133734Y440481D01*
X1134109Y440439D01*
X1134484Y440481D01*
X1134817Y440606D01*
X1135067Y440773D01*
X1135276Y441023D01*
X1135359Y441356D01*
X1135276Y441689D01*
X1135067Y441939D01*
X1134817Y442106D01*
X1134484Y442231D01*
X1134109Y442273D01*
X1133734Y442231D01*
X1133401Y442106D01*
X1133151Y441939D01*
X1132942Y441689D01*
X1132859Y441356D01*
G01X1139059Y421723D02*
X1136559D01*
Y422764D01*
X1136684Y423098D01*
X1136851Y423306D01*
X1137184Y423389D01*
X1137517Y423306D01*
X1137726Y423056D01*
X1137851Y422764D01*
Y421723D01*
G01Y422764D02*
X1139059Y423389D01*
G01X1136976Y424864D02*
X1136726Y425114D01*
X1136601Y425406D01*
X1136559Y425739D01*
X1136642Y426156D01*
X1136851Y426448D01*
X1137101Y426531D01*
X1137351Y426489D01*
X1137559Y426323D01*
X1137976Y425489D01*
X1138267Y425114D01*
X1138684Y424864D01*
X1139059Y424781D01*
Y426531D01*
G01X1138684Y427839D02*
X1138892Y428089D01*
X1139017Y428381D01*
X1139059Y428756D01*
X1138976Y429131D01*
X1138809Y429423D01*
X1138517Y429631D01*
X1138184Y429673D01*
X1137851Y429589D01*
X1137642Y429381D01*
X1137476Y429089D01*
X1137434Y428798D01*
X1137476Y428506D01*
X1137642Y428131D01*
X1136559Y428256D01*
Y429381D01*
G01Y430606D02*
X1139059Y431189D01*
X1136559Y431856D01*
X1139059Y432523D01*
X1136559Y433106D01*
G01X1139059Y434956D02*
X1139017Y435248D01*
X1138892Y435581D01*
X1138684Y435789D01*
X1138392Y435873D01*
X1138101Y435789D01*
X1137851Y435539D01*
X1137726Y435164D01*
Y434748D01*
X1137642Y434498D01*
X1137434Y434289D01*
X1137142Y434206D01*
X1136851Y434331D01*
X1136642Y434623D01*
X1136559Y434956D01*
X1136642Y435289D01*
X1136851Y435581D01*
X1137142Y435706D01*
X1137434Y435623D01*
X1137642Y435414D01*
X1137726Y435164D01*
Y434748D01*
X1137851Y434373D01*
X1138101Y434123D01*
X1138392Y434039D01*
X1138684Y434123D01*
X1138892Y434331D01*
X1139017Y434664D01*
X1139059Y434956D01*
G01X1138559Y437139D02*
X1138851Y437389D01*
X1139017Y437723D01*
X1139059Y438098D01*
X1139017Y438431D01*
X1138809Y438764D01*
X1138559Y438973D01*
X1138309Y439014D01*
X1138017Y438931D01*
X1137809Y438639D01*
X1137726Y438348D01*
Y437973D01*
G01Y438348D02*
X1137601Y438598D01*
X1137392Y438806D01*
X1137142Y438889D01*
X1136892Y438806D01*
X1136684Y438598D01*
X1136559Y438223D01*
X1136601Y437848D01*
X1136767Y437473D01*
G01X1131959Y421923D02*
X1129459D01*
Y422964D01*
X1129584Y423298D01*
X1129751Y423506D01*
X1130084Y423589D01*
X1130417Y423506D01*
X1130626Y423256D01*
X1130751Y422964D01*
Y421923D01*
G01Y422964D02*
X1131959Y423589D01*
G01X1129876Y425064D02*
X1129626Y425314D01*
X1129501Y425606D01*
X1129459Y425939D01*
X1129542Y426356D01*
X1129751Y426648D01*
X1130001Y426731D01*
X1130251Y426689D01*
X1130459Y426523D01*
X1130876Y425689D01*
X1131167Y425314D01*
X1131584Y425064D01*
X1131959Y424981D01*
Y426731D01*
G01X1131584Y428039D02*
X1131792Y428289D01*
X1131917Y428581D01*
X1131959Y428956D01*
X1131876Y429331D01*
X1131709Y429623D01*
X1131417Y429831D01*
X1131084Y429873D01*
X1130751Y429789D01*
X1130542Y429581D01*
X1130376Y429289D01*
X1130334Y428998D01*
X1130376Y428706D01*
X1130542Y428331D01*
X1129459Y428456D01*
Y429581D01*
G01Y430806D02*
X1131959Y431389D01*
X1129459Y432056D01*
X1131959Y432723D01*
X1129459Y433306D01*
G01X1131959Y435156D02*
X1129459D01*
X1129959Y434656D01*
G01X1131959D02*
Y435656D01*
G01X1129459Y438256D02*
X1129542Y437923D01*
X1129751Y437673D01*
X1130001Y437506D01*
X1130334Y437381D01*
X1130709Y437339D01*
X1131084Y437381D01*
X1131417Y437506D01*
X1131667Y437673D01*
X1131876Y437923D01*
X1131959Y438256D01*
X1131876Y438589D01*
X1131667Y438839D01*
X1131417Y439006D01*
X1131084Y439131D01*
X1130709Y439173D01*
X1130334Y439131D01*
X1130001Y439006D01*
X1129751Y438839D01*
X1129542Y438589D01*
X1129459Y438256D01*
G01X1131959Y441856D02*
X1129459D01*
X1131251Y440314D01*
Y442398D01*
G01X1124559Y421923D02*
X1122059D01*
Y422964D01*
X1122184Y423298D01*
X1122351Y423506D01*
X1122684Y423589D01*
X1123017Y423506D01*
X1123226Y423256D01*
X1123351Y422964D01*
Y421923D01*
G01Y422964D02*
X1124559Y423589D01*
G01X1122476Y425064D02*
X1122226Y425314D01*
X1122101Y425606D01*
X1122059Y425939D01*
X1122142Y426356D01*
X1122351Y426648D01*
X1122601Y426731D01*
X1122851Y426689D01*
X1123059Y426523D01*
X1123476Y425689D01*
X1123767Y425314D01*
X1124184Y425064D01*
X1124559Y424981D01*
Y426731D01*
G01X1124184Y428039D02*
X1124392Y428289D01*
X1124517Y428581D01*
X1124559Y428956D01*
X1124476Y429331D01*
X1124309Y429623D01*
X1124017Y429831D01*
X1123684Y429873D01*
X1123351Y429789D01*
X1123142Y429581D01*
X1122976Y429289D01*
X1122934Y428998D01*
X1122976Y428706D01*
X1123142Y428331D01*
X1122059Y428456D01*
Y429581D01*
G01Y430806D02*
X1124559Y431389D01*
X1122059Y432056D01*
X1124559Y432723D01*
X1122059Y433306D01*
G01X1124559Y435156D02*
X1122059D01*
X1122559Y434656D01*
G01X1124559D02*
Y435656D01*
G01X1122059Y438256D02*
X1122142Y437923D01*
X1122351Y437673D01*
X1122601Y437506D01*
X1122934Y437381D01*
X1123309Y437339D01*
X1123684Y437381D01*
X1124017Y437506D01*
X1124267Y437673D01*
X1124476Y437923D01*
X1124559Y438256D01*
X1124476Y438589D01*
X1124267Y438839D01*
X1124017Y439006D01*
X1123684Y439131D01*
X1123309Y439173D01*
X1122934Y439131D01*
X1122601Y439006D01*
X1122351Y438839D01*
X1122142Y438589D01*
X1122059Y438256D01*
G01X1124059Y440439D02*
X1124351Y440689D01*
X1124517Y441023D01*
X1124559Y441398D01*
X1124517Y441731D01*
X1124309Y442064D01*
X1124059Y442273D01*
X1123809Y442314D01*
X1123517Y442231D01*
X1123309Y441939D01*
X1123226Y441648D01*
Y441273D01*
G01Y441648D02*
X1123101Y441898D01*
X1122892Y442106D01*
X1122642Y442189D01*
X1122392Y442106D01*
X1122184Y441898D01*
X1122059Y441523D01*
X1122101Y441148D01*
X1122267Y440773D01*
G01X1128259Y421923D02*
X1125759D01*
Y422964D01*
X1125884Y423298D01*
X1126051Y423506D01*
X1126384Y423589D01*
X1126717Y423506D01*
X1126926Y423256D01*
X1127051Y422964D01*
Y421923D01*
G01Y422964D02*
X1128259Y423589D01*
G01X1126176Y425064D02*
X1125926Y425314D01*
X1125801Y425606D01*
X1125759Y425939D01*
X1125842Y426356D01*
X1126051Y426648D01*
X1126301Y426731D01*
X1126551Y426689D01*
X1126759Y426523D01*
X1127176Y425689D01*
X1127467Y425314D01*
X1127884Y425064D01*
X1128259Y424981D01*
Y426731D01*
G01X1127884Y428039D02*
X1128092Y428289D01*
X1128217Y428581D01*
X1128259Y428956D01*
X1128176Y429331D01*
X1128009Y429623D01*
X1127717Y429831D01*
X1127384Y429873D01*
X1127051Y429789D01*
X1126842Y429581D01*
X1126676Y429289D01*
X1126634Y428998D01*
X1126676Y428706D01*
X1126842Y428331D01*
X1125759Y428456D01*
Y429581D01*
G01Y430806D02*
X1128259Y431389D01*
X1125759Y432056D01*
X1128259Y432723D01*
X1125759Y433306D01*
G01X1128259Y435156D02*
X1125759D01*
X1126259Y434656D01*
G01X1128259D02*
Y435656D01*
G01X1125759Y438256D02*
X1125842Y437923D01*
X1126051Y437673D01*
X1126301Y437506D01*
X1126634Y437381D01*
X1127009Y437339D01*
X1127384Y437381D01*
X1127717Y437506D01*
X1127967Y437673D01*
X1128176Y437923D01*
X1128259Y438256D01*
X1128176Y438589D01*
X1127967Y438839D01*
X1127717Y439006D01*
X1127384Y439131D01*
X1127009Y439173D01*
X1126634Y439131D01*
X1126301Y439006D01*
X1126051Y438839D01*
X1125842Y438589D01*
X1125759Y438256D01*
G01X1126176Y440564D02*
X1125926Y440814D01*
X1125801Y441106D01*
X1125759Y441439D01*
X1125842Y441856D01*
X1126051Y442148D01*
X1126301Y442231D01*
X1126551Y442189D01*
X1126759Y442023D01*
X1127176Y441189D01*
X1127467Y440814D01*
X1127884Y440564D01*
X1128259Y440481D01*
Y442231D01*
G01X1109759Y421923D02*
X1107259D01*
Y422964D01*
X1107384Y423298D01*
X1107551Y423506D01*
X1107884Y423589D01*
X1108217Y423506D01*
X1108426Y423256D01*
X1108551Y422964D01*
Y421923D01*
G01Y422964D02*
X1109759Y423589D01*
G01Y425856D02*
X1107259D01*
X1107759Y425356D01*
G01X1109759D02*
Y426356D01*
G01X1107259Y428956D02*
X1109759D01*
G01X1107259Y427998D02*
Y429914D01*
G01X1109759Y432056D02*
X1107259D01*
X1107759Y431556D01*
G01X1109759D02*
Y432556D01*
G01X1109384Y434239D02*
X1109592Y434489D01*
X1109717Y434781D01*
X1109759Y435156D01*
X1109676Y435531D01*
X1109509Y435823D01*
X1109217Y436031D01*
X1108884Y436073D01*
X1108551Y435989D01*
X1108342Y435781D01*
X1108176Y435489D01*
X1108134Y435198D01*
X1108176Y434906D01*
X1108342Y434531D01*
X1107259Y434656D01*
Y435781D01*
G01X1113459Y421923D02*
X1110959D01*
Y422964D01*
X1111084Y423298D01*
X1111251Y423506D01*
X1111584Y423589D01*
X1111917Y423506D01*
X1112126Y423256D01*
X1112251Y422964D01*
Y421923D01*
G01Y422964D02*
X1113459Y423589D01*
G01Y425856D02*
X1110959D01*
X1111459Y425356D01*
G01X1113459D02*
Y426356D01*
G01X1110959Y428956D02*
X1113459D01*
G01X1110959Y427998D02*
Y429914D01*
G01X1111376Y431264D02*
X1111126Y431514D01*
X1111001Y431806D01*
X1110959Y432139D01*
X1111042Y432556D01*
X1111251Y432848D01*
X1111501Y432931D01*
X1111751Y432889D01*
X1111959Y432723D01*
X1112376Y431889D01*
X1112667Y431514D01*
X1113084Y431264D01*
X1113459Y431181D01*
Y432931D01*
G01X1112959Y434239D02*
X1113251Y434489D01*
X1113417Y434823D01*
X1113459Y435198D01*
X1113417Y435531D01*
X1113209Y435864D01*
X1112959Y436073D01*
X1112709Y436114D01*
X1112417Y436031D01*
X1112209Y435739D01*
X1112126Y435448D01*
Y435073D01*
G01Y435448D02*
X1112001Y435698D01*
X1111792Y435906D01*
X1111542Y435989D01*
X1111292Y435906D01*
X1111084Y435698D01*
X1110959Y435323D01*
X1111001Y434948D01*
X1111167Y434573D01*
G01X1105994Y420849D02*
X1103494D01*
Y421890D01*
X1103619Y422224D01*
X1103786Y422432D01*
X1104119Y422515D01*
X1104452Y422432D01*
X1104661Y422182D01*
X1104786Y421890D01*
Y420849D01*
G01Y421890D02*
X1105994Y422515D01*
G01X1103911Y423990D02*
X1103661Y424240D01*
X1103536Y424532D01*
X1103494Y424865D01*
X1103577Y425282D01*
X1103786Y425574D01*
X1104036Y425657D01*
X1104286Y425615D01*
X1104494Y425449D01*
X1104911Y424615D01*
X1105202Y424240D01*
X1105619Y423990D01*
X1105994Y423907D01*
Y425657D01*
G01X1105619Y426965D02*
X1105827Y427215D01*
X1105952Y427507D01*
X1105994Y427882D01*
X1105911Y428257D01*
X1105744Y428549D01*
X1105452Y428757D01*
X1105119Y428799D01*
X1104786Y428715D01*
X1104577Y428507D01*
X1104411Y428215D01*
X1104369Y427924D01*
X1104411Y427632D01*
X1104577Y427257D01*
X1103494Y427382D01*
Y428507D01*
G01Y429732D02*
X1105994Y430315D01*
X1103494Y430982D01*
X1105994Y431649D01*
X1103494Y432232D01*
G01X1104952Y433290D02*
X1104661Y433582D01*
X1104494Y433832D01*
X1104411Y434165D01*
X1104494Y434457D01*
X1104661Y434665D01*
X1104911Y434832D01*
X1105202Y434874D01*
X1105452Y434832D01*
X1105702Y434665D01*
X1105911Y434415D01*
X1105994Y434124D01*
X1105911Y433790D01*
X1105661Y433499D01*
X1105286Y433332D01*
X1104869Y433290D01*
X1104327Y433374D01*
X1104036Y433499D01*
X1103744Y433707D01*
X1103536Y433999D01*
X1103494Y434290D01*
X1103577Y434582D01*
X1103786Y434790D01*
G01X1105994Y437682D02*
X1103494D01*
X1105286Y436140D01*
Y438224D01*
G01X1117159Y421923D02*
X1114659D01*
Y422964D01*
X1114784Y423298D01*
X1114951Y423506D01*
X1115284Y423589D01*
X1115617Y423506D01*
X1115826Y423256D01*
X1115951Y422964D01*
Y421923D01*
G01Y422964D02*
X1117159Y423589D01*
G01X1115076Y425064D02*
X1114826Y425314D01*
X1114701Y425606D01*
X1114659Y425939D01*
X1114742Y426356D01*
X1114951Y426648D01*
X1115201Y426731D01*
X1115451Y426689D01*
X1115659Y426523D01*
X1116076Y425689D01*
X1116367Y425314D01*
X1116784Y425064D01*
X1117159Y424981D01*
Y426731D01*
G01X1116784Y428039D02*
X1116992Y428289D01*
X1117117Y428581D01*
X1117159Y428956D01*
X1117076Y429331D01*
X1116909Y429623D01*
X1116617Y429831D01*
X1116284Y429873D01*
X1115951Y429789D01*
X1115742Y429581D01*
X1115576Y429289D01*
X1115534Y428998D01*
X1115576Y428706D01*
X1115742Y428331D01*
X1114659Y428456D01*
Y429581D01*
G01Y430806D02*
X1117159Y431389D01*
X1114659Y432056D01*
X1117159Y432723D01*
X1114659Y433306D01*
G01X1117159Y435156D02*
X1114659D01*
X1115159Y434656D01*
G01X1117159D02*
Y435656D01*
G01X1114659Y438256D02*
X1114742Y437923D01*
X1114951Y437673D01*
X1115201Y437506D01*
X1115534Y437381D01*
X1115909Y437339D01*
X1116284Y437381D01*
X1116617Y437506D01*
X1116867Y437673D01*
X1117076Y437923D01*
X1117159Y438256D01*
X1117076Y438589D01*
X1116867Y438839D01*
X1116617Y439006D01*
X1116284Y439131D01*
X1115909Y439173D01*
X1115534Y439131D01*
X1115201Y439006D01*
X1114951Y438839D01*
X1114742Y438589D01*
X1114659Y438256D01*
G01X1117159Y441356D02*
X1114659D01*
X1115159Y440856D01*
G01X1117159D02*
Y441856D01*
G01X1120859Y421923D02*
X1118359D01*
Y422964D01*
X1118484Y423298D01*
X1118651Y423506D01*
X1118984Y423589D01*
X1119317Y423506D01*
X1119526Y423256D01*
X1119651Y422964D01*
Y421923D01*
G01Y422964D02*
X1120859Y423589D01*
G01X1118776Y425064D02*
X1118526Y425314D01*
X1118401Y425606D01*
X1118359Y425939D01*
X1118442Y426356D01*
X1118651Y426648D01*
X1118901Y426731D01*
X1119151Y426689D01*
X1119359Y426523D01*
X1119776Y425689D01*
X1120067Y425314D01*
X1120484Y425064D01*
X1120859Y424981D01*
Y426731D01*
G01X1120484Y428039D02*
X1120692Y428289D01*
X1120817Y428581D01*
X1120859Y428956D01*
X1120776Y429331D01*
X1120609Y429623D01*
X1120317Y429831D01*
X1119984Y429873D01*
X1119651Y429789D01*
X1119442Y429581D01*
X1119276Y429289D01*
X1119234Y428998D01*
X1119276Y428706D01*
X1119442Y428331D01*
X1118359Y428456D01*
Y429581D01*
G01Y430806D02*
X1120859Y431389D01*
X1118359Y432056D01*
X1120859Y432723D01*
X1118359Y433306D01*
G01X1120567Y434448D02*
X1120776Y434739D01*
X1120859Y435073D01*
X1120776Y435406D01*
X1120526Y435698D01*
X1120151Y435906D01*
X1119776Y435989D01*
X1119317D01*
X1118942Y435906D01*
X1118609Y435698D01*
X1118442Y435448D01*
X1118359Y435156D01*
X1118442Y434823D01*
X1118609Y434573D01*
X1118859Y434406D01*
X1119192Y434323D01*
X1119484Y434406D01*
X1119776Y434614D01*
X1119942Y434864D01*
X1119984Y435156D01*
X1119901Y435489D01*
X1119692Y435739D01*
X1119317Y435989D01*
G01X1120567Y437548D02*
X1120776Y437839D01*
X1120859Y438173D01*
X1120776Y438506D01*
X1120526Y438798D01*
X1120151Y439006D01*
X1119776Y439089D01*
X1119317D01*
X1118942Y439006D01*
X1118609Y438798D01*
X1118442Y438548D01*
X1118359Y438256D01*
X1118442Y437923D01*
X1118609Y437673D01*
X1118859Y437506D01*
X1119192Y437423D01*
X1119484Y437506D01*
X1119776Y437714D01*
X1119942Y437964D01*
X1119984Y438256D01*
X1119901Y438589D01*
X1119692Y438839D01*
X1119317Y439089D01*
G01X1102294Y420849D02*
X1099794D01*
Y421890D01*
X1099919Y422224D01*
X1100086Y422432D01*
X1100419Y422515D01*
X1100752Y422432D01*
X1100961Y422182D01*
X1101086Y421890D01*
Y420849D01*
G01Y421890D02*
X1102294Y422515D01*
G01X1100211Y423990D02*
X1099961Y424240D01*
X1099836Y424532D01*
X1099794Y424865D01*
X1099877Y425282D01*
X1100086Y425574D01*
X1100336Y425657D01*
X1100586Y425615D01*
X1100794Y425449D01*
X1101211Y424615D01*
X1101502Y424240D01*
X1101919Y423990D01*
X1102294Y423907D01*
Y425657D01*
G01X1101919Y426965D02*
X1102127Y427215D01*
X1102252Y427507D01*
X1102294Y427882D01*
X1102211Y428257D01*
X1102044Y428549D01*
X1101752Y428757D01*
X1101419Y428799D01*
X1101086Y428715D01*
X1100877Y428507D01*
X1100711Y428215D01*
X1100669Y427924D01*
X1100711Y427632D01*
X1100877Y427257D01*
X1099794Y427382D01*
Y428507D01*
G01Y429732D02*
X1102294Y430315D01*
X1099794Y430982D01*
X1102294Y431649D01*
X1099794Y432232D01*
G01X1101252Y433290D02*
X1100961Y433582D01*
X1100794Y433832D01*
X1100711Y434165D01*
X1100794Y434457D01*
X1100961Y434665D01*
X1101211Y434832D01*
X1101502Y434874D01*
X1101752Y434832D01*
X1102002Y434665D01*
X1102211Y434415D01*
X1102294Y434124D01*
X1102211Y433790D01*
X1101961Y433499D01*
X1101586Y433332D01*
X1101169Y433290D01*
X1100627Y433374D01*
X1100336Y433499D01*
X1100044Y433707D01*
X1099836Y433999D01*
X1099794Y434290D01*
X1099877Y434582D01*
X1100086Y434790D01*
G01X1101919Y436265D02*
X1102127Y436515D01*
X1102252Y436807D01*
X1102294Y437182D01*
X1102211Y437557D01*
X1102044Y437849D01*
X1101752Y438057D01*
X1101419Y438099D01*
X1101086Y438015D01*
X1100877Y437807D01*
X1100711Y437515D01*
X1100669Y437224D01*
X1100711Y436932D01*
X1100877Y436557D01*
X1099794Y436682D01*
Y437807D01*
G01X1096367Y423673D02*
X1096242Y423423D01*
X1096159Y423131D01*
Y422798D01*
X1096284Y422423D01*
X1096492Y422131D01*
X1096742Y421923D01*
X1097159Y421756D01*
X1097534Y421714D01*
X1097909Y421798D01*
X1098159Y421923D01*
X1098409Y422173D01*
X1098576Y422464D01*
X1098659Y422756D01*
Y423048D01*
X1098576Y423339D01*
X1098451Y423589D01*
X1098284Y423798D01*
G01X1096576Y425064D02*
X1096326Y425314D01*
X1096201Y425606D01*
X1096159Y425939D01*
X1096242Y426356D01*
X1096451Y426648D01*
X1096701Y426731D01*
X1096951Y426689D01*
X1097159Y426523D01*
X1097576Y425689D01*
X1097867Y425314D01*
X1098284Y425064D01*
X1098659Y424981D01*
Y426731D01*
G01X1098284Y428039D02*
X1098492Y428289D01*
X1098617Y428581D01*
X1098659Y428956D01*
X1098576Y429331D01*
X1098409Y429623D01*
X1098117Y429831D01*
X1097784Y429873D01*
X1097451Y429789D01*
X1097242Y429581D01*
X1097076Y429289D01*
X1097034Y428998D01*
X1097076Y428706D01*
X1097242Y428331D01*
X1096159Y428456D01*
Y429581D01*
G01Y430806D02*
X1098659Y431389D01*
X1096159Y432056D01*
X1098659Y432723D01*
X1096159Y433306D01*
G01X1096576Y434364D02*
X1096326Y434614D01*
X1096201Y434906D01*
X1096159Y435239D01*
X1096242Y435656D01*
X1096451Y435948D01*
X1096701Y436031D01*
X1096951Y435989D01*
X1097159Y435823D01*
X1097576Y434989D01*
X1097867Y434614D01*
X1098284Y434364D01*
X1098659Y434281D01*
Y436031D01*
G01X1096159Y438256D02*
X1096242Y437923D01*
X1096451Y437673D01*
X1096701Y437506D01*
X1097034Y437381D01*
X1097409Y437339D01*
X1097784Y437381D01*
X1098117Y437506D01*
X1098367Y437673D01*
X1098576Y437923D01*
X1098659Y438256D01*
X1098576Y438589D01*
X1098367Y438839D01*
X1098117Y439006D01*
X1097784Y439131D01*
X1097409Y439173D01*
X1097034Y439131D01*
X1096701Y439006D01*
X1096451Y438839D01*
X1096242Y438589D01*
X1096159Y438256D01*
G01X1150702Y491679D02*
X1148202D01*
Y492720D01*
X1148327Y493054D01*
X1148494Y493262D01*
X1148827Y493345D01*
X1149160Y493262D01*
X1149369Y493012D01*
X1149494Y492720D01*
Y491679D01*
G01Y492720D02*
X1150702Y493345D01*
G01Y495612D02*
X1150660Y495904D01*
X1150535Y496237D01*
X1150327Y496445D01*
X1150035Y496529D01*
X1149744Y496445D01*
X1149494Y496195D01*
X1149369Y495820D01*
Y495404D01*
X1149285Y495154D01*
X1149077Y494945D01*
X1148785Y494862D01*
X1148494Y494987D01*
X1148285Y495279D01*
X1148202Y495612D01*
X1148285Y495945D01*
X1148494Y496237D01*
X1148785Y496362D01*
X1149077Y496279D01*
X1149285Y496070D01*
X1149369Y495820D01*
Y495404D01*
X1149494Y495029D01*
X1149744Y494779D01*
X1150035Y494695D01*
X1150327Y494779D01*
X1150535Y494987D01*
X1150660Y495320D01*
X1150702Y495612D01*
G01X1148202Y497462D02*
X1150702Y498045D01*
X1148202Y498712D01*
X1150702Y499379D01*
X1148202Y499962D01*
G01X1148619Y501020D02*
X1148369Y501270D01*
X1148244Y501562D01*
X1148202Y501895D01*
X1148285Y502312D01*
X1148494Y502604D01*
X1148744Y502687D01*
X1148994Y502645D01*
X1149202Y502479D01*
X1149619Y501645D01*
X1149910Y501270D01*
X1150327Y501020D01*
X1150702Y500937D01*
Y502687D01*
G01X1146305Y491943D02*
X1143805D01*
Y492984D01*
X1143930Y493318D01*
X1144097Y493526D01*
X1144430Y493609D01*
X1144763Y493526D01*
X1144972Y493276D01*
X1145097Y492984D01*
Y491943D01*
G01Y492984D02*
X1146305Y493609D01*
G01Y495876D02*
X1146263Y496168D01*
X1146138Y496501D01*
X1145930Y496709D01*
X1145638Y496793D01*
X1145347Y496709D01*
X1145097Y496459D01*
X1144972Y496084D01*
Y495668D01*
X1144888Y495418D01*
X1144680Y495209D01*
X1144388Y495126D01*
X1144097Y495251D01*
X1143888Y495543D01*
X1143805Y495876D01*
X1143888Y496209D01*
X1144097Y496501D01*
X1144388Y496626D01*
X1144680Y496543D01*
X1144888Y496334D01*
X1144972Y496084D01*
Y495668D01*
X1145097Y495293D01*
X1145347Y495043D01*
X1145638Y494959D01*
X1145930Y495043D01*
X1146138Y495251D01*
X1146263Y495584D01*
X1146305Y495876D01*
G01X1143805Y497726D02*
X1146305Y498309D01*
X1143805Y498976D01*
X1146305Y499643D01*
X1143805Y500226D01*
G01X1145805Y501159D02*
X1146097Y501409D01*
X1146263Y501743D01*
X1146305Y502118D01*
X1146263Y502451D01*
X1146055Y502784D01*
X1145805Y502993D01*
X1145555Y503034D01*
X1145263Y502951D01*
X1145055Y502659D01*
X1144972Y502368D01*
Y501993D01*
G01Y502368D02*
X1144847Y502618D01*
X1144638Y502826D01*
X1144388Y502909D01*
X1144138Y502826D01*
X1143930Y502618D01*
X1143805Y502243D01*
X1143847Y501868D01*
X1144013Y501493D01*
G01X1150297Y505039D02*
X1147797D01*
Y506080D01*
X1147922Y506414D01*
X1148089Y506622D01*
X1148422Y506705D01*
X1148755Y506622D01*
X1148964Y506372D01*
X1149089Y506080D01*
Y505039D01*
G01Y506080D02*
X1150297Y506705D01*
G01Y508972D02*
X1150255Y509264D01*
X1150130Y509597D01*
X1149922Y509805D01*
X1149630Y509889D01*
X1149339Y509805D01*
X1149089Y509555D01*
X1148964Y509180D01*
Y508764D01*
X1148880Y508514D01*
X1148672Y508305D01*
X1148380Y508222D01*
X1148089Y508347D01*
X1147880Y508639D01*
X1147797Y508972D01*
X1147880Y509305D01*
X1148089Y509597D01*
X1148380Y509722D01*
X1148672Y509639D01*
X1148880Y509430D01*
X1148964Y509180D01*
Y508764D01*
X1149089Y508389D01*
X1149339Y508139D01*
X1149630Y508055D01*
X1149922Y508139D01*
X1150130Y508347D01*
X1150255Y508680D01*
X1150297Y508972D01*
G01Y511030D02*
X1147797Y512072D01*
X1150297Y513114D01*
G01X1149422Y512739D02*
Y511405D01*
G01X1150297Y515172D02*
X1147797D01*
X1148297Y514672D01*
G01X1150297D02*
Y515672D01*
G01X1130585Y493929D02*
Y496429D01*
X1131626D01*
X1131960Y496304D01*
X1132168Y496137D01*
X1132251Y495804D01*
X1132168Y495471D01*
X1131918Y495262D01*
X1131626Y495137D01*
X1130585D01*
G01X1131626D02*
X1132251Y493929D01*
G01X1133726D02*
Y496429D01*
X1135310D01*
G01X1134726Y495221D02*
X1133726D01*
G01X1136826Y496012D02*
X1137076Y496262D01*
X1137368Y496387D01*
X1137701Y496429D01*
X1138118Y496346D01*
X1138410Y496137D01*
X1138493Y495887D01*
X1138451Y495637D01*
X1138285Y495429D01*
X1137451Y495012D01*
X1137076Y494721D01*
X1136826Y494304D01*
X1136743Y493929D01*
X1138493D01*
G01X1139801Y494429D02*
X1140051Y494137D01*
X1140385Y493971D01*
X1140760Y493929D01*
X1141093Y493971D01*
X1141426Y494179D01*
X1141635Y494429D01*
X1141676Y494679D01*
X1141593Y494971D01*
X1141301Y495179D01*
X1141010Y495262D01*
X1140635D01*
G01X1141010D02*
X1141260Y495387D01*
X1141468Y495596D01*
X1141551Y495846D01*
X1141468Y496096D01*
X1141260Y496304D01*
X1140885Y496429D01*
X1140510Y496387D01*
X1140135Y496221D01*
G01X1117685Y493529D02*
Y496029D01*
X1118726D01*
X1119060Y495904D01*
X1119268Y495737D01*
X1119351Y495404D01*
X1119268Y495071D01*
X1119018Y494862D01*
X1118726Y494737D01*
X1117685D01*
G01X1118726D02*
X1119351Y493529D01*
G01X1120826D02*
Y496029D01*
X1122410D01*
G01X1121826Y494821D02*
X1120826D01*
G01X1123926Y495612D02*
X1124176Y495862D01*
X1124468Y495987D01*
X1124801Y496029D01*
X1125218Y495946D01*
X1125510Y495737D01*
X1125593Y495487D01*
X1125551Y495237D01*
X1125385Y495029D01*
X1124551Y494612D01*
X1124176Y494321D01*
X1123926Y493904D01*
X1123843Y493529D01*
X1125593D01*
G01X1128318D02*
Y496029D01*
X1126776Y494237D01*
X1128860D01*
G01X1101285Y487029D02*
Y489529D01*
X1102326D01*
X1102660Y489404D01*
X1102868Y489237D01*
X1102951Y488904D01*
X1102868Y488571D01*
X1102618Y488362D01*
X1102326Y488237D01*
X1101285D01*
G01X1102326D02*
X1102951Y487029D01*
G01X1105218D02*
X1105510Y487071D01*
X1105843Y487196D01*
X1106051Y487404D01*
X1106135Y487696D01*
X1106051Y487987D01*
X1105801Y488237D01*
X1105426Y488362D01*
X1105010D01*
X1104760Y488446D01*
X1104551Y488654D01*
X1104468Y488946D01*
X1104593Y489237D01*
X1104885Y489446D01*
X1105218Y489529D01*
X1105551Y489446D01*
X1105843Y489237D01*
X1105968Y488946D01*
X1105885Y488654D01*
X1105676Y488446D01*
X1105426Y488362D01*
X1105010D01*
X1104635Y488237D01*
X1104385Y487987D01*
X1104301Y487696D01*
X1104385Y487404D01*
X1104593Y487196D01*
X1104926Y487071D01*
X1105218Y487029D01*
G01X1107276D02*
X1108318Y489529D01*
X1109360Y487029D01*
G01X1108985Y487904D02*
X1107651D01*
G01X1111918Y487029D02*
Y489529D01*
X1110376Y487737D01*
X1112460D01*
G01X1109185Y490429D02*
Y492929D01*
X1110226D01*
X1110560Y492804D01*
X1110768Y492637D01*
X1110851Y492304D01*
X1110768Y491971D01*
X1110518Y491762D01*
X1110226Y491637D01*
X1109185D01*
G01X1110226D02*
X1110851Y490429D01*
G01X1113118D02*
X1113410Y490471D01*
X1113743Y490596D01*
X1113951Y490804D01*
X1114035Y491096D01*
X1113951Y491387D01*
X1113701Y491637D01*
X1113326Y491762D01*
X1112910D01*
X1112660Y491846D01*
X1112451Y492054D01*
X1112368Y492346D01*
X1112493Y492637D01*
X1112785Y492846D01*
X1113118Y492929D01*
X1113451Y492846D01*
X1113743Y492637D01*
X1113868Y492346D01*
X1113785Y492054D01*
X1113576Y491846D01*
X1113326Y491762D01*
X1112910D01*
X1112535Y491637D01*
X1112285Y491387D01*
X1112201Y491096D01*
X1112285Y490804D01*
X1112493Y490596D01*
X1112826Y490471D01*
X1113118Y490429D01*
G01X1115176D02*
X1116218Y492929D01*
X1117260Y490429D01*
G01X1116885Y491304D02*
X1115551D01*
G01X1118526Y492512D02*
X1118776Y492762D01*
X1119068Y492887D01*
X1119401Y492929D01*
X1119818Y492846D01*
X1120110Y492637D01*
X1120193Y492387D01*
X1120151Y492137D01*
X1119985Y491929D01*
X1119151Y491512D01*
X1118776Y491221D01*
X1118526Y490804D01*
X1118443Y490429D01*
X1120193D01*
G01X1141555Y483158D02*
Y485658D01*
X1142596D01*
X1142930Y485533D01*
X1143138Y485366D01*
X1143221Y485033D01*
X1143138Y484700D01*
X1142888Y484491D01*
X1142596Y484366D01*
X1141555D01*
G01X1142596D02*
X1143221Y483158D01*
G01X1145488D02*
X1145780Y483200D01*
X1146113Y483325D01*
X1146321Y483533D01*
X1146405Y483825D01*
X1146321Y484116D01*
X1146071Y484366D01*
X1145696Y484491D01*
X1145280D01*
X1145030Y484575D01*
X1144821Y484783D01*
X1144738Y485075D01*
X1144863Y485366D01*
X1145155Y485575D01*
X1145488Y485658D01*
X1145821Y485575D01*
X1146113Y485366D01*
X1146238Y485075D01*
X1146155Y484783D01*
X1145946Y484575D01*
X1145696Y484491D01*
X1145280D01*
X1144905Y484366D01*
X1144655Y484116D01*
X1144571Y483825D01*
X1144655Y483533D01*
X1144863Y483325D01*
X1145196Y483200D01*
X1145488Y483158D01*
G01X1147546D02*
X1148588Y485658D01*
X1149630Y483158D01*
G01X1149255Y484033D02*
X1147921D01*
G01X1150771Y483533D02*
X1151021Y483325D01*
X1151313Y483200D01*
X1151688Y483158D01*
X1152063Y483241D01*
X1152355Y483408D01*
X1152563Y483700D01*
X1152605Y484033D01*
X1152521Y484366D01*
X1152313Y484575D01*
X1152021Y484741D01*
X1151730Y484783D01*
X1151438Y484741D01*
X1151063Y484575D01*
X1151188Y485658D01*
X1152313D01*
G01X1141582Y487594D02*
Y490094D01*
X1142623D01*
X1142957Y489969D01*
X1143165Y489802D01*
X1143248Y489469D01*
X1143165Y489136D01*
X1142915Y488927D01*
X1142623Y488802D01*
X1141582D01*
G01X1142623D02*
X1143248Y487594D01*
G01X1145515D02*
X1145807Y487636D01*
X1146140Y487761D01*
X1146348Y487969D01*
X1146432Y488261D01*
X1146348Y488552D01*
X1146098Y488802D01*
X1145723Y488927D01*
X1145307D01*
X1145057Y489011D01*
X1144848Y489219D01*
X1144765Y489511D01*
X1144890Y489802D01*
X1145182Y490011D01*
X1145515Y490094D01*
X1145848Y490011D01*
X1146140Y489802D01*
X1146265Y489511D01*
X1146182Y489219D01*
X1145973Y489011D01*
X1145723Y488927D01*
X1145307D01*
X1144932Y488802D01*
X1144682Y488552D01*
X1144598Y488261D01*
X1144682Y487969D01*
X1144890Y487761D01*
X1145223Y487636D01*
X1145515Y487594D01*
G01X1147365Y490094D02*
X1147948Y487594D01*
X1148615Y490094D01*
X1149282Y487594D01*
X1149865Y490094D01*
G01X1151715Y487594D02*
X1152007Y487636D01*
X1152340Y487761D01*
X1152548Y487969D01*
X1152632Y488261D01*
X1152548Y488552D01*
X1152298Y488802D01*
X1151923Y488927D01*
X1151507D01*
X1151257Y489011D01*
X1151048Y489219D01*
X1150965Y489511D01*
X1151090Y489802D01*
X1151382Y490011D01*
X1151715Y490094D01*
X1152048Y490011D01*
X1152340Y489802D01*
X1152465Y489511D01*
X1152382Y489219D01*
X1152173Y489011D01*
X1151923Y488927D01*
X1151507D01*
X1151132Y488802D01*
X1150882Y488552D01*
X1150798Y488261D01*
X1150882Y487969D01*
X1151090Y487761D01*
X1151423Y487636D01*
X1151715Y487594D01*
G01X1099910Y472629D02*
X1099785Y472379D01*
X1099702Y472087D01*
Y471754D01*
X1099827Y471379D01*
X1100035Y471087D01*
X1100285Y470879D01*
X1100702Y470712D01*
X1101077Y470670D01*
X1101452Y470754D01*
X1101702Y470879D01*
X1101952Y471129D01*
X1102119Y471420D01*
X1102202Y471712D01*
Y472004D01*
X1102119Y472295D01*
X1101994Y472545D01*
X1101827Y472754D01*
G01X1102202Y474812D02*
X1102160Y475104D01*
X1102035Y475437D01*
X1101827Y475645D01*
X1101535Y475729D01*
X1101244Y475645D01*
X1100994Y475395D01*
X1100869Y475020D01*
Y474604D01*
X1100785Y474354D01*
X1100577Y474145D01*
X1100285Y474062D01*
X1099994Y474187D01*
X1099785Y474479D01*
X1099702Y474812D01*
X1099785Y475145D01*
X1099994Y475437D01*
X1100285Y475562D01*
X1100577Y475479D01*
X1100785Y475270D01*
X1100869Y475020D01*
Y474604D01*
X1100994Y474229D01*
X1101244Y473979D01*
X1101535Y473895D01*
X1101827Y473979D01*
X1102035Y474187D01*
X1102160Y474520D01*
X1102202Y474812D01*
G01Y476870D02*
X1099702Y477912D01*
X1102202Y478954D01*
G01X1101327Y478579D02*
Y477245D01*
G01X1102202Y480929D02*
X1101660Y481012D01*
X1101202Y481137D01*
X1100785Y481304D01*
X1100327Y481512D01*
X1099702Y481845D01*
Y480179D01*
G01X1143621Y506416D02*
X1143496Y506166D01*
X1143413Y505874D01*
Y505541D01*
X1143538Y505166D01*
X1143746Y504874D01*
X1143996Y504666D01*
X1144413Y504499D01*
X1144788Y504457D01*
X1145163Y504541D01*
X1145413Y504666D01*
X1145663Y504916D01*
X1145830Y505207D01*
X1145913Y505499D01*
Y505791D01*
X1145830Y506082D01*
X1145705Y506332D01*
X1145538Y506541D01*
G01X1145913Y508599D02*
X1145871Y508891D01*
X1145746Y509224D01*
X1145538Y509432D01*
X1145246Y509516D01*
X1144955Y509432D01*
X1144705Y509182D01*
X1144580Y508807D01*
Y508391D01*
X1144496Y508141D01*
X1144288Y507932D01*
X1143996Y507849D01*
X1143705Y507974D01*
X1143496Y508266D01*
X1143413Y508599D01*
X1143496Y508932D01*
X1143705Y509224D01*
X1143996Y509349D01*
X1144288Y509266D01*
X1144496Y509057D01*
X1144580Y508807D01*
Y508391D01*
X1144705Y508016D01*
X1144955Y507766D01*
X1145246Y507682D01*
X1145538Y507766D01*
X1145746Y507974D01*
X1145871Y508307D01*
X1145913Y508599D01*
G01Y510657D02*
X1143413Y511699D01*
X1145913Y512741D01*
G01X1145038Y512366D02*
Y511032D01*
G01X1143830Y514007D02*
X1143580Y514257D01*
X1143455Y514549D01*
X1143413Y514882D01*
X1143496Y515299D01*
X1143705Y515591D01*
X1143955Y515674D01*
X1144205Y515632D01*
X1144413Y515466D01*
X1144830Y514632D01*
X1145121Y514257D01*
X1145538Y514007D01*
X1145913Y513924D01*
Y515674D01*
G01X1105410Y472129D02*
X1105285Y471879D01*
X1105202Y471587D01*
Y471254D01*
X1105327Y470879D01*
X1105535Y470587D01*
X1105785Y470379D01*
X1106202Y470212D01*
X1106577Y470170D01*
X1106952Y470254D01*
X1107202Y470379D01*
X1107452Y470629D01*
X1107619Y470920D01*
X1107702Y471212D01*
Y471504D01*
X1107619Y471795D01*
X1107494Y472045D01*
X1107327Y472254D01*
G01X1107702Y474312D02*
X1107660Y474604D01*
X1107535Y474937D01*
X1107327Y475145D01*
X1107035Y475229D01*
X1106744Y475145D01*
X1106494Y474895D01*
X1106369Y474520D01*
Y474104D01*
X1106285Y473854D01*
X1106077Y473645D01*
X1105785Y473562D01*
X1105494Y473687D01*
X1105285Y473979D01*
X1105202Y474312D01*
X1105285Y474645D01*
X1105494Y474937D01*
X1105785Y475062D01*
X1106077Y474979D01*
X1106285Y474770D01*
X1106369Y474520D01*
Y474104D01*
X1106494Y473729D01*
X1106744Y473479D01*
X1107035Y473395D01*
X1107327Y473479D01*
X1107535Y473687D01*
X1107660Y474020D01*
X1107702Y474312D01*
G01Y476370D02*
X1105202Y477412D01*
X1107702Y478454D01*
G01X1106827Y478079D02*
Y476745D01*
G01X1107702Y480512D02*
X1107660Y480804D01*
X1107535Y481137D01*
X1107327Y481345D01*
X1107035Y481429D01*
X1106744Y481345D01*
X1106494Y481095D01*
X1106369Y480720D01*
Y480304D01*
X1106285Y480054D01*
X1106077Y479845D01*
X1105785Y479762D01*
X1105494Y479887D01*
X1105285Y480179D01*
X1105202Y480512D01*
X1105285Y480845D01*
X1105494Y481137D01*
X1105785Y481262D01*
X1106077Y481179D01*
X1106285Y480970D01*
X1106369Y480720D01*
Y480304D01*
X1106494Y479929D01*
X1106744Y479679D01*
X1107035Y479595D01*
X1107327Y479679D01*
X1107535Y479887D01*
X1107660Y480220D01*
X1107702Y480512D01*
G01X1103235Y485721D02*
X1102985Y485846D01*
X1102693Y485929D01*
X1102360D01*
X1101985Y485804D01*
X1101693Y485596D01*
X1101485Y485346D01*
X1101318Y484929D01*
X1101276Y484554D01*
X1101360Y484179D01*
X1101485Y483929D01*
X1101735Y483679D01*
X1102026Y483512D01*
X1102318Y483429D01*
X1102610D01*
X1102901Y483512D01*
X1103151Y483637D01*
X1103360Y483804D01*
G01X1105418Y483429D02*
X1105710Y483471D01*
X1106043Y483596D01*
X1106251Y483804D01*
X1106335Y484096D01*
X1106251Y484387D01*
X1106001Y484637D01*
X1105626Y484762D01*
X1105210D01*
X1104960Y484846D01*
X1104751Y485054D01*
X1104668Y485346D01*
X1104793Y485637D01*
X1105085Y485846D01*
X1105418Y485929D01*
X1105751Y485846D01*
X1106043Y485637D01*
X1106168Y485346D01*
X1106085Y485054D01*
X1105876Y484846D01*
X1105626Y484762D01*
X1105210D01*
X1104835Y484637D01*
X1104585Y484387D01*
X1104501Y484096D01*
X1104585Y483804D01*
X1104793Y483596D01*
X1105126Y483471D01*
X1105418Y483429D01*
G01X1107476D02*
X1108518Y485929D01*
X1109560Y483429D01*
G01X1109185Y484304D02*
X1107851D01*
G01X1110701Y483929D02*
X1110951Y483637D01*
X1111285Y483471D01*
X1111660Y483429D01*
X1111993Y483471D01*
X1112326Y483679D01*
X1112535Y483929D01*
X1112576Y484179D01*
X1112493Y484471D01*
X1112201Y484679D01*
X1111910Y484762D01*
X1111535D01*
G01X1111910D02*
X1112160Y484887D01*
X1112368Y485096D01*
X1112451Y485346D01*
X1112368Y485596D01*
X1112160Y485804D01*
X1111785Y485929D01*
X1111410Y485887D01*
X1111035Y485721D01*
G01X1097785Y498521D02*
X1097535Y498646D01*
X1097243Y498729D01*
X1096910D01*
X1096535Y498604D01*
X1096243Y498396D01*
X1096035Y498146D01*
X1095868Y497729D01*
X1095826Y497354D01*
X1095910Y496979D01*
X1096035Y496729D01*
X1096285Y496479D01*
X1096576Y496312D01*
X1096868Y496229D01*
X1097160D01*
X1097451Y496312D01*
X1097701Y496437D01*
X1097910Y496604D01*
G01X1099885Y496229D02*
X1099968Y496771D01*
X1100093Y497229D01*
X1100260Y497646D01*
X1100468Y498104D01*
X1100801Y498729D01*
X1099135D01*
G01X1102026Y496229D02*
X1103068Y498729D01*
X1104110Y496229D01*
G01X1103735Y497104D02*
X1102401D01*
G01X1106668Y496229D02*
Y498729D01*
X1105126Y496937D01*
X1107210D01*
G01X1109768Y496229D02*
Y498729D01*
X1108226Y496937D01*
X1110310D01*
G01X1125501Y485729D02*
X1123835D01*
Y488229D01*
X1125501D01*
G01X1124835Y487021D02*
X1123835D01*
G01X1126851Y488229D02*
Y486437D01*
X1127018Y486062D01*
X1127351Y485812D01*
X1127768Y485729D01*
X1128185Y485812D01*
X1128518Y486062D01*
X1128685Y486437D01*
Y488229D01*
G01X1130868Y485729D02*
X1131160Y485771D01*
X1131493Y485896D01*
X1131701Y486104D01*
X1131785Y486396D01*
X1131701Y486687D01*
X1131451Y486937D01*
X1131076Y487062D01*
X1130660D01*
X1130410Y487146D01*
X1130201Y487354D01*
X1130118Y487646D01*
X1130243Y487937D01*
X1130535Y488146D01*
X1130868Y488229D01*
X1131201Y488146D01*
X1131493Y487937D01*
X1131618Y487646D01*
X1131535Y487354D01*
X1131326Y487146D01*
X1131076Y487062D01*
X1130660D01*
X1130285Y486937D01*
X1130035Y486687D01*
X1129951Y486396D01*
X1130035Y486104D01*
X1130243Y485896D01*
X1130576Y485771D01*
X1130868Y485729D01*
G01X1132926D02*
X1133968Y488229D01*
X1135010Y485729D01*
G01X1134635Y486604D02*
X1133301D01*
G01X1137068Y485729D02*
Y488229D01*
X1136568Y487729D01*
G01Y485729D02*
X1137568D01*
G01X1156604Y482440D02*
Y480774D01*
X1154104D01*
Y482440D01*
G01X1155312Y481774D02*
Y480774D01*
G01X1154104Y483790D02*
X1155896D01*
X1156271Y483957D01*
X1156521Y484290D01*
X1156604Y484707D01*
X1156521Y485124D01*
X1156271Y485457D01*
X1155896Y485624D01*
X1154104D01*
G01X1156604Y487807D02*
X1156562Y488099D01*
X1156437Y488432D01*
X1156229Y488640D01*
X1155937Y488724D01*
X1155646Y488640D01*
X1155396Y488390D01*
X1155271Y488015D01*
Y487599D01*
X1155187Y487349D01*
X1154979Y487140D01*
X1154687Y487057D01*
X1154396Y487182D01*
X1154187Y487474D01*
X1154104Y487807D01*
X1154187Y488140D01*
X1154396Y488432D01*
X1154687Y488557D01*
X1154979Y488474D01*
X1155187Y488265D01*
X1155271Y488015D01*
Y487599D01*
X1155396Y487224D01*
X1155646Y486974D01*
X1155937Y486890D01*
X1156229Y486974D01*
X1156437Y487182D01*
X1156562Y487515D01*
X1156604Y487807D01*
G01Y489865D02*
X1154104Y490907D01*
X1156604Y491949D01*
G01X1155729Y491574D02*
Y490240D01*
G01X1154521Y493215D02*
X1154271Y493465D01*
X1154146Y493757D01*
X1154104Y494090D01*
X1154187Y494507D01*
X1154396Y494799D01*
X1154646Y494882D01*
X1154896Y494840D01*
X1155104Y494674D01*
X1155521Y493840D01*
X1155812Y493465D01*
X1156229Y493215D01*
X1156604Y493132D01*
Y494882D01*
G01X1137217Y551459D02*
X1136967Y551584D01*
X1136675Y551667D01*
X1136342D01*
X1135967Y551542D01*
X1135675Y551334D01*
X1135467Y551084D01*
X1135300Y550667D01*
X1135258Y550292D01*
X1135342Y549917D01*
X1135467Y549667D01*
X1135717Y549417D01*
X1136008Y549250D01*
X1136300Y549167D01*
X1136592D01*
X1136883Y549250D01*
X1137133Y549375D01*
X1137342Y549542D01*
G01X1138483D02*
X1138733Y549334D01*
X1139025Y549209D01*
X1139400Y549167D01*
X1139775Y549250D01*
X1140067Y549417D01*
X1140275Y549709D01*
X1140317Y550042D01*
X1140233Y550375D01*
X1140025Y550584D01*
X1139733Y550750D01*
X1139442Y550792D01*
X1139150Y550750D01*
X1138775Y550584D01*
X1138900Y551667D01*
X1140025D01*
G01X1141458Y549167D02*
X1142500Y551667D01*
X1143542Y549167D01*
G01X1143167Y550042D02*
X1141833D01*
G01X1145600Y549167D02*
Y551667D01*
X1145100Y551167D01*
G01Y549167D02*
X1146100D01*
G01X1147992Y549459D02*
X1148283Y549250D01*
X1148617Y549167D01*
X1148950Y549250D01*
X1149242Y549500D01*
X1149450Y549875D01*
X1149533Y550250D01*
Y550709D01*
X1149450Y551084D01*
X1149242Y551417D01*
X1148992Y551584D01*
X1148700Y551667D01*
X1148367Y551584D01*
X1148117Y551417D01*
X1147950Y551167D01*
X1147867Y550834D01*
X1147950Y550542D01*
X1148158Y550250D01*
X1148408Y550084D01*
X1148700Y550042D01*
X1149033Y550125D01*
X1149283Y550334D01*
X1149533Y550709D01*
G01X1119217Y551459D02*
X1118967Y551584D01*
X1118675Y551667D01*
X1118342D01*
X1117967Y551542D01*
X1117675Y551334D01*
X1117467Y551084D01*
X1117300Y550667D01*
X1117258Y550292D01*
X1117342Y549917D01*
X1117467Y549667D01*
X1117717Y549417D01*
X1118008Y549250D01*
X1118300Y549167D01*
X1118592D01*
X1118883Y549250D01*
X1119133Y549375D01*
X1119342Y549542D01*
G01X1120483D02*
X1120733Y549334D01*
X1121025Y549209D01*
X1121400Y549167D01*
X1121775Y549250D01*
X1122067Y549417D01*
X1122275Y549709D01*
X1122317Y550042D01*
X1122233Y550375D01*
X1122025Y550584D01*
X1121733Y550750D01*
X1121442Y550792D01*
X1121150Y550750D01*
X1120775Y550584D01*
X1120900Y551667D01*
X1122025D01*
G01X1123458Y549167D02*
X1124500Y551667D01*
X1125542Y549167D01*
G01X1125167Y550042D02*
X1123833D01*
G01X1127600Y549167D02*
Y551667D01*
X1127100Y551167D01*
G01Y549167D02*
X1128100D01*
G01X1130700D02*
X1130992Y549209D01*
X1131325Y549334D01*
X1131533Y549542D01*
X1131617Y549834D01*
X1131533Y550125D01*
X1131283Y550375D01*
X1130908Y550500D01*
X1130492D01*
X1130242Y550584D01*
X1130033Y550792D01*
X1129950Y551084D01*
X1130075Y551375D01*
X1130367Y551584D01*
X1130700Y551667D01*
X1131033Y551584D01*
X1131325Y551375D01*
X1131450Y551084D01*
X1131367Y550792D01*
X1131158Y550584D01*
X1130908Y550500D01*
X1130492D01*
X1130117Y550375D01*
X1129867Y550125D01*
X1129783Y549834D01*
X1129867Y549542D01*
X1130075Y549334D01*
X1130408Y549209D01*
X1130700Y549167D01*
G01X1103485Y551953D02*
X1103235Y552078D01*
X1102943Y552161D01*
X1102610D01*
X1102235Y552036D01*
X1101943Y551828D01*
X1101735Y551578D01*
X1101568Y551161D01*
X1101526Y550786D01*
X1101610Y550411D01*
X1101735Y550161D01*
X1101985Y549911D01*
X1102276Y549744D01*
X1102568Y549661D01*
X1102860D01*
X1103151Y549744D01*
X1103401Y549869D01*
X1103610Y550036D01*
G01X1104751D02*
X1105001Y549828D01*
X1105293Y549703D01*
X1105668Y549661D01*
X1106043Y549744D01*
X1106335Y549911D01*
X1106543Y550203D01*
X1106585Y550536D01*
X1106501Y550869D01*
X1106293Y551078D01*
X1106001Y551244D01*
X1105710Y551286D01*
X1105418Y551244D01*
X1105043Y551078D01*
X1105168Y552161D01*
X1106293D01*
G01X1107726Y549661D02*
X1108768Y552161D01*
X1109810Y549661D01*
G01X1109435Y550536D02*
X1108101D01*
G01X1111868Y549661D02*
Y552161D01*
X1111368Y551661D01*
G01Y549661D02*
X1112368D01*
G01X1114885D02*
X1114968Y550203D01*
X1115093Y550661D01*
X1115260Y551078D01*
X1115468Y551536D01*
X1115801Y552161D01*
X1114135D01*
G01X1097717Y555458D02*
X1097467Y555583D01*
X1097175Y555666D01*
X1096842D01*
X1096467Y555541D01*
X1096175Y555333D01*
X1095967Y555083D01*
X1095800Y554666D01*
X1095758Y554291D01*
X1095842Y553916D01*
X1095967Y553666D01*
X1096217Y553416D01*
X1096508Y553249D01*
X1096800Y553166D01*
X1097092D01*
X1097383Y553249D01*
X1097633Y553374D01*
X1097842Y553541D01*
G01X1098983D02*
X1099233Y553333D01*
X1099525Y553208D01*
X1099900Y553166D01*
X1100275Y553249D01*
X1100567Y553416D01*
X1100775Y553708D01*
X1100817Y554041D01*
X1100733Y554374D01*
X1100525Y554583D01*
X1100233Y554749D01*
X1099942Y554791D01*
X1099650Y554749D01*
X1099275Y554583D01*
X1099400Y555666D01*
X1100525D01*
G01X1101958Y553166D02*
X1103000Y555666D01*
X1104042Y553166D01*
G01X1103667Y554041D02*
X1102333D01*
G01X1106100Y553166D02*
Y555666D01*
X1105600Y555166D01*
G01Y553166D02*
X1106600D01*
G01X1108408Y554208D02*
X1108700Y554499D01*
X1108950Y554666D01*
X1109283Y554749D01*
X1109575Y554666D01*
X1109783Y554499D01*
X1109950Y554249D01*
X1109992Y553958D01*
X1109950Y553708D01*
X1109783Y553458D01*
X1109533Y553249D01*
X1109242Y553166D01*
X1108908Y553249D01*
X1108617Y553499D01*
X1108450Y553874D01*
X1108408Y554291D01*
X1108492Y554833D01*
X1108617Y555124D01*
X1108825Y555416D01*
X1109117Y555624D01*
X1109408Y555666D01*
X1109700Y555583D01*
X1109908Y555374D01*
G01X1130860Y589340D02*
X1130610Y589465D01*
X1130318Y589548D01*
X1129985D01*
X1129610Y589423D01*
X1129318Y589215D01*
X1129110Y588965D01*
X1128943Y588548D01*
X1128901Y588173D01*
X1128985Y587798D01*
X1129110Y587548D01*
X1129360Y587298D01*
X1129651Y587131D01*
X1129943Y587048D01*
X1130235D01*
X1130526Y587131D01*
X1130776Y587256D01*
X1130985Y587423D01*
G01X1132126D02*
X1132376Y587215D01*
X1132668Y587090D01*
X1133043Y587048D01*
X1133418Y587131D01*
X1133710Y587298D01*
X1133918Y587590D01*
X1133960Y587923D01*
X1133876Y588256D01*
X1133668Y588465D01*
X1133376Y588631D01*
X1133085Y588673D01*
X1132793Y588631D01*
X1132418Y588465D01*
X1132543Y589548D01*
X1133668D01*
G01X1135101Y587048D02*
X1136143Y589548D01*
X1137185Y587048D01*
G01X1136810Y587923D02*
X1135476D01*
G01X1138535Y587340D02*
X1138826Y587131D01*
X1139160Y587048D01*
X1139493Y587131D01*
X1139785Y587381D01*
X1139993Y587756D01*
X1140076Y588131D01*
Y588590D01*
X1139993Y588965D01*
X1139785Y589298D01*
X1139535Y589465D01*
X1139243Y589548D01*
X1138910Y589465D01*
X1138660Y589298D01*
X1138493Y589048D01*
X1138410Y588715D01*
X1138493Y588423D01*
X1138701Y588131D01*
X1138951Y587965D01*
X1139243Y587923D01*
X1139576Y588006D01*
X1139826Y588215D01*
X1140076Y588590D01*
G01X1117415Y589908D02*
X1117165Y590033D01*
X1116873Y590116D01*
X1116540D01*
X1116165Y589991D01*
X1115873Y589783D01*
X1115665Y589533D01*
X1115498Y589116D01*
X1115456Y588741D01*
X1115540Y588366D01*
X1115665Y588116D01*
X1115915Y587866D01*
X1116206Y587699D01*
X1116498Y587616D01*
X1116790D01*
X1117081Y587699D01*
X1117331Y587824D01*
X1117540Y587991D01*
G01X1118681D02*
X1118931Y587783D01*
X1119223Y587658D01*
X1119598Y587616D01*
X1119973Y587699D01*
X1120265Y587866D01*
X1120473Y588158D01*
X1120515Y588491D01*
X1120431Y588824D01*
X1120223Y589033D01*
X1119931Y589199D01*
X1119640Y589241D01*
X1119348Y589199D01*
X1118973Y589033D01*
X1119098Y590116D01*
X1120223D01*
G01X1121656Y587616D02*
X1122698Y590116D01*
X1123740Y587616D01*
G01X1123365Y588491D02*
X1122031D01*
G01X1125798Y587616D02*
X1126090Y587658D01*
X1126423Y587783D01*
X1126631Y587991D01*
X1126715Y588283D01*
X1126631Y588574D01*
X1126381Y588824D01*
X1126006Y588949D01*
X1125590D01*
X1125340Y589033D01*
X1125131Y589241D01*
X1125048Y589533D01*
X1125173Y589824D01*
X1125465Y590033D01*
X1125798Y590116D01*
X1126131Y590033D01*
X1126423Y589824D01*
X1126548Y589533D01*
X1126465Y589241D01*
X1126256Y589033D01*
X1126006Y588949D01*
X1125590D01*
X1125215Y588824D01*
X1124965Y588574D01*
X1124881Y588283D01*
X1124965Y587991D01*
X1125173Y587783D01*
X1125506Y587658D01*
X1125798Y587616D01*
G01X1103421Y591025D02*
X1103171Y591150D01*
X1102879Y591233D01*
X1102546D01*
X1102171Y591108D01*
X1101879Y590900D01*
X1101671Y590650D01*
X1101504Y590233D01*
X1101462Y589858D01*
X1101546Y589483D01*
X1101671Y589233D01*
X1101921Y588983D01*
X1102212Y588816D01*
X1102504Y588733D01*
X1102796D01*
X1103087Y588816D01*
X1103337Y588941D01*
X1103546Y589108D01*
G01X1104687D02*
X1104937Y588900D01*
X1105229Y588775D01*
X1105604Y588733D01*
X1105979Y588816D01*
X1106271Y588983D01*
X1106479Y589275D01*
X1106521Y589608D01*
X1106437Y589941D01*
X1106229Y590150D01*
X1105937Y590316D01*
X1105646Y590358D01*
X1105354Y590316D01*
X1104979Y590150D01*
X1105104Y591233D01*
X1106229D01*
G01X1107662Y588733D02*
X1108704Y591233D01*
X1109746Y588733D01*
G01X1109371Y589608D02*
X1108037D01*
G01X1111721Y588733D02*
X1111804Y589275D01*
X1111929Y589733D01*
X1112096Y590150D01*
X1112304Y590608D01*
X1112637Y591233D01*
X1110971D01*
G01X1157927Y123994D02*
X1161260Y130994D01*
X1164593Y123994D01*
G01X1163393Y126444D02*
X1159127D01*
G01X1170927Y127727D02*
X1171460Y128077D01*
X1171860Y128661D01*
X1172127Y129477D01*
X1171860Y130177D01*
X1171327Y130644D01*
X1170393Y130994D01*
X1166793D01*
Y123994D01*
X1171193D01*
X1172127Y124461D01*
X1172660Y125161D01*
X1172927Y125977D01*
X1172660Y126794D01*
X1171860Y127494D01*
X1170927Y127727D01*
X1166793D01*
G01X1174980Y122797D02*
X1188299D01*
Y128098D01*
X1213486D01*
Y142610D01*
X1236556D01*
Y139500D01*
X1247999D01*
X1248000Y139501D01*
Y148684D01*
X1263429D01*
X1263430Y148685D01*
Y163376D01*
X1273099D01*
Y176999D01*
X1273100Y177000D01*
X1290500D01*
Y184500D01*
G01X1210103Y113002D02*
X1207603D01*
Y114043D01*
X1207728Y114377D01*
X1207895Y114585D01*
X1208228Y114668D01*
X1208561Y114585D01*
X1208770Y114335D01*
X1208895Y114043D01*
Y113002D01*
G01Y114043D02*
X1210103Y114668D01*
G01Y116935D02*
X1207603D01*
X1208103Y116435D01*
G01X1210103D02*
Y117435D01*
G01X1207603Y118785D02*
X1210103Y119368D01*
X1207603Y120035D01*
X1210103Y120702D01*
X1207603Y121285D01*
G01X1209603Y122218D02*
X1209895Y122468D01*
X1210061Y122802D01*
X1210103Y123177D01*
X1210061Y123510D01*
X1209853Y123843D01*
X1209603Y124052D01*
X1209353Y124093D01*
X1209061Y124010D01*
X1208853Y123718D01*
X1208770Y123427D01*
Y123052D01*
G01Y123427D02*
X1208645Y123677D01*
X1208436Y123885D01*
X1208186Y123968D01*
X1207936Y123885D01*
X1207728Y123677D01*
X1207603Y123302D01*
X1207645Y122927D01*
X1207811Y122552D01*
G01X1210103Y126235D02*
X1207603D01*
X1208103Y125735D01*
G01X1210103D02*
Y126735D01*
G01X1205907Y109896D02*
X1203407D01*
Y110937D01*
X1203532Y111271D01*
X1203699Y111479D01*
X1204032Y111562D01*
X1204365Y111479D01*
X1204574Y111229D01*
X1204699Y110937D01*
Y109896D01*
G01Y110937D02*
X1205907Y111562D01*
G01Y113829D02*
X1203407D01*
X1203907Y113329D01*
G01X1205907D02*
Y114329D01*
G01X1203407Y115679D02*
X1205907Y116262D01*
X1203407Y116929D01*
X1205907Y117596D01*
X1203407Y118179D01*
G01X1205407Y119112D02*
X1205699Y119362D01*
X1205865Y119696D01*
X1205907Y120071D01*
X1205865Y120404D01*
X1205657Y120737D01*
X1205407Y120946D01*
X1205157Y120987D01*
X1204865Y120904D01*
X1204657Y120612D01*
X1204574Y120321D01*
Y119946D01*
G01Y120321D02*
X1204449Y120571D01*
X1204240Y120779D01*
X1203990Y120862D01*
X1203740Y120779D01*
X1203532Y120571D01*
X1203407Y120196D01*
X1203449Y119821D01*
X1203615Y119446D01*
G01X1203824Y122337D02*
X1203574Y122587D01*
X1203449Y122879D01*
X1203407Y123212D01*
X1203490Y123629D01*
X1203699Y123921D01*
X1203949Y124004D01*
X1204199Y123962D01*
X1204407Y123796D01*
X1204824Y122962D01*
X1205115Y122587D01*
X1205532Y122337D01*
X1205907Y122254D01*
Y124004D01*
G01X1200239Y152833D02*
X1197739D01*
Y153874D01*
X1197864Y154208D01*
X1198031Y154416D01*
X1198364Y154499D01*
X1198697Y154416D01*
X1198906Y154166D01*
X1199031Y153874D01*
Y152833D01*
G01Y153874D02*
X1200239Y154499D01*
G01Y156766D02*
X1200197Y157058D01*
X1200072Y157391D01*
X1199864Y157599D01*
X1199572Y157683D01*
X1199281Y157599D01*
X1199031Y157349D01*
X1198906Y156974D01*
Y156558D01*
X1198822Y156308D01*
X1198614Y156099D01*
X1198322Y156016D01*
X1198031Y156141D01*
X1197822Y156433D01*
X1197739Y156766D01*
X1197822Y157099D01*
X1198031Y157391D01*
X1198322Y157516D01*
X1198614Y157433D01*
X1198822Y157224D01*
X1198906Y156974D01*
Y156558D01*
X1199031Y156183D01*
X1199281Y155933D01*
X1199572Y155849D01*
X1199864Y155933D01*
X1200072Y156141D01*
X1200197Y156474D01*
X1200239Y156766D01*
G01Y160699D02*
Y159033D01*
X1197739D01*
Y160699D01*
G01X1198947Y160033D02*
Y159033D01*
G01X1199739Y162049D02*
X1200031Y162299D01*
X1200197Y162633D01*
X1200239Y163008D01*
X1200197Y163341D01*
X1199989Y163674D01*
X1199739Y163883D01*
X1199489Y163924D01*
X1199197Y163841D01*
X1198989Y163549D01*
X1198906Y163258D01*
Y162883D01*
G01Y163258D02*
X1198781Y163508D01*
X1198572Y163716D01*
X1198322Y163799D01*
X1198072Y163716D01*
X1197864Y163508D01*
X1197739Y163133D01*
X1197781Y162758D01*
X1197947Y162383D01*
G01X1199864Y165149D02*
X1200072Y165399D01*
X1200197Y165691D01*
X1200239Y166066D01*
X1200156Y166441D01*
X1199989Y166733D01*
X1199697Y166941D01*
X1199364Y166983D01*
X1199031Y166899D01*
X1198822Y166691D01*
X1198656Y166399D01*
X1198614Y166108D01*
X1198656Y165816D01*
X1198822Y165441D01*
X1197739Y165566D01*
Y166691D01*
G01X1198744Y129441D02*
Y131941D01*
X1199785D01*
X1200119Y131816D01*
X1200327Y131649D01*
X1200410Y131316D01*
X1200327Y130983D01*
X1200077Y130774D01*
X1199785Y130649D01*
X1198744D01*
G01X1199785D02*
X1200410Y129441D01*
G01X1202677D02*
X1202969Y129483D01*
X1203302Y129608D01*
X1203510Y129816D01*
X1203594Y130108D01*
X1203510Y130399D01*
X1203260Y130649D01*
X1202885Y130774D01*
X1202469D01*
X1202219Y130858D01*
X1202010Y131066D01*
X1201927Y131358D01*
X1202052Y131649D01*
X1202344Y131858D01*
X1202677Y131941D01*
X1203010Y131858D01*
X1203302Y131649D01*
X1203427Y131358D01*
X1203344Y131066D01*
X1203135Y130858D01*
X1202885Y130774D01*
X1202469D01*
X1202094Y130649D01*
X1201844Y130399D01*
X1201760Y130108D01*
X1201844Y129816D01*
X1202052Y129608D01*
X1202385Y129483D01*
X1202677Y129441D01*
G01X1204985D02*
Y131941D01*
X1206569D01*
G01X1205985Y130733D02*
X1204985D01*
G01X1208877Y129441D02*
Y131941D01*
X1208377Y131441D01*
G01Y129441D02*
X1209377D01*
G01X1211977D02*
Y131941D01*
X1211477Y131441D01*
G01Y129441D02*
X1212477D01*
G01X1180443Y126546D02*
X1177943D01*
Y127587D01*
X1178068Y127921D01*
X1178235Y128129D01*
X1178568Y128212D01*
X1178901Y128129D01*
X1179110Y127879D01*
X1179235Y127587D01*
Y126546D01*
G01Y127587D02*
X1180443Y128212D01*
G01Y130479D02*
X1180401Y130771D01*
X1180276Y131104D01*
X1180068Y131312D01*
X1179776Y131396D01*
X1179485Y131312D01*
X1179235Y131062D01*
X1179110Y130687D01*
Y130271D01*
X1179026Y130021D01*
X1178818Y129812D01*
X1178526Y129729D01*
X1178235Y129854D01*
X1178026Y130146D01*
X1177943Y130479D01*
X1178026Y130812D01*
X1178235Y131104D01*
X1178526Y131229D01*
X1178818Y131146D01*
X1179026Y130937D01*
X1179110Y130687D01*
Y130271D01*
X1179235Y129896D01*
X1179485Y129646D01*
X1179776Y129562D01*
X1180068Y129646D01*
X1180276Y129854D01*
X1180401Y130187D01*
X1180443Y130479D01*
G01Y132787D02*
X1177943D01*
Y134371D01*
G01X1179151Y133787D02*
Y132787D01*
G01X1180443Y136679D02*
X1177943D01*
X1178443Y136179D01*
G01X1180443D02*
Y137179D01*
G01X1177943Y139779D02*
X1178026Y139446D01*
X1178235Y139196D01*
X1178485Y139029D01*
X1178818Y138904D01*
X1179193Y138862D01*
X1179568Y138904D01*
X1179901Y139029D01*
X1180151Y139196D01*
X1180360Y139446D01*
X1180443Y139779D01*
X1180360Y140112D01*
X1180151Y140362D01*
X1179901Y140529D01*
X1179568Y140654D01*
X1179193Y140696D01*
X1178818Y140654D01*
X1178485Y140529D01*
X1178235Y140362D01*
X1178026Y140112D01*
X1177943Y139779D01*
G01X1173606Y140230D02*
X1171106D01*
Y141271D01*
X1171231Y141605D01*
X1171398Y141813D01*
X1171731Y141896D01*
X1172064Y141813D01*
X1172273Y141563D01*
X1172398Y141271D01*
Y140230D01*
G01Y141271D02*
X1173606Y141896D01*
G01Y144163D02*
X1173564Y144455D01*
X1173439Y144788D01*
X1173231Y144996D01*
X1172939Y145080D01*
X1172648Y144996D01*
X1172398Y144746D01*
X1172273Y144371D01*
Y143955D01*
X1172189Y143705D01*
X1171981Y143496D01*
X1171689Y143413D01*
X1171398Y143538D01*
X1171189Y143830D01*
X1171106Y144163D01*
X1171189Y144496D01*
X1171398Y144788D01*
X1171689Y144913D01*
X1171981Y144830D01*
X1172189Y144621D01*
X1172273Y144371D01*
Y143955D01*
X1172398Y143580D01*
X1172648Y143330D01*
X1172939Y143246D01*
X1173231Y143330D01*
X1173439Y143538D01*
X1173564Y143871D01*
X1173606Y144163D01*
G01Y146471D02*
X1171106D01*
Y148055D01*
G01X1172314Y147471D02*
Y146471D01*
G01X1173606Y150363D02*
X1171106D01*
X1171606Y149863D01*
G01X1173606D02*
Y150863D01*
G01X1186291Y129184D02*
Y131684D01*
X1187332D01*
X1187666Y131559D01*
X1187874Y131392D01*
X1187957Y131059D01*
X1187874Y130726D01*
X1187624Y130517D01*
X1187332Y130392D01*
X1186291D01*
G01X1187332D02*
X1187957Y129184D01*
G01X1190224D02*
X1190516Y129226D01*
X1190849Y129351D01*
X1191057Y129559D01*
X1191141Y129851D01*
X1191057Y130142D01*
X1190807Y130392D01*
X1190432Y130517D01*
X1190016D01*
X1189766Y130601D01*
X1189557Y130809D01*
X1189474Y131101D01*
X1189599Y131392D01*
X1189891Y131601D01*
X1190224Y131684D01*
X1190557Y131601D01*
X1190849Y131392D01*
X1190974Y131101D01*
X1190891Y130809D01*
X1190682Y130601D01*
X1190432Y130517D01*
X1190016D01*
X1189641Y130392D01*
X1189391Y130142D01*
X1189307Y129851D01*
X1189391Y129559D01*
X1189599Y129351D01*
X1189932Y129226D01*
X1190224Y129184D01*
G01X1192532D02*
Y131684D01*
X1194116D01*
G01X1193532Y130476D02*
X1192532D01*
G01X1195716Y129476D02*
X1196007Y129267D01*
X1196341Y129184D01*
X1196674Y129267D01*
X1196966Y129517D01*
X1197174Y129892D01*
X1197257Y130267D01*
Y130726D01*
X1197174Y131101D01*
X1196966Y131434D01*
X1196716Y131601D01*
X1196424Y131684D01*
X1196091Y131601D01*
X1195841Y131434D01*
X1195674Y131184D01*
X1195591Y130851D01*
X1195674Y130559D01*
X1195882Y130267D01*
X1196132Y130101D01*
X1196424Y130059D01*
X1196757Y130142D01*
X1197007Y130351D01*
X1197257Y130726D01*
G01X1177088Y152119D02*
Y154619D01*
X1178129D01*
X1178463Y154494D01*
X1178671Y154327D01*
X1178754Y153994D01*
X1178671Y153661D01*
X1178421Y153452D01*
X1178129Y153327D01*
X1177088D01*
G01X1178129D02*
X1178754Y152119D01*
G01X1181021D02*
X1181313Y152161D01*
X1181646Y152286D01*
X1181854Y152494D01*
X1181938Y152786D01*
X1181854Y153077D01*
X1181604Y153327D01*
X1181229Y153452D01*
X1180813D01*
X1180563Y153536D01*
X1180354Y153744D01*
X1180271Y154036D01*
X1180396Y154327D01*
X1180688Y154536D01*
X1181021Y154619D01*
X1181354Y154536D01*
X1181646Y154327D01*
X1181771Y154036D01*
X1181688Y153744D01*
X1181479Y153536D01*
X1181229Y153452D01*
X1180813D01*
X1180438Y153327D01*
X1180188Y153077D01*
X1180104Y152786D01*
X1180188Y152494D01*
X1180396Y152286D01*
X1180729Y152161D01*
X1181021Y152119D01*
G01X1184954D02*
X1183288D01*
Y154619D01*
X1184954D01*
G01X1184288Y153411D02*
X1183288D01*
G01X1187721Y152119D02*
Y154619D01*
X1186179Y152827D01*
X1188263D01*
G01X1190321Y154619D02*
X1189988Y154536D01*
X1189738Y154327D01*
X1189571Y154077D01*
X1189446Y153744D01*
X1189404Y153369D01*
X1189446Y152994D01*
X1189571Y152661D01*
X1189738Y152411D01*
X1189988Y152202D01*
X1190321Y152119D01*
X1190654Y152202D01*
X1190904Y152411D01*
X1191071Y152661D01*
X1191196Y152994D01*
X1191238Y153369D01*
X1191196Y153744D01*
X1191071Y154077D01*
X1190904Y154327D01*
X1190654Y154536D01*
X1190321Y154619D01*
G01X1176143Y147583D02*
Y150083D01*
X1177184D01*
X1177518Y149958D01*
X1177726Y149791D01*
X1177809Y149458D01*
X1177726Y149125D01*
X1177476Y148916D01*
X1177184Y148791D01*
X1176143D01*
G01X1177184D02*
X1177809Y147583D01*
G01X1180076D02*
X1180368Y147625D01*
X1180701Y147750D01*
X1180909Y147958D01*
X1180993Y148250D01*
X1180909Y148541D01*
X1180659Y148791D01*
X1180284Y148916D01*
X1179868D01*
X1179618Y149000D01*
X1179409Y149208D01*
X1179326Y149500D01*
X1179451Y149791D01*
X1179743Y150000D01*
X1180076Y150083D01*
X1180409Y150000D01*
X1180701Y149791D01*
X1180826Y149500D01*
X1180743Y149208D01*
X1180534Y149000D01*
X1180284Y148916D01*
X1179868D01*
X1179493Y148791D01*
X1179243Y148541D01*
X1179159Y148250D01*
X1179243Y147958D01*
X1179451Y147750D01*
X1179784Y147625D01*
X1180076Y147583D01*
G01X1182384D02*
Y150083D01*
X1183968D01*
G01X1183384Y148875D02*
X1182384D01*
G01X1185484Y149666D02*
X1185734Y149916D01*
X1186026Y150041D01*
X1186359Y150083D01*
X1186776Y150000D01*
X1187068Y149791D01*
X1187151Y149541D01*
X1187109Y149291D01*
X1186943Y149083D01*
X1186109Y148666D01*
X1185734Y148375D01*
X1185484Y147958D01*
X1185401Y147583D01*
X1187151D01*
G01X1177208Y155959D02*
Y158459D01*
X1178249D01*
X1178583Y158334D01*
X1178791Y158167D01*
X1178874Y157834D01*
X1178791Y157501D01*
X1178541Y157292D01*
X1178249Y157167D01*
X1177208D01*
G01X1178249D02*
X1178874Y155959D01*
G01X1181141D02*
X1181433Y156001D01*
X1181766Y156126D01*
X1181974Y156334D01*
X1182058Y156626D01*
X1181974Y156917D01*
X1181724Y157167D01*
X1181349Y157292D01*
X1180933D01*
X1180683Y157376D01*
X1180474Y157584D01*
X1180391Y157876D01*
X1180516Y158167D01*
X1180808Y158376D01*
X1181141Y158459D01*
X1181474Y158376D01*
X1181766Y158167D01*
X1181891Y157876D01*
X1181808Y157584D01*
X1181599Y157376D01*
X1181349Y157292D01*
X1180933D01*
X1180558Y157167D01*
X1180308Y156917D01*
X1180224Y156626D01*
X1180308Y156334D01*
X1180516Y156126D01*
X1180849Y156001D01*
X1181141Y155959D01*
G01X1185074D02*
X1183408D01*
Y158459D01*
X1185074D01*
G01X1184408Y157251D02*
X1183408D01*
G01X1186424Y156459D02*
X1186674Y156167D01*
X1187008Y156001D01*
X1187383Y155959D01*
X1187716Y156001D01*
X1188049Y156209D01*
X1188258Y156459D01*
X1188299Y156709D01*
X1188216Y157001D01*
X1187924Y157209D01*
X1187633Y157292D01*
X1187258D01*
G01X1187633D02*
X1187883Y157417D01*
X1188091Y157626D01*
X1188174Y157876D01*
X1188091Y158126D01*
X1187883Y158334D01*
X1187508Y158459D01*
X1187133Y158417D01*
X1186758Y158251D01*
G01X1190441Y155959D02*
X1190733Y156001D01*
X1191066Y156126D01*
X1191274Y156334D01*
X1191358Y156626D01*
X1191274Y156917D01*
X1191024Y157167D01*
X1190649Y157292D01*
X1190233D01*
X1189983Y157376D01*
X1189774Y157584D01*
X1189691Y157876D01*
X1189816Y158167D01*
X1190108Y158376D01*
X1190441Y158459D01*
X1190774Y158376D01*
X1191066Y158167D01*
X1191191Y157876D01*
X1191108Y157584D01*
X1190899Y157376D01*
X1190649Y157292D01*
X1190233D01*
X1189858Y157167D01*
X1189608Y156917D01*
X1189524Y156626D01*
X1189608Y156334D01*
X1189816Y156126D01*
X1190149Y156001D01*
X1190441Y155959D01*
G01X1184840Y129130D02*
X1182340D01*
Y130171D01*
X1182465Y130505D01*
X1182632Y130713D01*
X1182965Y130796D01*
X1183298Y130713D01*
X1183507Y130463D01*
X1183632Y130171D01*
Y129130D01*
G01Y130171D02*
X1184840Y130796D01*
G01Y133063D02*
X1184798Y133355D01*
X1184673Y133688D01*
X1184465Y133896D01*
X1184173Y133980D01*
X1183882Y133896D01*
X1183632Y133646D01*
X1183507Y133271D01*
Y132855D01*
X1183423Y132605D01*
X1183215Y132396D01*
X1182923Y132313D01*
X1182632Y132438D01*
X1182423Y132730D01*
X1182340Y133063D01*
X1182423Y133396D01*
X1182632Y133688D01*
X1182923Y133813D01*
X1183215Y133730D01*
X1183423Y133521D01*
X1183507Y133271D01*
Y132855D01*
X1183632Y132480D01*
X1183882Y132230D01*
X1184173Y132146D01*
X1184465Y132230D01*
X1184673Y132438D01*
X1184798Y132771D01*
X1184840Y133063D01*
G01Y135371D02*
X1182340D01*
Y136955D01*
G01X1183548Y136371D02*
Y135371D01*
G01X1184465Y138346D02*
X1184673Y138596D01*
X1184798Y138888D01*
X1184840Y139263D01*
X1184757Y139638D01*
X1184590Y139930D01*
X1184298Y140138D01*
X1183965Y140180D01*
X1183632Y140096D01*
X1183423Y139888D01*
X1183257Y139596D01*
X1183215Y139305D01*
X1183257Y139013D01*
X1183423Y138638D01*
X1182340Y138763D01*
Y139888D01*
G01X1196268Y152892D02*
X1193768D01*
Y153933D01*
X1193893Y154267D01*
X1194060Y154475D01*
X1194393Y154558D01*
X1194726Y154475D01*
X1194935Y154225D01*
X1195060Y153933D01*
Y152892D01*
G01Y153933D02*
X1196268Y154558D01*
G01Y156825D02*
X1196226Y157117D01*
X1196101Y157450D01*
X1195893Y157658D01*
X1195601Y157742D01*
X1195310Y157658D01*
X1195060Y157408D01*
X1194935Y157033D01*
Y156617D01*
X1194851Y156367D01*
X1194643Y156158D01*
X1194351Y156075D01*
X1194060Y156200D01*
X1193851Y156492D01*
X1193768Y156825D01*
X1193851Y157158D01*
X1194060Y157450D01*
X1194351Y157575D01*
X1194643Y157492D01*
X1194851Y157283D01*
X1194935Y157033D01*
Y156617D01*
X1195060Y156242D01*
X1195310Y155992D01*
X1195601Y155908D01*
X1195893Y155992D01*
X1196101Y156200D01*
X1196226Y156533D01*
X1196268Y156825D01*
G01Y160758D02*
Y159092D01*
X1193768D01*
Y160758D01*
G01X1194976Y160092D02*
Y159092D01*
G01X1195768Y162108D02*
X1196060Y162358D01*
X1196226Y162692D01*
X1196268Y163067D01*
X1196226Y163400D01*
X1196018Y163733D01*
X1195768Y163942D01*
X1195518Y163983D01*
X1195226Y163900D01*
X1195018Y163608D01*
X1194935Y163317D01*
Y162942D01*
G01Y163317D02*
X1194810Y163567D01*
X1194601Y163775D01*
X1194351Y163858D01*
X1194101Y163775D01*
X1193893Y163567D01*
X1193768Y163192D01*
X1193810Y162817D01*
X1193976Y162442D01*
G01X1196268Y166125D02*
X1193768D01*
X1194268Y165625D01*
G01X1196268D02*
Y166625D01*
G01X1201697Y154383D02*
X1201572Y154133D01*
X1201489Y153841D01*
Y153508D01*
X1201614Y153133D01*
X1201822Y152841D01*
X1202072Y152633D01*
X1202489Y152466D01*
X1202864Y152424D01*
X1203239Y152508D01*
X1203489Y152633D01*
X1203739Y152883D01*
X1203906Y153174D01*
X1203989Y153466D01*
Y153758D01*
X1203906Y154049D01*
X1203781Y154299D01*
X1203614Y154508D01*
G01X1203989Y156566D02*
X1203947Y156858D01*
X1203822Y157191D01*
X1203614Y157399D01*
X1203322Y157483D01*
X1203031Y157399D01*
X1202781Y157149D01*
X1202656Y156774D01*
Y156358D01*
X1202572Y156108D01*
X1202364Y155899D01*
X1202072Y155816D01*
X1201781Y155941D01*
X1201572Y156233D01*
X1201489Y156566D01*
X1201572Y156899D01*
X1201781Y157191D01*
X1202072Y157316D01*
X1202364Y157233D01*
X1202572Y157024D01*
X1202656Y156774D01*
Y156358D01*
X1202781Y155983D01*
X1203031Y155733D01*
X1203322Y155649D01*
X1203614Y155733D01*
X1203822Y155941D01*
X1203947Y156274D01*
X1203989Y156566D01*
G01Y160499D02*
Y158833D01*
X1201489D01*
Y160499D01*
G01X1202697Y159833D02*
Y158833D01*
G01X1203989Y162766D02*
X1201489D01*
X1201989Y162266D01*
G01X1203989D02*
Y163266D01*
G01X1201906Y165074D02*
X1201656Y165324D01*
X1201531Y165616D01*
X1201489Y165949D01*
X1201572Y166366D01*
X1201781Y166658D01*
X1202031Y166741D01*
X1202281Y166699D01*
X1202489Y166533D01*
X1202906Y165699D01*
X1203197Y165324D01*
X1203614Y165074D01*
X1203989Y164991D01*
Y166741D01*
G01X1210522Y154701D02*
X1210397Y154451D01*
X1210314Y154159D01*
Y153826D01*
X1210439Y153451D01*
X1210647Y153159D01*
X1210897Y152951D01*
X1211314Y152784D01*
X1211689Y152742D01*
X1212064Y152826D01*
X1212314Y152951D01*
X1212564Y153201D01*
X1212731Y153492D01*
X1212814Y153784D01*
Y154076D01*
X1212731Y154367D01*
X1212606Y154617D01*
X1212439Y154826D01*
G01X1212814Y156884D02*
X1212772Y157176D01*
X1212647Y157509D01*
X1212439Y157717D01*
X1212147Y157801D01*
X1211856Y157717D01*
X1211606Y157467D01*
X1211481Y157092D01*
Y156676D01*
X1211397Y156426D01*
X1211189Y156217D01*
X1210897Y156134D01*
X1210606Y156259D01*
X1210397Y156551D01*
X1210314Y156884D01*
X1210397Y157217D01*
X1210606Y157509D01*
X1210897Y157634D01*
X1211189Y157551D01*
X1211397Y157342D01*
X1211481Y157092D01*
Y156676D01*
X1211606Y156301D01*
X1211856Y156051D01*
X1212147Y155967D01*
X1212439Y156051D01*
X1212647Y156259D01*
X1212772Y156592D01*
X1212814Y156884D01*
G01Y160817D02*
Y159151D01*
X1210314D01*
Y160817D01*
G01X1211522Y160151D02*
Y159151D01*
G01X1212814Y163084D02*
X1210314D01*
X1210814Y162584D01*
G01X1212814D02*
Y163584D01*
G01Y166684D02*
X1210314D01*
X1212106Y165142D01*
Y167226D01*
G01X1177613Y145725D02*
X1177363Y145850D01*
X1177071Y145933D01*
X1176738D01*
X1176363Y145808D01*
X1176071Y145600D01*
X1175863Y145350D01*
X1175696Y144933D01*
X1175654Y144558D01*
X1175738Y144183D01*
X1175863Y143933D01*
X1176113Y143683D01*
X1176404Y143516D01*
X1176696Y143433D01*
X1176988D01*
X1177279Y143516D01*
X1177529Y143641D01*
X1177738Y143808D01*
G01X1179796Y143433D02*
X1180088Y143475D01*
X1180421Y143600D01*
X1180629Y143808D01*
X1180713Y144100D01*
X1180629Y144391D01*
X1180379Y144641D01*
X1180004Y144766D01*
X1179588D01*
X1179338Y144850D01*
X1179129Y145058D01*
X1179046Y145350D01*
X1179171Y145641D01*
X1179463Y145850D01*
X1179796Y145933D01*
X1180129Y145850D01*
X1180421Y145641D01*
X1180546Y145350D01*
X1180463Y145058D01*
X1180254Y144850D01*
X1180004Y144766D01*
X1179588D01*
X1179213Y144641D01*
X1178963Y144391D01*
X1178879Y144100D01*
X1178963Y143808D01*
X1179171Y143600D01*
X1179504Y143475D01*
X1179796Y143433D01*
G01X1182104D02*
Y145933D01*
X1183688D01*
G01X1183104Y144725D02*
X1182104D01*
G01X1185204Y145516D02*
X1185454Y145766D01*
X1185746Y145891D01*
X1186079Y145933D01*
X1186496Y145850D01*
X1186788Y145641D01*
X1186871Y145391D01*
X1186829Y145141D01*
X1186663Y144933D01*
X1185829Y144516D01*
X1185454Y144225D01*
X1185204Y143808D01*
X1185121Y143433D01*
X1186871D01*
G01X1171564Y153736D02*
X1171439Y153486D01*
X1171356Y153194D01*
Y152861D01*
X1171481Y152486D01*
X1171689Y152194D01*
X1171939Y151986D01*
X1172356Y151819D01*
X1172731Y151777D01*
X1173106Y151861D01*
X1173356Y151986D01*
X1173606Y152236D01*
X1173773Y152527D01*
X1173856Y152819D01*
Y153111D01*
X1173773Y153402D01*
X1173648Y153652D01*
X1173481Y153861D01*
G01X1173856Y155919D02*
X1173814Y156211D01*
X1173689Y156544D01*
X1173481Y156752D01*
X1173189Y156836D01*
X1172898Y156752D01*
X1172648Y156502D01*
X1172523Y156127D01*
Y155711D01*
X1172439Y155461D01*
X1172231Y155252D01*
X1171939Y155169D01*
X1171648Y155294D01*
X1171439Y155586D01*
X1171356Y155919D01*
X1171439Y156252D01*
X1171648Y156544D01*
X1171939Y156669D01*
X1172231Y156586D01*
X1172439Y156377D01*
X1172523Y156127D01*
Y155711D01*
X1172648Y155336D01*
X1172898Y155086D01*
X1173189Y155002D01*
X1173481Y155086D01*
X1173689Y155294D01*
X1173814Y155627D01*
X1173856Y155919D01*
G01Y159852D02*
Y158186D01*
X1171356D01*
Y159852D01*
G01X1172564Y159186D02*
Y158186D01*
G01X1173856Y162119D02*
X1171356D01*
X1171856Y161619D01*
G01X1173856D02*
Y162619D01*
G01Y165136D02*
X1173314Y165219D01*
X1172856Y165344D01*
X1172439Y165511D01*
X1171981Y165719D01*
X1171356Y166052D01*
Y164386D01*
G01X1197936Y139517D02*
Y137851D01*
X1195436D01*
Y139517D01*
G01X1196644Y138851D02*
Y137851D01*
G01X1195436Y140867D02*
X1197228D01*
X1197603Y141034D01*
X1197853Y141367D01*
X1197936Y141784D01*
X1197853Y142201D01*
X1197603Y142534D01*
X1197228Y142701D01*
X1195436D01*
G01X1197936Y144884D02*
X1197894Y145176D01*
X1197769Y145509D01*
X1197561Y145717D01*
X1197269Y145801D01*
X1196978Y145717D01*
X1196728Y145467D01*
X1196603Y145092D01*
Y144676D01*
X1196519Y144426D01*
X1196311Y144217D01*
X1196019Y144134D01*
X1195728Y144259D01*
X1195519Y144551D01*
X1195436Y144884D01*
X1195519Y145217D01*
X1195728Y145509D01*
X1196019Y145634D01*
X1196311Y145551D01*
X1196519Y145342D01*
X1196603Y145092D01*
Y144676D01*
X1196728Y144301D01*
X1196978Y144051D01*
X1197269Y143967D01*
X1197561Y144051D01*
X1197769Y144259D01*
X1197894Y144592D01*
X1197936Y144884D01*
G01Y147192D02*
X1195436D01*
Y148776D01*
G01X1196644Y148192D02*
Y147192D01*
G01X1197936Y151084D02*
X1195436D01*
X1195936Y150584D01*
G01X1197936D02*
Y151584D01*
G01X1202912Y139517D02*
Y137851D01*
X1200412D01*
Y139517D01*
G01X1201620Y138851D02*
Y137851D01*
G01X1200412Y140867D02*
X1202204D01*
X1202579Y141034D01*
X1202829Y141367D01*
X1202912Y141784D01*
X1202829Y142201D01*
X1202579Y142534D01*
X1202204Y142701D01*
X1200412D01*
G01X1202912Y144884D02*
X1202870Y145176D01*
X1202745Y145509D01*
X1202537Y145717D01*
X1202245Y145801D01*
X1201954Y145717D01*
X1201704Y145467D01*
X1201579Y145092D01*
Y144676D01*
X1201495Y144426D01*
X1201287Y144217D01*
X1200995Y144134D01*
X1200704Y144259D01*
X1200495Y144551D01*
X1200412Y144884D01*
X1200495Y145217D01*
X1200704Y145509D01*
X1200995Y145634D01*
X1201287Y145551D01*
X1201495Y145342D01*
X1201579Y145092D01*
Y144676D01*
X1201704Y144301D01*
X1201954Y144051D01*
X1202245Y143967D01*
X1202537Y144051D01*
X1202745Y144259D01*
X1202870Y144592D01*
X1202912Y144884D01*
G01Y148817D02*
Y147151D01*
X1200412D01*
Y148817D01*
G01X1201620Y148151D02*
Y147151D01*
G01X1202912Y151084D02*
X1200412D01*
X1200912Y150584D01*
G01X1202912D02*
Y151584D01*
G01X1201310Y116015D02*
X1201268Y115682D01*
X1201102Y115390D01*
X1200852Y115140D01*
X1200560Y114973D01*
X1200227Y114890D01*
X1199893D01*
X1199560Y114973D01*
X1199268Y115140D01*
X1199018Y115390D01*
X1198852Y115682D01*
X1198810Y116015D01*
X1198852Y116348D01*
X1199018Y116640D01*
X1199268Y116890D01*
X1199560Y117057D01*
X1199893Y117140D01*
X1200227D01*
X1200560Y117057D01*
X1200852Y116890D01*
X1201102Y116640D01*
X1201268Y116348D01*
X1201310Y116015D01*
G01X1200643Y116348D02*
X1201310Y116848D01*
G01Y119115D02*
X1198810D01*
X1199310Y118615D01*
G01X1201310D02*
Y119615D01*
G01Y121423D02*
X1198810D01*
Y123007D01*
G01X1200018Y122423D02*
Y121423D01*
G01X1201310Y125315D02*
X1198810D01*
X1199310Y124815D01*
G01X1201310D02*
Y125815D01*
G01X1215025Y131674D02*
Y134924D01*
X1218525D01*
G01X1214175Y111622D02*
X1214133Y111289D01*
X1213967Y110997D01*
X1213717Y110747D01*
X1213425Y110580D01*
X1213092Y110497D01*
X1212758D01*
X1212425Y110580D01*
X1212133Y110747D01*
X1211883Y110997D01*
X1211717Y111289D01*
X1211675Y111622D01*
X1211717Y111955D01*
X1211883Y112247D01*
X1212133Y112497D01*
X1212425Y112664D01*
X1212758Y112747D01*
X1213092D01*
X1213425Y112664D01*
X1213717Y112497D01*
X1213967Y112247D01*
X1214133Y111955D01*
X1214175Y111622D01*
G01X1213508Y111955D02*
X1214175Y112455D01*
G01Y114722D02*
X1211675D01*
X1212175Y114222D01*
G01X1214175D02*
Y115222D01*
G01X1211675Y116572D02*
X1214175Y117155D01*
X1211675Y117822D01*
X1214175Y118489D01*
X1211675Y119072D01*
G01X1213133Y120130D02*
X1212842Y120422D01*
X1212675Y120672D01*
X1212592Y121005D01*
X1212675Y121297D01*
X1212842Y121505D01*
X1213092Y121672D01*
X1213383Y121714D01*
X1213633Y121672D01*
X1213883Y121505D01*
X1214092Y121255D01*
X1214175Y120964D01*
X1214092Y120630D01*
X1213842Y120339D01*
X1213467Y120172D01*
X1213050Y120130D01*
X1212508Y120214D01*
X1212217Y120339D01*
X1211925Y120547D01*
X1211717Y120839D01*
X1211675Y121130D01*
X1211758Y121422D01*
X1211967Y121630D01*
G01X1216222Y146386D02*
X1216097Y146136D01*
X1216014Y145844D01*
Y145511D01*
X1216139Y145136D01*
X1216347Y144844D01*
X1216597Y144636D01*
X1217014Y144469D01*
X1217389Y144427D01*
X1217764Y144511D01*
X1218014Y144636D01*
X1218264Y144886D01*
X1218431Y145177D01*
X1218514Y145469D01*
Y145761D01*
X1218431Y146052D01*
X1218306Y146302D01*
X1218139Y146511D01*
G01X1218222Y147861D02*
X1218431Y148152D01*
X1218514Y148486D01*
X1218431Y148819D01*
X1218181Y149111D01*
X1217806Y149319D01*
X1217431Y149402D01*
X1216972D01*
X1216597Y149319D01*
X1216264Y149111D01*
X1216097Y148861D01*
X1216014Y148569D01*
X1216097Y148236D01*
X1216264Y147986D01*
X1216514Y147819D01*
X1216847Y147736D01*
X1217139Y147819D01*
X1217431Y148027D01*
X1217597Y148277D01*
X1217639Y148569D01*
X1217556Y148902D01*
X1217347Y149152D01*
X1216972Y149402D01*
G01X1218514Y150877D02*
X1216014D01*
Y152461D01*
G01X1217222Y151877D02*
Y150877D01*
G01X1218514Y154769D02*
X1216014D01*
X1216514Y154269D01*
G01X1218514D02*
Y155269D01*
G01X1214989Y168086D02*
Y170586D01*
X1216030D01*
X1216364Y170461D01*
X1216572Y170294D01*
X1216655Y169961D01*
X1216572Y169628D01*
X1216322Y169419D01*
X1216030Y169294D01*
X1214989D01*
G01X1216030D02*
X1216655Y168086D01*
G01X1218922D02*
Y170586D01*
X1218422Y170086D01*
G01Y168086D02*
X1219422D01*
G01X1220772Y170586D02*
X1221355Y168086D01*
X1222022Y170586D01*
X1222689Y168086D01*
X1223272Y170586D01*
G01X1224330Y170169D02*
X1224580Y170419D01*
X1224872Y170544D01*
X1225205Y170586D01*
X1225622Y170503D01*
X1225914Y170294D01*
X1225997Y170044D01*
X1225955Y169794D01*
X1225789Y169586D01*
X1224955Y169169D01*
X1224580Y168878D01*
X1224330Y168461D01*
X1224247Y168086D01*
X1225997D01*
G01X1227305Y168586D02*
X1227555Y168294D01*
X1227889Y168128D01*
X1228264Y168086D01*
X1228597Y168128D01*
X1228930Y168336D01*
X1229139Y168586D01*
X1229180Y168836D01*
X1229097Y169128D01*
X1228805Y169336D01*
X1228514Y169419D01*
X1228139D01*
G01X1228514D02*
X1228764Y169544D01*
X1228972Y169753D01*
X1229055Y170003D01*
X1228972Y170253D01*
X1228764Y170461D01*
X1228389Y170586D01*
X1228014Y170544D01*
X1227639Y170378D01*
G01X1215089Y172086D02*
Y174586D01*
X1216130D01*
X1216464Y174461D01*
X1216672Y174294D01*
X1216755Y173961D01*
X1216672Y173628D01*
X1216422Y173419D01*
X1216130Y173294D01*
X1215089D01*
G01X1216130D02*
X1216755Y172086D01*
G01X1219022D02*
Y174586D01*
X1218522Y174086D01*
G01Y172086D02*
X1219522D01*
G01X1220872Y174586D02*
X1221455Y172086D01*
X1222122Y174586D01*
X1222789Y172086D01*
X1223372Y174586D01*
G01X1224430Y174169D02*
X1224680Y174419D01*
X1224972Y174544D01*
X1225305Y174586D01*
X1225722Y174503D01*
X1226014Y174294D01*
X1226097Y174044D01*
X1226055Y173794D01*
X1225889Y173586D01*
X1225055Y173169D01*
X1224680Y172878D01*
X1224430Y172461D01*
X1224347Y172086D01*
X1226097D01*
G01X1227530Y174169D02*
X1227780Y174419D01*
X1228072Y174544D01*
X1228405Y174586D01*
X1228822Y174503D01*
X1229114Y174294D01*
X1229197Y174044D01*
X1229155Y173794D01*
X1228989Y173586D01*
X1228155Y173169D01*
X1227780Y172878D01*
X1227530Y172461D01*
X1227447Y172086D01*
X1229197D01*
G01X1176398Y160109D02*
Y162609D01*
X1177439D01*
X1177773Y162484D01*
X1177981Y162317D01*
X1178064Y161984D01*
X1177981Y161651D01*
X1177731Y161442D01*
X1177439Y161317D01*
X1176398D01*
G01X1177439D02*
X1178064Y160109D01*
G01X1180331D02*
X1180623Y160151D01*
X1180956Y160276D01*
X1181164Y160484D01*
X1181248Y160776D01*
X1181164Y161067D01*
X1180914Y161317D01*
X1180539Y161442D01*
X1180123D01*
X1179873Y161526D01*
X1179664Y161734D01*
X1179581Y162026D01*
X1179706Y162317D01*
X1179998Y162526D01*
X1180331Y162609D01*
X1180664Y162526D01*
X1180956Y162317D01*
X1181081Y162026D01*
X1180998Y161734D01*
X1180789Y161526D01*
X1180539Y161442D01*
X1180123D01*
X1179748Y161317D01*
X1179498Y161067D01*
X1179414Y160776D01*
X1179498Y160484D01*
X1179706Y160276D01*
X1180039Y160151D01*
X1180331Y160109D01*
G01X1184264D02*
X1182598D01*
Y162609D01*
X1184264D01*
G01X1183598Y161401D02*
X1182598D01*
G01X1185614Y160609D02*
X1185864Y160317D01*
X1186198Y160151D01*
X1186573Y160109D01*
X1186906Y160151D01*
X1187239Y160359D01*
X1187448Y160609D01*
X1187489Y160859D01*
X1187406Y161151D01*
X1187114Y161359D01*
X1186823Y161442D01*
X1186448D01*
G01X1186823D02*
X1187073Y161567D01*
X1187281Y161776D01*
X1187364Y162026D01*
X1187281Y162276D01*
X1187073Y162484D01*
X1186698Y162609D01*
X1186323Y162567D01*
X1185948Y162401D01*
G01X1190131Y160109D02*
Y162609D01*
X1188589Y160817D01*
X1190673D01*
G01X1176488Y164356D02*
Y166856D01*
X1177529D01*
X1177863Y166731D01*
X1178071Y166564D01*
X1178154Y166231D01*
X1178071Y165898D01*
X1177821Y165689D01*
X1177529Y165564D01*
X1176488D01*
G01X1177529D02*
X1178154Y164356D01*
G01X1180421D02*
X1180713Y164398D01*
X1181046Y164523D01*
X1181254Y164731D01*
X1181338Y165023D01*
X1181254Y165314D01*
X1181004Y165564D01*
X1180629Y165689D01*
X1180213D01*
X1179963Y165773D01*
X1179754Y165981D01*
X1179671Y166273D01*
X1179796Y166564D01*
X1180088Y166773D01*
X1180421Y166856D01*
X1180754Y166773D01*
X1181046Y166564D01*
X1181171Y166273D01*
X1181088Y165981D01*
X1180879Y165773D01*
X1180629Y165689D01*
X1180213D01*
X1179838Y165564D01*
X1179588Y165314D01*
X1179504Y165023D01*
X1179588Y164731D01*
X1179796Y164523D01*
X1180129Y164398D01*
X1180421Y164356D01*
G01X1184354D02*
X1182688D01*
Y166856D01*
X1184354D01*
G01X1183688Y165648D02*
X1182688D01*
G01X1185829Y166439D02*
X1186079Y166689D01*
X1186371Y166814D01*
X1186704Y166856D01*
X1187121Y166773D01*
X1187413Y166564D01*
X1187496Y166314D01*
X1187454Y166064D01*
X1187288Y165856D01*
X1186454Y165439D01*
X1186079Y165148D01*
X1185829Y164731D01*
X1185746Y164356D01*
X1187496D01*
G01X1188804Y164731D02*
X1189054Y164523D01*
X1189346Y164398D01*
X1189721Y164356D01*
X1190096Y164439D01*
X1190388Y164606D01*
X1190596Y164898D01*
X1190638Y165231D01*
X1190554Y165564D01*
X1190346Y165773D01*
X1190054Y165939D01*
X1189763Y165981D01*
X1189471Y165939D01*
X1189096Y165773D01*
X1189221Y166856D01*
X1190346D01*
G01X1163976Y179404D02*
Y176304D01*
X1164436Y176924D01*
G01Y179404D02*
X1163516D01*
G01X1161719Y178939D02*
X1161489Y179197D01*
X1161221Y179352D01*
X1160876Y179404D01*
X1160531Y179301D01*
X1160263Y179094D01*
X1160071Y178732D01*
X1160033Y178319D01*
X1160109Y177906D01*
X1160301Y177647D01*
X1160569Y177441D01*
X1160838Y177389D01*
X1161106Y177441D01*
X1161451Y177647D01*
X1161336Y176304D01*
X1160301D01*
G01X1167422Y175701D02*
Y172601D01*
X1167882Y173221D01*
G01Y175701D02*
X1166962D01*
G01X1163862D02*
Y172601D01*
X1165280Y174823D01*
X1163364D01*
G01X1170736Y179404D02*
Y176304D01*
X1171196Y176924D01*
G01Y179404D02*
X1170276D01*
G01X1168479Y178784D02*
X1168249Y179146D01*
X1167943Y179352D01*
X1167598Y179404D01*
X1167291Y179352D01*
X1166984Y179094D01*
X1166793Y178784D01*
X1166754Y178474D01*
X1166831Y178112D01*
X1167099Y177854D01*
X1167368Y177751D01*
X1167713D01*
G01X1167368D02*
X1167138Y177596D01*
X1166946Y177337D01*
X1166869Y177027D01*
X1166946Y176717D01*
X1167138Y176459D01*
X1167483Y176304D01*
X1167828Y176356D01*
X1168173Y176562D01*
G01X1174182Y175701D02*
Y172601D01*
X1174642Y173221D01*
G01Y175701D02*
X1173722D01*
G01X1171810Y173118D02*
X1171580Y172808D01*
X1171312Y172653D01*
X1171005Y172601D01*
X1170622Y172704D01*
X1170354Y172963D01*
X1170277Y173273D01*
X1170315Y173583D01*
X1170469Y173841D01*
X1171235Y174358D01*
X1171580Y174719D01*
X1171810Y175236D01*
X1171887Y175701D01*
X1170277D01*
G01X1177496Y179404D02*
Y176304D01*
X1177956Y176924D01*
G01Y179404D02*
X1177036D01*
G01X1174396D02*
Y176304D01*
X1174856Y176924D01*
G01Y179404D02*
X1173936D01*
G01X1180941Y175701D02*
Y172601D01*
X1181401Y173221D01*
G01Y175701D02*
X1180481D01*
G01X1177841Y172601D02*
X1178148Y172704D01*
X1178378Y172963D01*
X1178531Y173273D01*
X1178646Y173686D01*
X1178684Y174151D01*
X1178646Y174616D01*
X1178531Y175029D01*
X1178378Y175339D01*
X1178148Y175598D01*
X1177841Y175701D01*
X1177534Y175598D01*
X1177304Y175339D01*
X1177151Y175029D01*
X1177036Y174616D01*
X1176998Y174151D01*
X1177036Y173686D01*
X1177151Y173273D01*
X1177304Y172963D01*
X1177534Y172704D01*
X1177841Y172601D01*
G01X1183358Y179042D02*
X1183089Y179301D01*
X1182783Y179404D01*
X1182476Y179301D01*
X1182208Y178991D01*
X1182016Y178526D01*
X1181939Y178061D01*
Y177492D01*
X1182016Y177027D01*
X1182208Y176614D01*
X1182438Y176407D01*
X1182706Y176304D01*
X1183013Y176407D01*
X1183243Y176614D01*
X1183396Y176924D01*
X1183473Y177337D01*
X1183396Y177699D01*
X1183204Y178061D01*
X1182974Y178267D01*
X1182706Y178319D01*
X1182399Y178216D01*
X1182169Y177957D01*
X1181939Y177492D01*
G01X1186151Y174201D02*
X1185883Y174149D01*
X1185576Y173994D01*
X1185384Y173736D01*
X1185308Y173374D01*
X1185384Y173013D01*
X1185614Y172703D01*
X1185959Y172548D01*
X1186343D01*
X1186573Y172444D01*
X1186764Y172186D01*
X1186841Y171824D01*
X1186726Y171463D01*
X1186458Y171204D01*
X1186151Y171101D01*
X1185844Y171204D01*
X1185576Y171463D01*
X1185461Y171824D01*
X1185538Y172186D01*
X1185729Y172444D01*
X1185959Y172548D01*
X1186343D01*
X1186688Y172703D01*
X1186918Y173013D01*
X1186994Y173374D01*
X1186918Y173736D01*
X1186726Y173994D01*
X1186419Y174149D01*
X1186151Y174201D01*
G01X1189543Y177904D02*
X1189466Y177232D01*
X1189351Y176664D01*
X1189198Y176147D01*
X1189006Y175579D01*
X1188699Y174804D01*
X1190233D01*
G01X1193639Y172909D02*
X1193371Y172548D01*
X1193141Y172341D01*
X1192834Y172238D01*
X1192566Y172341D01*
X1192374Y172548D01*
X1192221Y172858D01*
X1192183Y173219D01*
X1192221Y173529D01*
X1192374Y173839D01*
X1192604Y174098D01*
X1192873Y174201D01*
X1193179Y174098D01*
X1193448Y173788D01*
X1193601Y173323D01*
X1193639Y172806D01*
X1193563Y172134D01*
X1193448Y171773D01*
X1193256Y171411D01*
X1192988Y171153D01*
X1192719Y171101D01*
X1192451Y171204D01*
X1192259Y171463D01*
G01X1197069Y177439D02*
X1196839Y177697D01*
X1196571Y177852D01*
X1196226Y177904D01*
X1195881Y177801D01*
X1195613Y177594D01*
X1195421Y177232D01*
X1195383Y176819D01*
X1195459Y176406D01*
X1195651Y176147D01*
X1195919Y175941D01*
X1196188Y175889D01*
X1196456Y175941D01*
X1196801Y176147D01*
X1196686Y174804D01*
X1195651D01*
G01X1199211Y174201D02*
Y171101D01*
X1200629Y173323D01*
X1198713D01*
G01X1203829Y177284D02*
X1203599Y177646D01*
X1203293Y177852D01*
X1202948Y177904D01*
X1202641Y177852D01*
X1202334Y177594D01*
X1202143Y177284D01*
X1202104Y176974D01*
X1202181Y176612D01*
X1202449Y176354D01*
X1202718Y176251D01*
X1203063D01*
G01X1202718D02*
X1202488Y176096D01*
X1202296Y175837D01*
X1202219Y175527D01*
X1202296Y175217D01*
X1202488Y174959D01*
X1202833Y174804D01*
X1203178Y174856D01*
X1203523Y175062D01*
G01X1207159Y171618D02*
X1206929Y171308D01*
X1206661Y171153D01*
X1206354Y171101D01*
X1205971Y171204D01*
X1205703Y171463D01*
X1205626Y171773D01*
X1205664Y172083D01*
X1205818Y172341D01*
X1206584Y172858D01*
X1206929Y173219D01*
X1207159Y173736D01*
X1207236Y174201D01*
X1205626D01*
G01X1209745Y177904D02*
Y174804D01*
X1210205Y175424D01*
G01Y177904D02*
X1209285D01*
G01X1216689Y165478D02*
X1216439Y165603D01*
X1216147Y165686D01*
X1215814D01*
X1215439Y165561D01*
X1215147Y165353D01*
X1214939Y165103D01*
X1214772Y164686D01*
X1214730Y164311D01*
X1214814Y163936D01*
X1214939Y163686D01*
X1215189Y163436D01*
X1215480Y163269D01*
X1215772Y163186D01*
X1216064D01*
X1216355Y163269D01*
X1216605Y163394D01*
X1216814Y163561D01*
G01X1218080Y165269D02*
X1218330Y165519D01*
X1218622Y165644D01*
X1218955Y165686D01*
X1219372Y165603D01*
X1219664Y165394D01*
X1219747Y165144D01*
X1219705Y164894D01*
X1219539Y164686D01*
X1218705Y164269D01*
X1218330Y163978D01*
X1218080Y163561D01*
X1217997Y163186D01*
X1219747D01*
G01X1221180Y165269D02*
X1221430Y165519D01*
X1221722Y165644D01*
X1222055Y165686D01*
X1222472Y165603D01*
X1222764Y165394D01*
X1222847Y165144D01*
X1222805Y164894D01*
X1222639Y164686D01*
X1221805Y164269D01*
X1221430Y163978D01*
X1221180Y163561D01*
X1221097Y163186D01*
X1222847D01*
G01X1223822Y165686D02*
X1224405Y163186D01*
X1225072Y165686D01*
X1225739Y163186D01*
X1226322Y165686D01*
G01X1228172Y163186D02*
Y165686D01*
X1227672Y165186D01*
G01Y163186D02*
X1228672D01*
G01X1231272D02*
Y165686D01*
X1230772Y165186D01*
G01Y163186D02*
X1231772D01*
G01X1158894Y425102D02*
Y425043D01*
X1224595D01*
Y434877D01*
X1245566D01*
Y456915D01*
X1229216D01*
Y470838D01*
X1223410D01*
Y483693D01*
X1204570D01*
Y480051D01*
X1158770D01*
Y450160D01*
G01X1208848Y444842D02*
Y447342D01*
X1209889D01*
X1210223Y447217D01*
X1210431Y447050D01*
X1210514Y446717D01*
X1210431Y446384D01*
X1210181Y446175D01*
X1209889Y446050D01*
X1208848D01*
G01X1209889D02*
X1210514Y444842D01*
G01X1212781D02*
Y447342D01*
X1212281Y446842D01*
G01Y444842D02*
X1213281D01*
G01X1215048Y447342D02*
Y444842D01*
X1216714D01*
G01X1218189Y446925D02*
X1218439Y447175D01*
X1218731Y447300D01*
X1219064Y447342D01*
X1219481Y447259D01*
X1219773Y447050D01*
X1219856Y446800D01*
X1219814Y446550D01*
X1219648Y446342D01*
X1218814Y445925D01*
X1218439Y445634D01*
X1218189Y445217D01*
X1218106Y444842D01*
X1219856D01*
G01X1221164Y445217D02*
X1221414Y445009D01*
X1221706Y444884D01*
X1222081Y444842D01*
X1222456Y444925D01*
X1222748Y445092D01*
X1222956Y445384D01*
X1222998Y445717D01*
X1222914Y446050D01*
X1222706Y446259D01*
X1222414Y446425D01*
X1222123Y446467D01*
X1221831Y446425D01*
X1221456Y446259D01*
X1221581Y447342D01*
X1222706D01*
G01X1208848Y448242D02*
Y450742D01*
X1209889D01*
X1210223Y450617D01*
X1210431Y450450D01*
X1210514Y450117D01*
X1210431Y449784D01*
X1210181Y449575D01*
X1209889Y449450D01*
X1208848D01*
G01X1209889D02*
X1210514Y448242D01*
G01X1212781D02*
Y450742D01*
X1212281Y450242D01*
G01Y448242D02*
X1213281D01*
G01X1215048Y450742D02*
Y448242D01*
X1216714D01*
G01X1218189Y450325D02*
X1218439Y450575D01*
X1218731Y450700D01*
X1219064Y450742D01*
X1219481Y450659D01*
X1219773Y450450D01*
X1219856Y450200D01*
X1219814Y449950D01*
X1219648Y449742D01*
X1218814Y449325D01*
X1218439Y449034D01*
X1218189Y448617D01*
X1218106Y448242D01*
X1219856D01*
G01X1222581D02*
Y450742D01*
X1221039Y448950D01*
X1223123D01*
G01X1210717Y464290D02*
Y466790D01*
X1211758D01*
X1212092Y466665D01*
X1212300Y466498D01*
X1212383Y466165D01*
X1212300Y465832D01*
X1212050Y465623D01*
X1211758Y465498D01*
X1210717D01*
G01X1211758D02*
X1212383Y464290D01*
G01X1213858Y465332D02*
X1214150Y465623D01*
X1214400Y465790D01*
X1214733Y465873D01*
X1215025Y465790D01*
X1215233Y465623D01*
X1215400Y465373D01*
X1215442Y465082D01*
X1215400Y464832D01*
X1215233Y464582D01*
X1214983Y464373D01*
X1214692Y464290D01*
X1214358Y464373D01*
X1214067Y464623D01*
X1213900Y464998D01*
X1213858Y465415D01*
X1213942Y465957D01*
X1214067Y466248D01*
X1214275Y466540D01*
X1214567Y466748D01*
X1214858Y466790D01*
X1215150Y466707D01*
X1215358Y466498D01*
G01X1216500Y466790D02*
X1217083Y464290D01*
X1217750Y466790D01*
X1218417Y464290D01*
X1219000Y466790D01*
G01X1220850Y464290D02*
Y466790D01*
X1220350Y466290D01*
G01Y464290D02*
X1221350D01*
G01X1223242Y464582D02*
X1223533Y464373D01*
X1223867Y464290D01*
X1224200Y464373D01*
X1224492Y464623D01*
X1224700Y464998D01*
X1224783Y465373D01*
Y465832D01*
X1224700Y466207D01*
X1224492Y466540D01*
X1224242Y466707D01*
X1223950Y466790D01*
X1223617Y466707D01*
X1223367Y466540D01*
X1223200Y466290D01*
X1223117Y465957D01*
X1223200Y465665D01*
X1223408Y465373D01*
X1223658Y465207D01*
X1223950Y465165D01*
X1224283Y465248D01*
X1224533Y465457D01*
X1224783Y465832D01*
G01X1218455Y426095D02*
X1215955D01*
Y427136D01*
X1216080Y427470D01*
X1216247Y427678D01*
X1216580Y427761D01*
X1216913Y427678D01*
X1217122Y427428D01*
X1217247Y427136D01*
Y426095D01*
G01Y427136D02*
X1218455Y427761D01*
G01Y430028D02*
X1215955D01*
X1216455Y429528D01*
G01X1218455D02*
Y430528D01*
G01X1215955Y432295D02*
X1218455D01*
Y433961D01*
G01X1217955Y435311D02*
X1218247Y435561D01*
X1218413Y435895D01*
X1218455Y436270D01*
X1218413Y436603D01*
X1218205Y436936D01*
X1217955Y437145D01*
X1217705Y437186D01*
X1217413Y437103D01*
X1217205Y436811D01*
X1217122Y436520D01*
Y436145D01*
G01Y436520D02*
X1216997Y436770D01*
X1216788Y436978D01*
X1216538Y437061D01*
X1216288Y436978D01*
X1216080Y436770D01*
X1215955Y436395D01*
X1215997Y436020D01*
X1216163Y435645D01*
G01X1218455Y439245D02*
X1217913Y439328D01*
X1217455Y439453D01*
X1217038Y439620D01*
X1216580Y439828D01*
X1215955Y440161D01*
Y438495D01*
G01X1200693Y450317D02*
X1198193D01*
Y451358D01*
X1198318Y451692D01*
X1198485Y451900D01*
X1198818Y451983D01*
X1199151Y451900D01*
X1199360Y451650D01*
X1199485Y451358D01*
Y450317D01*
G01Y451358D02*
X1200693Y451983D01*
G01Y454250D02*
X1198193D01*
X1198693Y453750D01*
G01X1200693D02*
Y454750D01*
G01X1198193Y456517D02*
X1200693D01*
Y458183D01*
G01X1198610Y459658D02*
X1198360Y459908D01*
X1198235Y460200D01*
X1198193Y460533D01*
X1198276Y460950D01*
X1198485Y461242D01*
X1198735Y461325D01*
X1198985Y461283D01*
X1199193Y461117D01*
X1199610Y460283D01*
X1199901Y459908D01*
X1200318Y459658D01*
X1200693Y459575D01*
Y461325D01*
G01X1199651Y462758D02*
X1199360Y463050D01*
X1199193Y463300D01*
X1199110Y463633D01*
X1199193Y463925D01*
X1199360Y464133D01*
X1199610Y464300D01*
X1199901Y464342D01*
X1200151Y464300D01*
X1200401Y464133D01*
X1200610Y463883D01*
X1200693Y463592D01*
X1200610Y463258D01*
X1200360Y462967D01*
X1199985Y462800D01*
X1199568Y462758D01*
X1199026Y462842D01*
X1198735Y462967D01*
X1198443Y463175D01*
X1198235Y463467D01*
X1198193Y463758D01*
X1198276Y464050D01*
X1198485Y464258D01*
G01X1162945Y435384D02*
Y437884D01*
X1163986D01*
X1164320Y437759D01*
X1164528Y437592D01*
X1164611Y437259D01*
X1164528Y436926D01*
X1164278Y436717D01*
X1163986Y436592D01*
X1162945D01*
G01X1163986D02*
X1164611Y435384D01*
G01X1166170Y435676D02*
X1166461Y435467D01*
X1166795Y435384D01*
X1167128Y435467D01*
X1167420Y435717D01*
X1167628Y436092D01*
X1167711Y436467D01*
Y436926D01*
X1167628Y437301D01*
X1167420Y437634D01*
X1167170Y437801D01*
X1166878Y437884D01*
X1166545Y437801D01*
X1166295Y437634D01*
X1166128Y437384D01*
X1166045Y437051D01*
X1166128Y436759D01*
X1166336Y436467D01*
X1166586Y436301D01*
X1166878Y436259D01*
X1167211Y436342D01*
X1167461Y436551D01*
X1167711Y436926D01*
G01X1168936Y435384D02*
X1169978Y437884D01*
X1171020Y435384D01*
G01X1170645Y436259D02*
X1169311D01*
G01X1172286Y437467D02*
X1172536Y437717D01*
X1172828Y437842D01*
X1173161Y437884D01*
X1173578Y437801D01*
X1173870Y437592D01*
X1173953Y437342D01*
X1173911Y437092D01*
X1173745Y436884D01*
X1172911Y436467D01*
X1172536Y436176D01*
X1172286Y435759D01*
X1172203Y435384D01*
X1173953D01*
G01X1176178D02*
Y437884D01*
X1175678Y437384D01*
G01Y435384D02*
X1176678D01*
G01X1162946Y439026D02*
Y441526D01*
X1163987D01*
X1164321Y441401D01*
X1164529Y441234D01*
X1164612Y440901D01*
X1164529Y440568D01*
X1164279Y440359D01*
X1163987Y440234D01*
X1162946D01*
G01X1163987D02*
X1164612Y439026D01*
G01X1166171Y439318D02*
X1166462Y439109D01*
X1166796Y439026D01*
X1167129Y439109D01*
X1167421Y439359D01*
X1167629Y439734D01*
X1167712Y440109D01*
Y440568D01*
X1167629Y440943D01*
X1167421Y441276D01*
X1167171Y441443D01*
X1166879Y441526D01*
X1166546Y441443D01*
X1166296Y441276D01*
X1166129Y441026D01*
X1166046Y440693D01*
X1166129Y440401D01*
X1166337Y440109D01*
X1166587Y439943D01*
X1166879Y439901D01*
X1167212Y439984D01*
X1167462Y440193D01*
X1167712Y440568D01*
G01X1168937Y439026D02*
X1169979Y441526D01*
X1171021Y439026D01*
G01X1170646Y439901D02*
X1169312D01*
G01X1173079Y439026D02*
Y441526D01*
X1172579Y441026D01*
G01Y439026D02*
X1173579D01*
G01X1176179D02*
X1176471Y439068D01*
X1176804Y439193D01*
X1177012Y439401D01*
X1177096Y439693D01*
X1177012Y439984D01*
X1176762Y440234D01*
X1176387Y440359D01*
X1175971D01*
X1175721Y440443D01*
X1175512Y440651D01*
X1175429Y440943D01*
X1175554Y441234D01*
X1175846Y441443D01*
X1176179Y441526D01*
X1176512Y441443D01*
X1176804Y441234D01*
X1176929Y440943D01*
X1176846Y440651D01*
X1176637Y440443D01*
X1176387Y440359D01*
X1175971D01*
X1175596Y440234D01*
X1175346Y439984D01*
X1175262Y439693D01*
X1175346Y439401D01*
X1175554Y439193D01*
X1175887Y439068D01*
X1176179Y439026D01*
G01X1162678Y454837D02*
Y457337D01*
X1163719D01*
X1164053Y457212D01*
X1164261Y457045D01*
X1164344Y456712D01*
X1164261Y456379D01*
X1164011Y456170D01*
X1163719Y456045D01*
X1162678D01*
G01X1163719D02*
X1164344Y454837D01*
G01X1165903Y455129D02*
X1166194Y454920D01*
X1166528Y454837D01*
X1166861Y454920D01*
X1167153Y455170D01*
X1167361Y455545D01*
X1167444Y455920D01*
Y456379D01*
X1167361Y456754D01*
X1167153Y457087D01*
X1166903Y457254D01*
X1166611Y457337D01*
X1166278Y457254D01*
X1166028Y457087D01*
X1165861Y456837D01*
X1165778Y456504D01*
X1165861Y456212D01*
X1166069Y455920D01*
X1166319Y455754D01*
X1166611Y455712D01*
X1166944Y455795D01*
X1167194Y456004D01*
X1167444Y456379D01*
G01X1168669Y454837D02*
X1169711Y457337D01*
X1170753Y454837D01*
G01X1170378Y455712D02*
X1169044D01*
G01X1172811Y454837D02*
Y457337D01*
X1172311Y456837D01*
G01Y454837D02*
X1173311D01*
G01X1174994Y455337D02*
X1175244Y455045D01*
X1175578Y454879D01*
X1175953Y454837D01*
X1176286Y454879D01*
X1176619Y455087D01*
X1176828Y455337D01*
X1176869Y455587D01*
X1176786Y455879D01*
X1176494Y456087D01*
X1176203Y456170D01*
X1175828D01*
G01X1176203D02*
X1176453Y456295D01*
X1176661Y456504D01*
X1176744Y456754D01*
X1176661Y457004D01*
X1176453Y457212D01*
X1176078Y457337D01*
X1175703Y457295D01*
X1175328Y457129D01*
G01X1164972Y459174D02*
X1162472D01*
Y460215D01*
X1162597Y460549D01*
X1162764Y460757D01*
X1163097Y460840D01*
X1163430Y460757D01*
X1163639Y460507D01*
X1163764Y460215D01*
Y459174D01*
G01Y460215D02*
X1164972Y460840D01*
G01X1164680Y462399D02*
X1164889Y462690D01*
X1164972Y463024D01*
X1164889Y463357D01*
X1164639Y463649D01*
X1164264Y463857D01*
X1163889Y463940D01*
X1163430D01*
X1163055Y463857D01*
X1162722Y463649D01*
X1162555Y463399D01*
X1162472Y463107D01*
X1162555Y462774D01*
X1162722Y462524D01*
X1162972Y462357D01*
X1163305Y462274D01*
X1163597Y462357D01*
X1163889Y462565D01*
X1164055Y462815D01*
X1164097Y463107D01*
X1164014Y463440D01*
X1163805Y463690D01*
X1163430Y463940D01*
G01X1164972Y465165D02*
X1162472Y466207D01*
X1164972Y467249D01*
G01X1164097Y466874D02*
Y465540D01*
G01X1164972Y469307D02*
X1162472D01*
X1162972Y468807D01*
G01X1164972D02*
Y469807D01*
G01X1162889Y471615D02*
X1162639Y471865D01*
X1162514Y472157D01*
X1162472Y472490D01*
X1162555Y472907D01*
X1162764Y473199D01*
X1163014Y473282D01*
X1163264Y473240D01*
X1163472Y473074D01*
X1163889Y472240D01*
X1164180Y471865D01*
X1164597Y471615D01*
X1164972Y471532D01*
Y473282D01*
G01X1168715Y459078D02*
X1166215D01*
Y460119D01*
X1166340Y460453D01*
X1166507Y460661D01*
X1166840Y460744D01*
X1167173Y460661D01*
X1167382Y460411D01*
X1167507Y460119D01*
Y459078D01*
G01Y460119D02*
X1168715Y460744D01*
G01Y463011D02*
X1166215D01*
X1166715Y462511D01*
G01X1168715D02*
Y463511D01*
G01X1166215Y465278D02*
X1168715D01*
Y466944D01*
G01Y469211D02*
X1166215D01*
X1166715Y468711D01*
G01X1168715D02*
Y469711D01*
G01X1167673Y471519D02*
X1167382Y471811D01*
X1167215Y472061D01*
X1167132Y472394D01*
X1167215Y472686D01*
X1167382Y472894D01*
X1167632Y473061D01*
X1167923Y473103D01*
X1168173Y473061D01*
X1168423Y472894D01*
X1168632Y472644D01*
X1168715Y472353D01*
X1168632Y472019D01*
X1168382Y471728D01*
X1168007Y471561D01*
X1167590Y471519D01*
X1167048Y471603D01*
X1166757Y471728D01*
X1166465Y471936D01*
X1166257Y472228D01*
X1166215Y472519D01*
X1166298Y472811D01*
X1166507Y473019D01*
G01X1162678Y451282D02*
Y453782D01*
X1163719D01*
X1164053Y453657D01*
X1164261Y453490D01*
X1164344Y453157D01*
X1164261Y452824D01*
X1164011Y452615D01*
X1163719Y452490D01*
X1162678D01*
G01X1163719D02*
X1164344Y451282D01*
G01X1165903Y451574D02*
X1166194Y451365D01*
X1166528Y451282D01*
X1166861Y451365D01*
X1167153Y451615D01*
X1167361Y451990D01*
X1167444Y452365D01*
Y452824D01*
X1167361Y453199D01*
X1167153Y453532D01*
X1166903Y453699D01*
X1166611Y453782D01*
X1166278Y453699D01*
X1166028Y453532D01*
X1165861Y453282D01*
X1165778Y452949D01*
X1165861Y452657D01*
X1166069Y452365D01*
X1166319Y452199D01*
X1166611Y452157D01*
X1166944Y452240D01*
X1167194Y452449D01*
X1167444Y452824D01*
G01X1168669Y451282D02*
X1169711Y453782D01*
X1170753Y451282D01*
G01X1170378Y452157D02*
X1169044D01*
G01X1172811Y451282D02*
Y453782D01*
X1172311Y453282D01*
G01Y451282D02*
X1173311D01*
G01X1175119Y452324D02*
X1175411Y452615D01*
X1175661Y452782D01*
X1175994Y452865D01*
X1176286Y452782D01*
X1176494Y452615D01*
X1176661Y452365D01*
X1176703Y452074D01*
X1176661Y451824D01*
X1176494Y451574D01*
X1176244Y451365D01*
X1175953Y451282D01*
X1175619Y451365D01*
X1175328Y451615D01*
X1175161Y451990D01*
X1175119Y452407D01*
X1175203Y452949D01*
X1175328Y453240D01*
X1175536Y453532D01*
X1175828Y453740D01*
X1176119Y453782D01*
X1176411Y453699D01*
X1176619Y453490D01*
G01X1209167Y459800D02*
Y462300D01*
X1210208D01*
X1210542Y462175D01*
X1210750Y462008D01*
X1210833Y461675D01*
X1210750Y461342D01*
X1210500Y461133D01*
X1210208Y461008D01*
X1209167D01*
G01X1210208D02*
X1210833Y459800D01*
G01X1212308Y460842D02*
X1212600Y461133D01*
X1212850Y461300D01*
X1213183Y461383D01*
X1213475Y461300D01*
X1213683Y461133D01*
X1213850Y460883D01*
X1213892Y460592D01*
X1213850Y460342D01*
X1213683Y460092D01*
X1213433Y459883D01*
X1213142Y459800D01*
X1212808Y459883D01*
X1212517Y460133D01*
X1212350Y460508D01*
X1212308Y460925D01*
X1212392Y461467D01*
X1212517Y461758D01*
X1212725Y462050D01*
X1213017Y462258D01*
X1213308Y462300D01*
X1213600Y462217D01*
X1213808Y462008D01*
G01X1214950Y462300D02*
X1215533Y459800D01*
X1216200Y462300D01*
X1216867Y459800D01*
X1217450Y462300D01*
G01X1219800Y459800D02*
Y462300D01*
X1218258Y460508D01*
X1220342D01*
G01X1222400Y462300D02*
X1222067Y462217D01*
X1221817Y462008D01*
X1221650Y461758D01*
X1221525Y461425D01*
X1221483Y461050D01*
X1221525Y460675D01*
X1221650Y460342D01*
X1221817Y460092D01*
X1222067Y459883D01*
X1222400Y459800D01*
X1222733Y459883D01*
X1222983Y460092D01*
X1223150Y460342D01*
X1223275Y460675D01*
X1223317Y461050D01*
X1223275Y461425D01*
X1223150Y461758D01*
X1222983Y462008D01*
X1222733Y462217D01*
X1222400Y462300D01*
G01X1172443Y459173D02*
X1169943D01*
Y460214D01*
X1170068Y460548D01*
X1170235Y460756D01*
X1170568Y460839D01*
X1170901Y460756D01*
X1171110Y460506D01*
X1171235Y460214D01*
Y459173D01*
G01Y460214D02*
X1172443Y460839D01*
G01X1172151Y462398D02*
X1172360Y462689D01*
X1172443Y463023D01*
X1172360Y463356D01*
X1172110Y463648D01*
X1171735Y463856D01*
X1171360Y463939D01*
X1170901D01*
X1170526Y463856D01*
X1170193Y463648D01*
X1170026Y463398D01*
X1169943Y463106D01*
X1170026Y462773D01*
X1170193Y462523D01*
X1170443Y462356D01*
X1170776Y462273D01*
X1171068Y462356D01*
X1171360Y462564D01*
X1171526Y462814D01*
X1171568Y463106D01*
X1171485Y463439D01*
X1171276Y463689D01*
X1170901Y463939D01*
G01X1172443Y465164D02*
X1169943Y466206D01*
X1172443Y467248D01*
G01X1171568Y466873D02*
Y465539D01*
G01X1172151Y468598D02*
X1172360Y468889D01*
X1172443Y469223D01*
X1172360Y469556D01*
X1172110Y469848D01*
X1171735Y470056D01*
X1171360Y470139D01*
X1170901D01*
X1170526Y470056D01*
X1170193Y469848D01*
X1170026Y469598D01*
X1169943Y469306D01*
X1170026Y468973D01*
X1170193Y468723D01*
X1170443Y468556D01*
X1170776Y468473D01*
X1171068Y468556D01*
X1171360Y468764D01*
X1171526Y469014D01*
X1171568Y469306D01*
X1171485Y469639D01*
X1171276Y469889D01*
X1170901Y470139D01*
G01X1200155Y425951D02*
X1197655D01*
Y426992D01*
X1197780Y427326D01*
X1197947Y427534D01*
X1198280Y427617D01*
X1198613Y427534D01*
X1198822Y427284D01*
X1198947Y426992D01*
Y425951D01*
G01Y426992D02*
X1200155Y427617D01*
G01X1199863Y429176D02*
X1200072Y429467D01*
X1200155Y429801D01*
X1200072Y430134D01*
X1199822Y430426D01*
X1199447Y430634D01*
X1199072Y430717D01*
X1198613D01*
X1198238Y430634D01*
X1197905Y430426D01*
X1197738Y430176D01*
X1197655Y429884D01*
X1197738Y429551D01*
X1197905Y429301D01*
X1198155Y429134D01*
X1198488Y429051D01*
X1198780Y429134D01*
X1199072Y429342D01*
X1199238Y429592D01*
X1199280Y429884D01*
X1199197Y430217D01*
X1198988Y430467D01*
X1198613Y430717D01*
G01X1200155Y431942D02*
X1197655Y432984D01*
X1200155Y434026D01*
G01X1199280Y433651D02*
Y432317D01*
G01X1198072Y435292D02*
X1197822Y435542D01*
X1197697Y435834D01*
X1197655Y436167D01*
X1197738Y436584D01*
X1197947Y436876D01*
X1198197Y436959D01*
X1198447Y436917D01*
X1198655Y436751D01*
X1199072Y435917D01*
X1199363Y435542D01*
X1199780Y435292D01*
X1200155Y435209D01*
Y436959D01*
G01X1197655Y439184D02*
X1197738Y438851D01*
X1197947Y438601D01*
X1198197Y438434D01*
X1198530Y438309D01*
X1198905Y438267D01*
X1199280Y438309D01*
X1199613Y438434D01*
X1199863Y438601D01*
X1200072Y438851D01*
X1200155Y439184D01*
X1200072Y439517D01*
X1199863Y439767D01*
X1199613Y439934D01*
X1199280Y440059D01*
X1198905Y440101D01*
X1198530Y440059D01*
X1198197Y439934D01*
X1197947Y439767D01*
X1197738Y439517D01*
X1197655Y439184D01*
G01X1177808Y438647D02*
Y441147D01*
X1178849D01*
X1179183Y441022D01*
X1179391Y440855D01*
X1179474Y440522D01*
X1179391Y440189D01*
X1179141Y439980D01*
X1178849Y439855D01*
X1177808D01*
G01X1178849D02*
X1179474Y438647D01*
G01X1180949Y439689D02*
X1181241Y439980D01*
X1181491Y440147D01*
X1181824Y440230D01*
X1182116Y440147D01*
X1182324Y439980D01*
X1182491Y439730D01*
X1182533Y439439D01*
X1182491Y439189D01*
X1182324Y438939D01*
X1182074Y438730D01*
X1181783Y438647D01*
X1181449Y438730D01*
X1181158Y438980D01*
X1180991Y439355D01*
X1180949Y439772D01*
X1181033Y440314D01*
X1181158Y440605D01*
X1181366Y440897D01*
X1181658Y441105D01*
X1181949Y441147D01*
X1182241Y441064D01*
X1182449Y440855D01*
G01X1183591Y441147D02*
X1184174Y438647D01*
X1184841Y441147D01*
X1185508Y438647D01*
X1186091Y441147D01*
G01X1187024Y439147D02*
X1187274Y438855D01*
X1187608Y438689D01*
X1187983Y438647D01*
X1188316Y438689D01*
X1188649Y438897D01*
X1188858Y439147D01*
X1188899Y439397D01*
X1188816Y439689D01*
X1188524Y439897D01*
X1188233Y439980D01*
X1187858D01*
G01X1188233D02*
X1188483Y440105D01*
X1188691Y440314D01*
X1188774Y440564D01*
X1188691Y440814D01*
X1188483Y441022D01*
X1188108Y441147D01*
X1187733Y441105D01*
X1187358Y440939D01*
G01X1191041Y441147D02*
X1190708Y441064D01*
X1190458Y440855D01*
X1190291Y440605D01*
X1190166Y440272D01*
X1190124Y439897D01*
X1190166Y439522D01*
X1190291Y439189D01*
X1190458Y438939D01*
X1190708Y438730D01*
X1191041Y438647D01*
X1191374Y438730D01*
X1191624Y438939D01*
X1191791Y439189D01*
X1191916Y439522D01*
X1191958Y439897D01*
X1191916Y440272D01*
X1191791Y440605D01*
X1191624Y440855D01*
X1191374Y441064D01*
X1191041Y441147D01*
G01X1173666Y442958D02*
X1173333Y443000D01*
X1173041Y443166D01*
X1172791Y443416D01*
X1172624Y443708D01*
X1172541Y444041D01*
Y444375D01*
X1172624Y444708D01*
X1172791Y445000D01*
X1173041Y445250D01*
X1173333Y445416D01*
X1173666Y445458D01*
X1173999Y445416D01*
X1174291Y445250D01*
X1174541Y445000D01*
X1174708Y444708D01*
X1174791Y444375D01*
Y444041D01*
X1174708Y443708D01*
X1174541Y443416D01*
X1174291Y443166D01*
X1173999Y443000D01*
X1173666Y442958D01*
G01X1173999Y443625D02*
X1174499Y442958D01*
G01X1176058Y443250D02*
X1176349Y443041D01*
X1176683Y442958D01*
X1177016Y443041D01*
X1177308Y443291D01*
X1177516Y443666D01*
X1177599Y444041D01*
Y444500D01*
X1177516Y444875D01*
X1177308Y445208D01*
X1177058Y445375D01*
X1176766Y445458D01*
X1176433Y445375D01*
X1176183Y445208D01*
X1176016Y444958D01*
X1175933Y444625D01*
X1176016Y444333D01*
X1176224Y444041D01*
X1176474Y443875D01*
X1176766Y443833D01*
X1177099Y443916D01*
X1177349Y444125D01*
X1177599Y444500D01*
G01X1178824Y442958D02*
X1179866Y445458D01*
X1180908Y442958D01*
G01X1180533Y443833D02*
X1179199D01*
G01X1182174Y445041D02*
X1182424Y445291D01*
X1182716Y445416D01*
X1183049Y445458D01*
X1183466Y445375D01*
X1183758Y445166D01*
X1183841Y444916D01*
X1183799Y444666D01*
X1183633Y444458D01*
X1182799Y444041D01*
X1182424Y443750D01*
X1182174Y443333D01*
X1182091Y442958D01*
X1183841D01*
G01X1208496Y458477D02*
Y456685D01*
X1208663Y456310D01*
X1208996Y456060D01*
X1209413Y455977D01*
X1209830Y456060D01*
X1210163Y456310D01*
X1210330Y456685D01*
Y458477D01*
G01X1211805Y456269D02*
X1212096Y456060D01*
X1212430Y455977D01*
X1212763Y456060D01*
X1213055Y456310D01*
X1213263Y456685D01*
X1213346Y457060D01*
Y457519D01*
X1213263Y457894D01*
X1213055Y458227D01*
X1212805Y458394D01*
X1212513Y458477D01*
X1212180Y458394D01*
X1211930Y458227D01*
X1211763Y457977D01*
X1211680Y457644D01*
X1211763Y457352D01*
X1211971Y457060D01*
X1212221Y456894D01*
X1212513Y456852D01*
X1212846Y456935D01*
X1213096Y457144D01*
X1213346Y457519D01*
G01X1214571Y455977D02*
X1215613Y458477D01*
X1216655Y455977D01*
G01X1216280Y456852D02*
X1214946D01*
G01X1218713Y455977D02*
Y458477D01*
X1218213Y457977D01*
G01Y455977D02*
X1219213D01*
G01X1204053Y451467D02*
X1203928Y451217D01*
X1203845Y450925D01*
Y450592D01*
X1203970Y450217D01*
X1204178Y449925D01*
X1204428Y449717D01*
X1204845Y449550D01*
X1205220Y449508D01*
X1205595Y449592D01*
X1205845Y449717D01*
X1206095Y449967D01*
X1206262Y450258D01*
X1206345Y450550D01*
Y450842D01*
X1206262Y451133D01*
X1206137Y451383D01*
X1205970Y451592D01*
G01X1206345Y453650D02*
X1203845D01*
X1204345Y453150D01*
G01X1206345D02*
Y454150D01*
G01X1203845Y455917D02*
X1206345D01*
Y457583D01*
G01Y459850D02*
X1203845D01*
X1204345Y459350D01*
G01X1206345D02*
Y460350D01*
G01X1203845Y462950D02*
X1203928Y462617D01*
X1204137Y462367D01*
X1204387Y462200D01*
X1204720Y462075D01*
X1205095Y462033D01*
X1205470Y462075D01*
X1205803Y462200D01*
X1206053Y462367D01*
X1206262Y462617D01*
X1206345Y462950D01*
X1206262Y463283D01*
X1206053Y463533D01*
X1205803Y463700D01*
X1205470Y463825D01*
X1205095Y463867D01*
X1204720Y463825D01*
X1204387Y463700D01*
X1204137Y463533D01*
X1203928Y463283D01*
X1203845Y462950D01*
G01X1210102Y454517D02*
X1209852Y454642D01*
X1209560Y454725D01*
X1209227D01*
X1208852Y454600D01*
X1208560Y454392D01*
X1208352Y454142D01*
X1208185Y453725D01*
X1208143Y453350D01*
X1208227Y452975D01*
X1208352Y452725D01*
X1208602Y452475D01*
X1208893Y452308D01*
X1209185Y452225D01*
X1209477D01*
X1209768Y452308D01*
X1210018Y452433D01*
X1210227Y452600D01*
G01X1212285Y452225D02*
Y454725D01*
X1211785Y454225D01*
G01Y452225D02*
X1212785D01*
G01X1215385Y454725D02*
Y452225D01*
G01X1214427Y454725D02*
X1216343D01*
G01X1217568Y452600D02*
X1217818Y452392D01*
X1218110Y452267D01*
X1218485Y452225D01*
X1218860Y452308D01*
X1219152Y452475D01*
X1219360Y452767D01*
X1219402Y453100D01*
X1219318Y453433D01*
X1219110Y453642D01*
X1218818Y453808D01*
X1218527Y453850D01*
X1218235Y453808D01*
X1217860Y453642D01*
X1217985Y454725D01*
X1219110D01*
G01X1220793Y453267D02*
X1221085Y453558D01*
X1221335Y453725D01*
X1221668Y453808D01*
X1221960Y453725D01*
X1222168Y453558D01*
X1222335Y453308D01*
X1222377Y453017D01*
X1222335Y452767D01*
X1222168Y452517D01*
X1221918Y452308D01*
X1221627Y452225D01*
X1221293Y452308D01*
X1221002Y452558D01*
X1220835Y452933D01*
X1220793Y453350D01*
X1220877Y453892D01*
X1221002Y454183D01*
X1221210Y454475D01*
X1221502Y454683D01*
X1221793Y454725D01*
X1222085Y454642D01*
X1222293Y454433D01*
G01X1164277Y449406D02*
X1164027Y449531D01*
X1163735Y449614D01*
X1163402D01*
X1163027Y449489D01*
X1162735Y449281D01*
X1162527Y449031D01*
X1162360Y448614D01*
X1162318Y448239D01*
X1162402Y447864D01*
X1162527Y447614D01*
X1162777Y447364D01*
X1163068Y447197D01*
X1163360Y447114D01*
X1163652D01*
X1163943Y447197D01*
X1164193Y447322D01*
X1164402Y447489D01*
G01X1166460Y447114D02*
Y449614D01*
X1165960Y449114D01*
G01Y447114D02*
X1166960D01*
G01X1168727Y449614D02*
Y447114D01*
X1170393D01*
G01X1172660D02*
Y449614D01*
X1172160Y449114D01*
G01Y447114D02*
X1173160D01*
G01X1174968Y448156D02*
X1175260Y448447D01*
X1175510Y448614D01*
X1175843Y448697D01*
X1176135Y448614D01*
X1176343Y448447D01*
X1176510Y448197D01*
X1176552Y447906D01*
X1176510Y447656D01*
X1176343Y447406D01*
X1176093Y447197D01*
X1175802Y447114D01*
X1175468Y447197D01*
X1175177Y447447D01*
X1175010Y447822D01*
X1174968Y448239D01*
X1175052Y448781D01*
X1175177Y449072D01*
X1175385Y449364D01*
X1175677Y449572D01*
X1175968Y449614D01*
X1176260Y449531D01*
X1176468Y449322D01*
G01X1186749Y447999D02*
X1186624Y447749D01*
X1186541Y447457D01*
Y447124D01*
X1186666Y446749D01*
X1186874Y446457D01*
X1187124Y446249D01*
X1187541Y446082D01*
X1187916Y446040D01*
X1188291Y446124D01*
X1188541Y446249D01*
X1188791Y446499D01*
X1188958Y446790D01*
X1189041Y447082D01*
Y447374D01*
X1188958Y447665D01*
X1188833Y447915D01*
X1188666Y448124D01*
G01X1189041Y450182D02*
X1186541D01*
X1187041Y449682D01*
G01X1189041D02*
Y450682D01*
G01X1186541Y452449D02*
X1189041D01*
Y454115D01*
G01Y456382D02*
X1186541D01*
X1187041Y455882D01*
G01X1189041D02*
Y456882D01*
G01Y459399D02*
X1188499Y459482D01*
X1188041Y459607D01*
X1187624Y459774D01*
X1187166Y459982D01*
X1186541Y460315D01*
Y458649D01*
G01X1190602Y448051D02*
X1190477Y447801D01*
X1190394Y447509D01*
Y447176D01*
X1190519Y446801D01*
X1190727Y446509D01*
X1190977Y446301D01*
X1191394Y446134D01*
X1191769Y446092D01*
X1192144Y446176D01*
X1192394Y446301D01*
X1192644Y446551D01*
X1192811Y446842D01*
X1192894Y447134D01*
Y447426D01*
X1192811Y447717D01*
X1192686Y447967D01*
X1192519Y448176D01*
G01X1192602Y449526D02*
X1192811Y449817D01*
X1192894Y450151D01*
X1192811Y450484D01*
X1192561Y450776D01*
X1192186Y450984D01*
X1191811Y451067D01*
X1191352D01*
X1190977Y450984D01*
X1190644Y450776D01*
X1190477Y450526D01*
X1190394Y450234D01*
X1190477Y449901D01*
X1190644Y449651D01*
X1190894Y449484D01*
X1191227Y449401D01*
X1191519Y449484D01*
X1191811Y449692D01*
X1191977Y449942D01*
X1192019Y450234D01*
X1191936Y450567D01*
X1191727Y450817D01*
X1191352Y451067D01*
G01X1192894Y452292D02*
X1190394Y453334D01*
X1192894Y454376D01*
G01X1192019Y454001D02*
Y452667D01*
G01X1192394Y455517D02*
X1192686Y455767D01*
X1192852Y456101D01*
X1192894Y456476D01*
X1192852Y456809D01*
X1192644Y457142D01*
X1192394Y457351D01*
X1192144Y457392D01*
X1191852Y457309D01*
X1191644Y457017D01*
X1191561Y456726D01*
Y456351D01*
G01Y456726D02*
X1191436Y456976D01*
X1191227Y457184D01*
X1190977Y457267D01*
X1190727Y457184D01*
X1190519Y456976D01*
X1190394Y456601D01*
X1190436Y456226D01*
X1190602Y455851D01*
G01X1176752Y464238D02*
X1176502Y464363D01*
X1176210Y464446D01*
X1175877D01*
X1175502Y464321D01*
X1175210Y464113D01*
X1175002Y463863D01*
X1174835Y463446D01*
X1174793Y463071D01*
X1174877Y462696D01*
X1175002Y462446D01*
X1175252Y462196D01*
X1175543Y462029D01*
X1175835Y461946D01*
X1176127D01*
X1176418Y462029D01*
X1176668Y462154D01*
X1176877Y462321D01*
G01X1178935Y461946D02*
Y464446D01*
X1178435Y463946D01*
G01Y461946D02*
X1179435D01*
G01X1181202Y464446D02*
Y461946D01*
X1182868D01*
G01X1184427Y462238D02*
X1184718Y462029D01*
X1185052Y461946D01*
X1185385Y462029D01*
X1185677Y462279D01*
X1185885Y462654D01*
X1185968Y463029D01*
Y463488D01*
X1185885Y463863D01*
X1185677Y464196D01*
X1185427Y464363D01*
X1185135Y464446D01*
X1184802Y464363D01*
X1184552Y464196D01*
X1184385Y463946D01*
X1184302Y463613D01*
X1184385Y463321D01*
X1184593Y463029D01*
X1184843Y462863D01*
X1185135Y462821D01*
X1185468Y462904D01*
X1185718Y463113D01*
X1185968Y463488D01*
G01X1212508Y431217D02*
X1212383Y430967D01*
X1212300Y430675D01*
Y430342D01*
X1212425Y429967D01*
X1212633Y429675D01*
X1212883Y429467D01*
X1213300Y429300D01*
X1213675Y429258D01*
X1214050Y429342D01*
X1214300Y429467D01*
X1214550Y429717D01*
X1214717Y430008D01*
X1214800Y430300D01*
Y430592D01*
X1214717Y430883D01*
X1214592Y431133D01*
X1214425Y431342D01*
G01X1213758Y432608D02*
X1213467Y432900D01*
X1213300Y433150D01*
X1213217Y433483D01*
X1213300Y433775D01*
X1213467Y433983D01*
X1213717Y434150D01*
X1214008Y434192D01*
X1214258Y434150D01*
X1214508Y433983D01*
X1214717Y433733D01*
X1214800Y433442D01*
X1214717Y433108D01*
X1214467Y432817D01*
X1214092Y432650D01*
X1213675Y432608D01*
X1213133Y432692D01*
X1212842Y432817D01*
X1212550Y433025D01*
X1212342Y433317D01*
X1212300Y433608D01*
X1212383Y433900D01*
X1212592Y434108D01*
G01X1212300Y435250D02*
X1214800Y435833D01*
X1212300Y436500D01*
X1214800Y437167D01*
X1212300Y437750D01*
G01X1214800Y439600D02*
X1212300D01*
X1212800Y439100D01*
G01X1214800D02*
Y440100D01*
G01X1212300Y442700D02*
X1212383Y442367D01*
X1212592Y442117D01*
X1212842Y441950D01*
X1213175Y441825D01*
X1213550Y441783D01*
X1213925Y441825D01*
X1214258Y441950D01*
X1214508Y442117D01*
X1214717Y442367D01*
X1214800Y442700D01*
X1214717Y443033D01*
X1214508Y443283D01*
X1214258Y443450D01*
X1213925Y443575D01*
X1213550Y443617D01*
X1213175Y443575D01*
X1212842Y443450D01*
X1212592Y443283D01*
X1212383Y443033D01*
X1212300Y442700D01*
G01X1204800Y425783D02*
X1202300D01*
Y426617D01*
X1202425Y426950D01*
X1202592Y427200D01*
X1202842Y427408D01*
X1203133Y427575D01*
X1203550Y427617D01*
X1203967Y427575D01*
X1204258Y427408D01*
X1204508Y427200D01*
X1204675Y426950D01*
X1204800Y426617D01*
Y425783D01*
G01X1204467Y428925D02*
X1204675Y429258D01*
X1204800Y429633D01*
Y429967D01*
X1204675Y430300D01*
X1204467Y430550D01*
X1204175Y430675D01*
X1203883Y430592D01*
X1203633Y430383D01*
X1203467Y430008D01*
X1203383Y429508D01*
X1203217Y429217D01*
X1202925Y429092D01*
X1202633Y429175D01*
X1202425Y429383D01*
X1202300Y429675D01*
Y429967D01*
X1202383Y430258D01*
X1202592Y430508D01*
G01X1204508Y432192D02*
X1204717Y432483D01*
X1204800Y432817D01*
X1204717Y433150D01*
X1204467Y433442D01*
X1204092Y433650D01*
X1203717Y433733D01*
X1203258D01*
X1202883Y433650D01*
X1202550Y433442D01*
X1202383Y433192D01*
X1202300Y432900D01*
X1202383Y432567D01*
X1202550Y432317D01*
X1202800Y432150D01*
X1203133Y432067D01*
X1203425Y432150D01*
X1203717Y432358D01*
X1203883Y432608D01*
X1203925Y432900D01*
X1203842Y433233D01*
X1203633Y433483D01*
X1203258Y433733D01*
G01X1204800Y434958D02*
X1202300Y436000D01*
X1204800Y437042D01*
G01X1203925Y436667D02*
Y435333D01*
G01X1203758Y438308D02*
X1203467Y438600D01*
X1203300Y438850D01*
X1203217Y439183D01*
X1203300Y439475D01*
X1203467Y439683D01*
X1203717Y439850D01*
X1204008Y439892D01*
X1204258Y439850D01*
X1204508Y439683D01*
X1204717Y439433D01*
X1204800Y439142D01*
X1204717Y438808D01*
X1204467Y438517D01*
X1204092Y438350D01*
X1203675Y438308D01*
X1203133Y438392D01*
X1202842Y438517D01*
X1202550Y438725D01*
X1202342Y439017D01*
X1202300Y439308D01*
X1202383Y439600D01*
X1202592Y439808D01*
G01X1180013Y434450D02*
Y436950D01*
X1180847D01*
X1181180Y436825D01*
X1181430Y436658D01*
X1181638Y436408D01*
X1181805Y436117D01*
X1181847Y435700D01*
X1181805Y435283D01*
X1181638Y434992D01*
X1181430Y434742D01*
X1181180Y434575D01*
X1180847Y434450D01*
X1180013D01*
G01X1183155Y434783D02*
X1183488Y434575D01*
X1183863Y434450D01*
X1184197D01*
X1184530Y434575D01*
X1184780Y434783D01*
X1184905Y435075D01*
X1184822Y435367D01*
X1184613Y435617D01*
X1184238Y435783D01*
X1183738Y435867D01*
X1183447Y436033D01*
X1183322Y436325D01*
X1183405Y436617D01*
X1183613Y436825D01*
X1183905Y436950D01*
X1184197D01*
X1184488Y436867D01*
X1184738Y436658D01*
G01X1186422Y434742D02*
X1186713Y434533D01*
X1187047Y434450D01*
X1187380Y434533D01*
X1187672Y434783D01*
X1187880Y435158D01*
X1187963Y435533D01*
Y435992D01*
X1187880Y436367D01*
X1187672Y436700D01*
X1187422Y436867D01*
X1187130Y436950D01*
X1186797Y436867D01*
X1186547Y436700D01*
X1186380Y436450D01*
X1186297Y436117D01*
X1186380Y435825D01*
X1186588Y435533D01*
X1186838Y435367D01*
X1187130Y435325D01*
X1187463Y435408D01*
X1187713Y435617D01*
X1187963Y435992D01*
G01X1189188Y434450D02*
X1190230Y436950D01*
X1191272Y434450D01*
G01X1190897Y435325D02*
X1189563D01*
G01X1192413Y434825D02*
X1192663Y434617D01*
X1192955Y434492D01*
X1193330Y434450D01*
X1193705Y434533D01*
X1193997Y434700D01*
X1194205Y434992D01*
X1194247Y435325D01*
X1194163Y435658D01*
X1193955Y435867D01*
X1193663Y436033D01*
X1193372Y436075D01*
X1193080Y436033D01*
X1192705Y435867D01*
X1192830Y436950D01*
X1193955D01*
G01X1206748Y466387D02*
X1206623Y466137D01*
X1206540Y465845D01*
Y465512D01*
X1206665Y465137D01*
X1206873Y464845D01*
X1207123Y464637D01*
X1207540Y464470D01*
X1207915Y464428D01*
X1208290Y464512D01*
X1208540Y464637D01*
X1208790Y464887D01*
X1208957Y465178D01*
X1209040Y465470D01*
Y465762D01*
X1208957Y466053D01*
X1208832Y466303D01*
X1208665Y466512D01*
G01X1209040Y467737D02*
X1206540D01*
Y468778D01*
X1206665Y469112D01*
X1206832Y469320D01*
X1207165Y469403D01*
X1207498Y469320D01*
X1207707Y469070D01*
X1207832Y468778D01*
Y467737D01*
G01Y468778D02*
X1209040Y469403D01*
G01X1208748Y470962D02*
X1208957Y471253D01*
X1209040Y471587D01*
X1208957Y471920D01*
X1208707Y472212D01*
X1208332Y472420D01*
X1207957Y472503D01*
X1207498D01*
X1207123Y472420D01*
X1206790Y472212D01*
X1206623Y471962D01*
X1206540Y471670D01*
X1206623Y471337D01*
X1206790Y471087D01*
X1207040Y470920D01*
X1207373Y470837D01*
X1207665Y470920D01*
X1207957Y471128D01*
X1208123Y471378D01*
X1208165Y471670D01*
X1208082Y472003D01*
X1207873Y472253D01*
X1207498Y472503D01*
G01X1206540Y473520D02*
X1209040Y474103D01*
X1206540Y474770D01*
X1209040Y475437D01*
X1206540Y476020D01*
G01X1209040Y477870D02*
X1206540D01*
X1207040Y477370D01*
G01X1209040D02*
Y478370D01*
G01X1216248Y441527D02*
X1216456Y441277D01*
X1216706Y441110D01*
X1216998Y441027D01*
X1217331Y441110D01*
X1217581Y441277D01*
X1217831Y441527D01*
X1217914Y441860D01*
Y443527D01*
G01X1219473Y441319D02*
X1219764Y441110D01*
X1220098Y441027D01*
X1220431Y441110D01*
X1220723Y441360D01*
X1220931Y441735D01*
X1221014Y442110D01*
Y442569D01*
X1220931Y442944D01*
X1220723Y443277D01*
X1220473Y443444D01*
X1220181Y443527D01*
X1219848Y443444D01*
X1219598Y443277D01*
X1219431Y443027D01*
X1219348Y442694D01*
X1219431Y442402D01*
X1219639Y442110D01*
X1219889Y441944D01*
X1220181Y441902D01*
X1220514Y441985D01*
X1220764Y442194D01*
X1221014Y442569D01*
G01X1222239Y441027D02*
X1223281Y443527D01*
X1224323Y441027D01*
G01X1223948Y441902D02*
X1222614D01*
G01X1225589Y443110D02*
X1225839Y443360D01*
X1226131Y443485D01*
X1226464Y443527D01*
X1226881Y443444D01*
X1227173Y443235D01*
X1227256Y442985D01*
X1227214Y442735D01*
X1227048Y442527D01*
X1226214Y442110D01*
X1225839Y441819D01*
X1225589Y441402D01*
X1225506Y441027D01*
X1227256D01*
G01X1196933Y443800D02*
Y442008D01*
X1197100Y441633D01*
X1197433Y441383D01*
X1197850Y441300D01*
X1198267Y441383D01*
X1198600Y441633D01*
X1198767Y442008D01*
Y443800D01*
G01X1200158Y442342D02*
X1200450Y442633D01*
X1200700Y442800D01*
X1201033Y442883D01*
X1201325Y442800D01*
X1201533Y442633D01*
X1201700Y442383D01*
X1201742Y442092D01*
X1201700Y441842D01*
X1201533Y441592D01*
X1201283Y441383D01*
X1200992Y441300D01*
X1200658Y441383D01*
X1200367Y441633D01*
X1200200Y442008D01*
X1200158Y442425D01*
X1200242Y442967D01*
X1200367Y443258D01*
X1200575Y443550D01*
X1200867Y443758D01*
X1201158Y443800D01*
X1201450Y443717D01*
X1201658Y443508D01*
G01X1202800Y443800D02*
X1203383Y441300D01*
X1204050Y443800D01*
X1204717Y441300D01*
X1205300Y443800D01*
G01X1207150Y441300D02*
Y443800D01*
X1206650Y443300D01*
G01Y441300D02*
X1207650D01*
G01X1209458Y443383D02*
X1209708Y443633D01*
X1210000Y443758D01*
X1210333Y443800D01*
X1210750Y443717D01*
X1211042Y443508D01*
X1211125Y443258D01*
X1211083Y443008D01*
X1210917Y442800D01*
X1210083Y442383D01*
X1209708Y442092D01*
X1209458Y441675D01*
X1209375Y441300D01*
X1211125D01*
G01X1180109Y448606D02*
X1181901D01*
X1182276Y448773D01*
X1182526Y449106D01*
X1182609Y449523D01*
X1182526Y449940D01*
X1182276Y450273D01*
X1181901Y450440D01*
X1180109D01*
G01X1182609Y452623D02*
X1180109D01*
X1180609Y452123D01*
G01X1182609D02*
Y453123D01*
G01X1180109Y454890D02*
X1182609D01*
Y456556D01*
G01X1182109Y457906D02*
X1182401Y458156D01*
X1182567Y458490D01*
X1182609Y458865D01*
X1182567Y459198D01*
X1182359Y459531D01*
X1182109Y459740D01*
X1181859Y459781D01*
X1181567Y459698D01*
X1181359Y459406D01*
X1181276Y459115D01*
Y458740D01*
G01Y459115D02*
X1181151Y459365D01*
X1180942Y459573D01*
X1180692Y459656D01*
X1180442Y459573D01*
X1180234Y459365D01*
X1180109Y458990D01*
X1180151Y458615D01*
X1180317Y458240D01*
G01X1192346Y461060D02*
X1194138D01*
X1194513Y461227D01*
X1194763Y461560D01*
X1194846Y461977D01*
X1194763Y462394D01*
X1194513Y462727D01*
X1194138Y462894D01*
X1192346D01*
G01X1194554Y464369D02*
X1194763Y464660D01*
X1194846Y464994D01*
X1194763Y465327D01*
X1194513Y465619D01*
X1194138Y465827D01*
X1193763Y465910D01*
X1193304D01*
X1192929Y465827D01*
X1192596Y465619D01*
X1192429Y465369D01*
X1192346Y465077D01*
X1192429Y464744D01*
X1192596Y464494D01*
X1192846Y464327D01*
X1193179Y464244D01*
X1193471Y464327D01*
X1193763Y464535D01*
X1193929Y464785D01*
X1193971Y465077D01*
X1193888Y465410D01*
X1193679Y465660D01*
X1193304Y465910D01*
G01X1194846Y467135D02*
X1192346Y468177D01*
X1194846Y469219D01*
G01X1193971Y468844D02*
Y467510D01*
G01X1194346Y470360D02*
X1194638Y470610D01*
X1194804Y470944D01*
X1194846Y471319D01*
X1194804Y471652D01*
X1194596Y471985D01*
X1194346Y472194D01*
X1194096Y472235D01*
X1193804Y472152D01*
X1193596Y471860D01*
X1193513Y471569D01*
Y471194D01*
G01Y471569D02*
X1193388Y471819D01*
X1193179Y472027D01*
X1192929Y472110D01*
X1192679Y472027D01*
X1192471Y471819D01*
X1192346Y471444D01*
X1192388Y471069D01*
X1192554Y470694D01*
G01X1196137Y447996D02*
Y446204D01*
X1196304Y445829D01*
X1196637Y445579D01*
X1197054Y445496D01*
X1197471Y445579D01*
X1197804Y445829D01*
X1197971Y446204D01*
Y447996D01*
G01X1199446Y445788D02*
X1199737Y445579D01*
X1200071Y445496D01*
X1200404Y445579D01*
X1200696Y445829D01*
X1200904Y446204D01*
X1200987Y446579D01*
Y447038D01*
X1200904Y447413D01*
X1200696Y447746D01*
X1200446Y447913D01*
X1200154Y447996D01*
X1199821Y447913D01*
X1199571Y447746D01*
X1199404Y447496D01*
X1199321Y447163D01*
X1199404Y446871D01*
X1199612Y446579D01*
X1199862Y446413D01*
X1200154Y446371D01*
X1200487Y446454D01*
X1200737Y446663D01*
X1200987Y447038D01*
G01X1202212Y445496D02*
X1203254Y447996D01*
X1204296Y445496D01*
G01X1203921Y446371D02*
X1202587D01*
G01X1206854Y445496D02*
Y447996D01*
X1205312Y446204D01*
X1207396D01*
G01X1183620Y469751D02*
Y476751D01*
X1189754Y469751D01*
Y476751D01*
G01X1210959Y468274D02*
Y470774D01*
X1212000D01*
X1212334Y470649D01*
X1212542Y470482D01*
X1212625Y470149D01*
X1212542Y469816D01*
X1212292Y469607D01*
X1212000Y469482D01*
X1210959D01*
G01X1212000D02*
X1212625Y468274D01*
G01X1214184Y468566D02*
X1214475Y468357D01*
X1214809Y468274D01*
X1215142Y468357D01*
X1215434Y468607D01*
X1215642Y468982D01*
X1215725Y469357D01*
Y469816D01*
X1215642Y470191D01*
X1215434Y470524D01*
X1215184Y470691D01*
X1214892Y470774D01*
X1214559Y470691D01*
X1214309Y470524D01*
X1214142Y470274D01*
X1214059Y469941D01*
X1214142Y469649D01*
X1214350Y469357D01*
X1214600Y469191D01*
X1214892Y469149D01*
X1215225Y469232D01*
X1215475Y469441D01*
X1215725Y469816D01*
G01X1216950Y468274D02*
X1217992Y470774D01*
X1219034Y468274D01*
G01X1218659Y469149D02*
X1217325D01*
G01X1221009Y468274D02*
X1221092Y468816D01*
X1221217Y469274D01*
X1221384Y469691D01*
X1221592Y470149D01*
X1221925Y470774D01*
X1220259D01*
G01X1210917Y475500D02*
Y478000D01*
X1211958D01*
X1212292Y477875D01*
X1212500Y477708D01*
X1212583Y477375D01*
X1212500Y477042D01*
X1212250Y476833D01*
X1211958Y476708D01*
X1210917D01*
G01X1211958D02*
X1212583Y475500D01*
G01X1214142Y475792D02*
X1214433Y475583D01*
X1214767Y475500D01*
X1215100Y475583D01*
X1215392Y475833D01*
X1215600Y476208D01*
X1215683Y476583D01*
Y477042D01*
X1215600Y477417D01*
X1215392Y477750D01*
X1215142Y477917D01*
X1214850Y478000D01*
X1214517Y477917D01*
X1214267Y477750D01*
X1214100Y477500D01*
X1214017Y477167D01*
X1214100Y476875D01*
X1214308Y476583D01*
X1214558Y476417D01*
X1214850Y476375D01*
X1215183Y476458D01*
X1215433Y476667D01*
X1215683Y477042D01*
G01X1216908Y475500D02*
X1217950Y478000D01*
X1218992Y475500D01*
G01X1218617Y476375D02*
X1217283D01*
G01X1220133Y475875D02*
X1220383Y475667D01*
X1220675Y475542D01*
X1221050Y475500D01*
X1221425Y475583D01*
X1221717Y475750D01*
X1221925Y476042D01*
X1221967Y476375D01*
X1221883Y476708D01*
X1221675Y476917D01*
X1221383Y477083D01*
X1221092Y477125D01*
X1220800Y477083D01*
X1220425Y476917D01*
X1220550Y478000D01*
X1221675D01*
G01X1210864Y471812D02*
Y474312D01*
X1211905D01*
X1212239Y474187D01*
X1212447Y474020D01*
X1212530Y473687D01*
X1212447Y473354D01*
X1212197Y473145D01*
X1211905Y473020D01*
X1210864D01*
G01X1211905D02*
X1212530Y471812D01*
G01X1214089Y472104D02*
X1214380Y471895D01*
X1214714Y471812D01*
X1215047Y471895D01*
X1215339Y472145D01*
X1215547Y472520D01*
X1215630Y472895D01*
Y473354D01*
X1215547Y473729D01*
X1215339Y474062D01*
X1215089Y474229D01*
X1214797Y474312D01*
X1214464Y474229D01*
X1214214Y474062D01*
X1214047Y473812D01*
X1213964Y473479D01*
X1214047Y473187D01*
X1214255Y472895D01*
X1214505Y472729D01*
X1214797Y472687D01*
X1215130Y472770D01*
X1215380Y472979D01*
X1215630Y473354D01*
G01X1216855Y471812D02*
X1217897Y474312D01*
X1218939Y471812D01*
G01X1218564Y472687D02*
X1217230D01*
G01X1220997Y471812D02*
X1221289Y471854D01*
X1221622Y471979D01*
X1221830Y472187D01*
X1221914Y472479D01*
X1221830Y472770D01*
X1221580Y473020D01*
X1221205Y473145D01*
X1220789D01*
X1220539Y473229D01*
X1220330Y473437D01*
X1220247Y473729D01*
X1220372Y474020D01*
X1220664Y474229D01*
X1220997Y474312D01*
X1221330Y474229D01*
X1221622Y474020D01*
X1221747Y473729D01*
X1221664Y473437D01*
X1221455Y473229D01*
X1221205Y473145D01*
X1220789D01*
X1220414Y473020D01*
X1220164Y472770D01*
X1220080Y472479D01*
X1220164Y472187D01*
X1220372Y471979D01*
X1220705Y471854D01*
X1220997Y471812D01*
G01X1178764Y467715D02*
X1176264D01*
Y468756D01*
X1176389Y469090D01*
X1176556Y469298D01*
X1176889Y469381D01*
X1177222Y469298D01*
X1177431Y469048D01*
X1177556Y468756D01*
Y467715D01*
G01Y468756D02*
X1178764Y469381D01*
G01Y471648D02*
X1176264D01*
X1176764Y471148D01*
G01X1178764D02*
Y472148D01*
G01X1176264Y473915D02*
X1178764D01*
Y475581D01*
G01X1176681Y477056D02*
X1176431Y477306D01*
X1176306Y477598D01*
X1176264Y477931D01*
X1176347Y478348D01*
X1176556Y478640D01*
X1176806Y478723D01*
X1177056Y478681D01*
X1177264Y478515D01*
X1177681Y477681D01*
X1177972Y477306D01*
X1178389Y477056D01*
X1178764Y476973D01*
Y478723D01*
G01X1160435Y481629D02*
Y484129D01*
X1161476D01*
X1161810Y484004D01*
X1162018Y483837D01*
X1162101Y483504D01*
X1162018Y483171D01*
X1161768Y482962D01*
X1161476Y482837D01*
X1160435D01*
G01X1161476D02*
X1162101Y481629D01*
G01X1164368D02*
X1164660Y481671D01*
X1164993Y481796D01*
X1165201Y482004D01*
X1165285Y482296D01*
X1165201Y482587D01*
X1164951Y482837D01*
X1164576Y482962D01*
X1164160D01*
X1163910Y483046D01*
X1163701Y483254D01*
X1163618Y483546D01*
X1163743Y483837D01*
X1164035Y484046D01*
X1164368Y484129D01*
X1164701Y484046D01*
X1164993Y483837D01*
X1165118Y483546D01*
X1165035Y483254D01*
X1164826Y483046D01*
X1164576Y482962D01*
X1164160D01*
X1163785Y482837D01*
X1163535Y482587D01*
X1163451Y482296D01*
X1163535Y482004D01*
X1163743Y481796D01*
X1164076Y481671D01*
X1164368Y481629D01*
G01X1166426D02*
X1167468Y484129D01*
X1168510Y481629D01*
G01X1168135Y482504D02*
X1166801D01*
G01X1170568Y481629D02*
Y484129D01*
X1170068Y483629D01*
G01Y481629D02*
X1171068D01*
G01X1173668D02*
Y484129D01*
X1173168Y483629D01*
G01Y481629D02*
X1174168D01*
G01X1159035Y489829D02*
Y492329D01*
X1160076D01*
X1160410Y492204D01*
X1160618Y492037D01*
X1160701Y491704D01*
X1160618Y491371D01*
X1160368Y491162D01*
X1160076Y491037D01*
X1159035D01*
G01X1160076D02*
X1160701Y489829D01*
G01X1162968D02*
X1163260Y489871D01*
X1163593Y489996D01*
X1163801Y490204D01*
X1163885Y490496D01*
X1163801Y490787D01*
X1163551Y491037D01*
X1163176Y491162D01*
X1162760D01*
X1162510Y491246D01*
X1162301Y491454D01*
X1162218Y491746D01*
X1162343Y492037D01*
X1162635Y492246D01*
X1162968Y492329D01*
X1163301Y492246D01*
X1163593Y492037D01*
X1163718Y491746D01*
X1163635Y491454D01*
X1163426Y491246D01*
X1163176Y491162D01*
X1162760D01*
X1162385Y491037D01*
X1162135Y490787D01*
X1162051Y490496D01*
X1162135Y490204D01*
X1162343Y489996D01*
X1162676Y489871D01*
X1162968Y489829D01*
G01X1165026D02*
X1166068Y492329D01*
X1167110Y489829D01*
G01X1166735Y490704D02*
X1165401D01*
G01X1169168Y489829D02*
Y492329D01*
X1168668Y491829D01*
G01Y489829D02*
X1169668D01*
G01X1172268Y492329D02*
X1171935Y492246D01*
X1171685Y492037D01*
X1171518Y491787D01*
X1171393Y491454D01*
X1171351Y491079D01*
X1171393Y490704D01*
X1171518Y490371D01*
X1171685Y490121D01*
X1171935Y489912D01*
X1172268Y489829D01*
X1172601Y489912D01*
X1172851Y490121D01*
X1173018Y490371D01*
X1173143Y490704D01*
X1173185Y491079D01*
X1173143Y491454D01*
X1173018Y491787D01*
X1172851Y492037D01*
X1172601Y492246D01*
X1172268Y492329D01*
G01X1198047Y514542D02*
X1197797Y514667D01*
X1197505Y514750D01*
X1197172D01*
X1196797Y514625D01*
X1196505Y514417D01*
X1196297Y514167D01*
X1196130Y513750D01*
X1196088Y513375D01*
X1196172Y513000D01*
X1196297Y512750D01*
X1196547Y512500D01*
X1196838Y512333D01*
X1197130Y512250D01*
X1197422D01*
X1197713Y512333D01*
X1197963Y512458D01*
X1198172Y512625D01*
G01X1199438Y513292D02*
X1199730Y513583D01*
X1199980Y513750D01*
X1200313Y513833D01*
X1200605Y513750D01*
X1200813Y513583D01*
X1200980Y513333D01*
X1201022Y513042D01*
X1200980Y512792D01*
X1200813Y512542D01*
X1200563Y512333D01*
X1200272Y512250D01*
X1199938Y512333D01*
X1199647Y512583D01*
X1199480Y512958D01*
X1199438Y513375D01*
X1199522Y513917D01*
X1199647Y514208D01*
X1199855Y514500D01*
X1200147Y514708D01*
X1200438Y514750D01*
X1200730Y514667D01*
X1200938Y514458D01*
G01X1203663Y513583D02*
X1203830Y513708D01*
X1203955Y513917D01*
X1204038Y514208D01*
X1203955Y514458D01*
X1203788Y514625D01*
X1203497Y514750D01*
X1202372D01*
Y512250D01*
X1203747D01*
X1204038Y512417D01*
X1204205Y512667D01*
X1204288Y512958D01*
X1204205Y513250D01*
X1203955Y513500D01*
X1203663Y513583D01*
X1202372D01*
G01X1206430Y512250D02*
Y514750D01*
X1205930Y514250D01*
G01Y512250D02*
X1206930D01*
G01X1211317Y514512D02*
X1211067Y514637D01*
X1210775Y514720D01*
X1210442D01*
X1210067Y514595D01*
X1209775Y514387D01*
X1209567Y514137D01*
X1209400Y513720D01*
X1209358Y513345D01*
X1209442Y512970D01*
X1209567Y512720D01*
X1209817Y512470D01*
X1210108Y512303D01*
X1210400Y512220D01*
X1210692D01*
X1210983Y512303D01*
X1211233Y512428D01*
X1211442Y512595D01*
G01X1212708Y513262D02*
X1213000Y513553D01*
X1213250Y513720D01*
X1213583Y513803D01*
X1213875Y513720D01*
X1214083Y513553D01*
X1214250Y513303D01*
X1214292Y513012D01*
X1214250Y512762D01*
X1214083Y512512D01*
X1213833Y512303D01*
X1213542Y512220D01*
X1213208Y512303D01*
X1212917Y512553D01*
X1212750Y512928D01*
X1212708Y513345D01*
X1212792Y513887D01*
X1212917Y514178D01*
X1213125Y514470D01*
X1213417Y514678D01*
X1213708Y514720D01*
X1214000Y514637D01*
X1214208Y514428D01*
G01X1216933Y513553D02*
X1217100Y513678D01*
X1217225Y513887D01*
X1217308Y514178D01*
X1217225Y514428D01*
X1217058Y514595D01*
X1216767Y514720D01*
X1215642D01*
Y512220D01*
X1217017D01*
X1217308Y512387D01*
X1217475Y512637D01*
X1217558Y512928D01*
X1217475Y513220D01*
X1217225Y513470D01*
X1216933Y513553D01*
X1215642D01*
G01X1218908Y514303D02*
X1219158Y514553D01*
X1219450Y514678D01*
X1219783Y514720D01*
X1220200Y514637D01*
X1220492Y514428D01*
X1220575Y514178D01*
X1220533Y513928D01*
X1220367Y513720D01*
X1219533Y513303D01*
X1219158Y513012D01*
X1218908Y512595D01*
X1218825Y512220D01*
X1220575D01*
G01X1209953Y482310D02*
X1209703Y482435D01*
X1209411Y482518D01*
X1209078D01*
X1208703Y482393D01*
X1208411Y482185D01*
X1208203Y481935D01*
X1208036Y481518D01*
X1207994Y481143D01*
X1208078Y480768D01*
X1208203Y480518D01*
X1208453Y480268D01*
X1208744Y480101D01*
X1209036Y480018D01*
X1209328D01*
X1209619Y480101D01*
X1209869Y480226D01*
X1210078Y480393D01*
G01X1211428Y480310D02*
X1211719Y480101D01*
X1212053Y480018D01*
X1212386Y480101D01*
X1212678Y480351D01*
X1212886Y480726D01*
X1212969Y481101D01*
Y481560D01*
X1212886Y481935D01*
X1212678Y482268D01*
X1212428Y482435D01*
X1212136Y482518D01*
X1211803Y482435D01*
X1211553Y482268D01*
X1211386Y482018D01*
X1211303Y481685D01*
X1211386Y481393D01*
X1211594Y481101D01*
X1211844Y480935D01*
X1212136Y480893D01*
X1212469Y480976D01*
X1212719Y481185D01*
X1212969Y481560D01*
G01X1214194Y480018D02*
X1215236Y482518D01*
X1216278Y480018D01*
G01X1215903Y480893D02*
X1214569D01*
G01X1218336Y480018D02*
Y482518D01*
X1217836Y482018D01*
G01Y480018D02*
X1218836D01*
G01X1160585Y496721D02*
X1160335Y496846D01*
X1160043Y496929D01*
X1159710D01*
X1159335Y496804D01*
X1159043Y496596D01*
X1158835Y496346D01*
X1158668Y495929D01*
X1158626Y495554D01*
X1158710Y495179D01*
X1158835Y494929D01*
X1159085Y494679D01*
X1159376Y494512D01*
X1159668Y494429D01*
X1159960D01*
X1160251Y494512D01*
X1160501Y494637D01*
X1160710Y494804D01*
G01X1162768Y494429D02*
X1163060Y494471D01*
X1163393Y494596D01*
X1163601Y494804D01*
X1163685Y495096D01*
X1163601Y495387D01*
X1163351Y495637D01*
X1162976Y495762D01*
X1162560D01*
X1162310Y495846D01*
X1162101Y496054D01*
X1162018Y496346D01*
X1162143Y496637D01*
X1162435Y496846D01*
X1162768Y496929D01*
X1163101Y496846D01*
X1163393Y496637D01*
X1163518Y496346D01*
X1163435Y496054D01*
X1163226Y495846D01*
X1162976Y495762D01*
X1162560D01*
X1162185Y495637D01*
X1161935Y495387D01*
X1161851Y495096D01*
X1161935Y494804D01*
X1162143Y494596D01*
X1162476Y494471D01*
X1162768Y494429D01*
G01X1164826D02*
X1165868Y496929D01*
X1166910Y494429D01*
G01X1166535Y495304D02*
X1165201D01*
G01X1168968Y494429D02*
Y496929D01*
X1168468Y496429D01*
G01Y494429D02*
X1169468D01*
G01X1172068Y496929D02*
X1171735Y496846D01*
X1171485Y496637D01*
X1171318Y496387D01*
X1171193Y496054D01*
X1171151Y495679D01*
X1171193Y495304D01*
X1171318Y494971D01*
X1171485Y494721D01*
X1171735Y494512D01*
X1172068Y494429D01*
X1172401Y494512D01*
X1172651Y494721D01*
X1172818Y494971D01*
X1172943Y495304D01*
X1172985Y495679D01*
X1172943Y496054D01*
X1172818Y496387D01*
X1172651Y496637D01*
X1172401Y496846D01*
X1172068Y496929D01*
G01X1161585Y487920D02*
X1161335Y488045D01*
X1161043Y488128D01*
X1160710D01*
X1160335Y488003D01*
X1160043Y487795D01*
X1159835Y487545D01*
X1159668Y487128D01*
X1159626Y486753D01*
X1159710Y486378D01*
X1159835Y486128D01*
X1160085Y485878D01*
X1160376Y485711D01*
X1160668Y485628D01*
X1160960D01*
X1161251Y485711D01*
X1161501Y485836D01*
X1161710Y486003D01*
G01X1163768Y485628D02*
X1164060Y485670D01*
X1164393Y485795D01*
X1164601Y486003D01*
X1164685Y486295D01*
X1164601Y486586D01*
X1164351Y486836D01*
X1163976Y486961D01*
X1163560D01*
X1163310Y487045D01*
X1163101Y487253D01*
X1163018Y487545D01*
X1163143Y487836D01*
X1163435Y488045D01*
X1163768Y488128D01*
X1164101Y488045D01*
X1164393Y487836D01*
X1164518Y487545D01*
X1164435Y487253D01*
X1164226Y487045D01*
X1163976Y486961D01*
X1163560D01*
X1163185Y486836D01*
X1162935Y486586D01*
X1162851Y486295D01*
X1162935Y486003D01*
X1163143Y485795D01*
X1163476Y485670D01*
X1163768Y485628D01*
G01X1165826D02*
X1166868Y488128D01*
X1167910Y485628D01*
G01X1167535Y486503D02*
X1166201D01*
G01X1169968Y485628D02*
Y488128D01*
X1169468Y487628D01*
G01Y485628D02*
X1170468D01*
G01X1173068D02*
Y488128D01*
X1172568Y487628D01*
G01Y485628D02*
X1173568D01*
G01X1214707Y495612D02*
X1214582Y495362D01*
X1214499Y495070D01*
Y494737D01*
X1214624Y494362D01*
X1214832Y494070D01*
X1215082Y493862D01*
X1215499Y493695D01*
X1215874Y493653D01*
X1216249Y493737D01*
X1216499Y493862D01*
X1216749Y494112D01*
X1216916Y494403D01*
X1216999Y494695D01*
Y494987D01*
X1216916Y495278D01*
X1216791Y495528D01*
X1216624Y495737D01*
G01X1215957Y497003D02*
X1215666Y497295D01*
X1215499Y497545D01*
X1215416Y497878D01*
X1215499Y498170D01*
X1215666Y498378D01*
X1215916Y498545D01*
X1216207Y498587D01*
X1216457Y498545D01*
X1216707Y498378D01*
X1216916Y498128D01*
X1216999Y497837D01*
X1216916Y497503D01*
X1216666Y497212D01*
X1216291Y497045D01*
X1215874Y497003D01*
X1215332Y497087D01*
X1215041Y497212D01*
X1214749Y497420D01*
X1214541Y497712D01*
X1214499Y498003D01*
X1214582Y498295D01*
X1214791Y498503D01*
G01X1215666Y501228D02*
X1215541Y501395D01*
X1215332Y501520D01*
X1215041Y501603D01*
X1214791Y501520D01*
X1214624Y501353D01*
X1214499Y501062D01*
Y499937D01*
X1216999D01*
Y501312D01*
X1216832Y501603D01*
X1216582Y501770D01*
X1216291Y501853D01*
X1215999Y501770D01*
X1215749Y501520D01*
X1215666Y501228D01*
Y499937D01*
G01X1216999Y503912D02*
X1216457Y503995D01*
X1215999Y504120D01*
X1215582Y504287D01*
X1215124Y504495D01*
X1214499Y504828D01*
Y503162D01*
G01X1220767Y590959D02*
X1220517Y591084D01*
X1220225Y591167D01*
X1219892D01*
X1219517Y591042D01*
X1219225Y590834D01*
X1219017Y590584D01*
X1218850Y590167D01*
X1218808Y589792D01*
X1218892Y589417D01*
X1219017Y589167D01*
X1219267Y588917D01*
X1219558Y588750D01*
X1219850Y588667D01*
X1220142D01*
X1220433Y588750D01*
X1220683Y588875D01*
X1220892Y589042D01*
G01X1222158Y589709D02*
X1222450Y590000D01*
X1222700Y590167D01*
X1223033Y590250D01*
X1223325Y590167D01*
X1223533Y590000D01*
X1223700Y589750D01*
X1223742Y589459D01*
X1223700Y589209D01*
X1223533Y588959D01*
X1223283Y588750D01*
X1222992Y588667D01*
X1222658Y588750D01*
X1222367Y589000D01*
X1222200Y589375D01*
X1222158Y589792D01*
X1222242Y590334D01*
X1222367Y590625D01*
X1222575Y590917D01*
X1222867Y591125D01*
X1223158Y591167D01*
X1223450Y591084D01*
X1223658Y590875D01*
G01X1225008Y588667D02*
X1226050Y591167D01*
X1227092Y588667D01*
G01X1226717Y589542D02*
X1225383D01*
G01X1228358Y590750D02*
X1228608Y591000D01*
X1228900Y591125D01*
X1229233Y591167D01*
X1229650Y591084D01*
X1229942Y590875D01*
X1230025Y590625D01*
X1229983Y590375D01*
X1229817Y590167D01*
X1228983Y589750D01*
X1228608Y589459D01*
X1228358Y589042D01*
X1228275Y588667D01*
X1230025D01*
G01X1229741Y639848D02*
X1197041D01*
Y658548D01*
X1229741D01*
Y639848D01*
G01X1238900Y-55300D02*
Y-58300D01*
X1240900D01*
G01X1243500D02*
Y-55300D01*
X1242900Y-55900D01*
G01Y-58300D02*
X1244100D01*
G01X1249700Y-55300D02*
Y-58300D01*
X1251700D01*
G01X1254300D02*
Y-55300D01*
X1253700Y-55900D01*
G01Y-58300D02*
X1254900D01*
G01X1256950Y-55800D02*
X1257250Y-55500D01*
X1257600Y-55350D01*
X1258000Y-55300D01*
X1258500Y-55400D01*
X1258850Y-55650D01*
X1258950Y-55950D01*
X1258900Y-56250D01*
X1258700Y-56500D01*
X1257700Y-57000D01*
X1257250Y-57350D01*
X1256950Y-57850D01*
X1256850Y-58300D01*
X1258950D01*
G01X1260000Y-59300D02*
X1263000D01*
G01X1264250Y-57950D02*
X1264600Y-58200D01*
X1265000Y-58300D01*
X1265400Y-58200D01*
X1265750Y-57900D01*
X1266000Y-57450D01*
X1266100Y-57000D01*
Y-56450D01*
X1266000Y-56000D01*
X1265750Y-55600D01*
X1265450Y-55400D01*
X1265100Y-55300D01*
X1264700Y-55400D01*
X1264400Y-55600D01*
X1264200Y-55900D01*
X1264100Y-56300D01*
X1264200Y-56650D01*
X1264450Y-57000D01*
X1264750Y-57200D01*
X1265100Y-57250D01*
X1265500Y-57150D01*
X1265800Y-56900D01*
X1266100Y-56450D01*
G01X1267600Y-57850D02*
X1267900Y-58100D01*
X1268250Y-58250D01*
X1268700Y-58300D01*
X1269150Y-58200D01*
X1269500Y-58000D01*
X1269750Y-57650D01*
X1269800Y-57250D01*
X1269700Y-56850D01*
X1269450Y-56600D01*
X1269100Y-56400D01*
X1268750Y-56350D01*
X1268400Y-56400D01*
X1267950Y-56600D01*
X1268100Y-55300D01*
X1269450D01*
G01X1272300Y-58300D02*
X1271900Y-58250D01*
X1271550Y-58050D01*
X1271250Y-57750D01*
X1271050Y-57400D01*
X1270950Y-57000D01*
Y-56600D01*
X1271050Y-56200D01*
X1271250Y-55850D01*
X1271550Y-55550D01*
X1271900Y-55350D01*
X1272300Y-55300D01*
X1272700Y-55350D01*
X1273050Y-55550D01*
X1273350Y-55850D01*
X1273550Y-56200D01*
X1273650Y-56600D01*
Y-57000D01*
X1273550Y-57400D01*
X1273350Y-57750D01*
X1273050Y-58050D01*
X1272700Y-58250D01*
X1272300Y-58300D01*
G01X1275050D02*
Y-55300D01*
G01Y-56750D02*
X1275300Y-56500D01*
X1275550Y-56350D01*
X1275950Y-56300D01*
X1276250Y-56350D01*
X1276600Y-56550D01*
X1276750Y-56850D01*
Y-58300D01*
G01X1278000D02*
Y-56300D01*
G01Y-56850D02*
X1278150Y-56600D01*
X1278400Y-56400D01*
X1278750Y-56300D01*
X1279100Y-56400D01*
X1279350Y-56600D01*
X1279500Y-56850D01*
Y-58300D01*
G01Y-56850D02*
X1279650Y-56600D01*
X1279900Y-56400D01*
X1280250Y-56300D01*
X1280600Y-56400D01*
X1280850Y-56600D01*
X1281000Y-56900D01*
Y-58300D01*
G01X1281600Y-59300D02*
X1284600D01*
G01X1285600Y-58300D02*
Y-55300D01*
X1286600D01*
X1287000Y-55450D01*
X1287300Y-55650D01*
X1287550Y-55950D01*
X1287750Y-56300D01*
X1287800Y-56800D01*
X1287750Y-57300D01*
X1287550Y-57650D01*
X1287300Y-57950D01*
X1287000Y-58150D01*
X1286600Y-58300D01*
X1285600D01*
G01X1227664Y16053D02*
X1227414Y16178D01*
X1227122Y16261D01*
X1226789D01*
X1226414Y16136D01*
X1226122Y15928D01*
X1225914Y15678D01*
X1225747Y15261D01*
X1225705Y14886D01*
X1225789Y14511D01*
X1225914Y14261D01*
X1226164Y14011D01*
X1226455Y13844D01*
X1226747Y13761D01*
X1227039D01*
X1227330Y13844D01*
X1227580Y13969D01*
X1227789Y14136D01*
G01X1229055Y14803D02*
X1229347Y15094D01*
X1229597Y15261D01*
X1229930Y15344D01*
X1230222Y15261D01*
X1230430Y15094D01*
X1230597Y14844D01*
X1230639Y14553D01*
X1230597Y14303D01*
X1230430Y14053D01*
X1230180Y13844D01*
X1229889Y13761D01*
X1229555Y13844D01*
X1229264Y14094D01*
X1229097Y14469D01*
X1229055Y14886D01*
X1229139Y15428D01*
X1229264Y15719D01*
X1229472Y16011D01*
X1229764Y16219D01*
X1230055Y16261D01*
X1230347Y16178D01*
X1230555Y15969D01*
G01X1233197Y15011D02*
X1234030D01*
Y14261D01*
X1233780Y14011D01*
X1233489Y13844D01*
X1233072Y13761D01*
X1232655Y13844D01*
X1232364Y14011D01*
X1232114Y14261D01*
X1231947Y14553D01*
X1231864Y14886D01*
Y15178D01*
X1231947Y15428D01*
X1232114Y15719D01*
X1232364Y15969D01*
X1232614Y16136D01*
X1232947Y16261D01*
X1233239D01*
X1233572Y16178D01*
X1233822Y16011D01*
G01X1236547Y13761D02*
Y16261D01*
X1235005Y14469D01*
X1237089D01*
G01X1234733Y11828D02*
X1234483Y11953D01*
X1234191Y12036D01*
X1233858D01*
X1233483Y11911D01*
X1233191Y11703D01*
X1232983Y11453D01*
X1232816Y11036D01*
X1232774Y10661D01*
X1232858Y10286D01*
X1232983Y10036D01*
X1233233Y9786D01*
X1233524Y9619D01*
X1233816Y9536D01*
X1234108D01*
X1234399Y9619D01*
X1234649Y9744D01*
X1234858Y9911D01*
G01X1236124Y10578D02*
X1236416Y10869D01*
X1236666Y11036D01*
X1236999Y11119D01*
X1237291Y11036D01*
X1237499Y10869D01*
X1237666Y10619D01*
X1237708Y10328D01*
X1237666Y10078D01*
X1237499Y9828D01*
X1237249Y9619D01*
X1236958Y9536D01*
X1236624Y9619D01*
X1236333Y9869D01*
X1236166Y10244D01*
X1236124Y10661D01*
X1236208Y11203D01*
X1236333Y11494D01*
X1236541Y11786D01*
X1236833Y11994D01*
X1237124Y12036D01*
X1237416Y11953D01*
X1237624Y11744D01*
G01X1240266Y10786D02*
X1241099D01*
Y10036D01*
X1240849Y9786D01*
X1240558Y9619D01*
X1240141Y9536D01*
X1239724Y9619D01*
X1239433Y9786D01*
X1239183Y10036D01*
X1239016Y10328D01*
X1238933Y10661D01*
Y10953D01*
X1239016Y11203D01*
X1239183Y11494D01*
X1239433Y11744D01*
X1239683Y11911D01*
X1240016Y12036D01*
X1240308D01*
X1240641Y11953D01*
X1240891Y11786D01*
G01X1242199Y9911D02*
X1242449Y9703D01*
X1242741Y9578D01*
X1243116Y9536D01*
X1243491Y9619D01*
X1243783Y9786D01*
X1243991Y10078D01*
X1244033Y10411D01*
X1243949Y10744D01*
X1243741Y10953D01*
X1243449Y11119D01*
X1243158Y11161D01*
X1242866Y11119D01*
X1242491Y10953D01*
X1242616Y12036D01*
X1243741D01*
G01X1267652Y-23000D02*
Y-19900D01*
X1267192Y-20520D01*
G01Y-23000D02*
X1268112D01*
G01X1271212D02*
Y-19900D01*
X1269794Y-22122D01*
X1271710D01*
G01X1274312Y-23000D02*
Y-19900D01*
X1272894Y-22122D01*
X1274810D01*
G01X1270924Y11083D02*
X1271154Y11393D01*
X1271422Y11548D01*
X1271729Y11600D01*
X1272112Y11497D01*
X1272380Y11238D01*
X1272457Y10928D01*
X1272419Y10618D01*
X1272265Y10360D01*
X1271499Y9843D01*
X1271154Y9482D01*
X1270924Y8965D01*
X1270847Y8500D01*
X1272457D01*
G01X1274752D02*
X1275020Y8552D01*
X1275327Y8707D01*
X1275519Y8965D01*
X1275595Y9327D01*
X1275519Y9688D01*
X1275289Y9998D01*
X1274944Y10153D01*
X1274560D01*
X1274330Y10257D01*
X1274139Y10515D01*
X1274062Y10877D01*
X1274177Y11238D01*
X1274445Y11497D01*
X1274752Y11600D01*
X1275059Y11497D01*
X1275327Y11238D01*
X1275442Y10877D01*
X1275365Y10515D01*
X1275174Y10257D01*
X1274944Y10153D01*
X1274560D01*
X1274215Y9998D01*
X1273985Y9688D01*
X1273909Y9327D01*
X1273985Y8965D01*
X1274177Y8707D01*
X1274484Y8552D01*
X1274752Y8500D01*
G01X1277852D02*
X1278120Y8552D01*
X1278427Y8707D01*
X1278619Y8965D01*
X1278695Y9327D01*
X1278619Y9688D01*
X1278389Y9998D01*
X1278044Y10153D01*
X1277660D01*
X1277430Y10257D01*
X1277239Y10515D01*
X1277162Y10877D01*
X1277277Y11238D01*
X1277545Y11497D01*
X1277852Y11600D01*
X1278159Y11497D01*
X1278427Y11238D01*
X1278542Y10877D01*
X1278465Y10515D01*
X1278274Y10257D01*
X1278044Y10153D01*
X1277660D01*
X1277315Y9998D01*
X1277085Y9688D01*
X1277009Y9327D01*
X1277085Y8965D01*
X1277277Y8707D01*
X1277584Y8552D01*
X1277852Y8500D01*
G01X1270986Y6973D02*
X1295376D01*
Y-18617D01*
X1270986D01*
G01X1270152Y15000D02*
Y18100D01*
X1269692Y17480D01*
G01Y15000D02*
X1270612D01*
G01X1273712D02*
Y18100D01*
X1272294Y15878D01*
X1274210D01*
G01X1276812Y15000D02*
Y18100D01*
X1275394Y15878D01*
X1277310D01*
G01X1270986Y44773D02*
X1295376D01*
Y19183D01*
X1270986D01*
G01X1238576Y92593D02*
Y95093D01*
X1239617D01*
X1239951Y94968D01*
X1240159Y94801D01*
X1240242Y94468D01*
X1240159Y94135D01*
X1239909Y93926D01*
X1239617Y93801D01*
X1238576D01*
G01X1239617D02*
X1240242Y92593D01*
G01X1241717Y93635D02*
X1242009Y93926D01*
X1242259Y94093D01*
X1242592Y94176D01*
X1242884Y94093D01*
X1243092Y93926D01*
X1243259Y93676D01*
X1243301Y93385D01*
X1243259Y93135D01*
X1243092Y92885D01*
X1242842Y92676D01*
X1242551Y92593D01*
X1242217Y92676D01*
X1241926Y92926D01*
X1241759Y93301D01*
X1241717Y93718D01*
X1241801Y94260D01*
X1241926Y94551D01*
X1242134Y94843D01*
X1242426Y95051D01*
X1242717Y95093D01*
X1243009Y95010D01*
X1243217Y94801D01*
G01X1244817Y92593D02*
Y95093D01*
X1246401D01*
G01X1245817Y93885D02*
X1244817D01*
G01X1248001Y92885D02*
X1248292Y92676D01*
X1248626Y92593D01*
X1248959Y92676D01*
X1249251Y92926D01*
X1249459Y93301D01*
X1249542Y93676D01*
Y94135D01*
X1249459Y94510D01*
X1249251Y94843D01*
X1249001Y95010D01*
X1248709Y95093D01*
X1248376Y95010D01*
X1248126Y94843D01*
X1247959Y94593D01*
X1247876Y94260D01*
X1247959Y93968D01*
X1248167Y93676D01*
X1248417Y93510D01*
X1248709Y93468D01*
X1249042Y93551D01*
X1249292Y93760D01*
X1249542Y94135D01*
G01X1253921Y93928D02*
Y96428D01*
X1254962D01*
X1255296Y96303D01*
X1255504Y96136D01*
X1255587Y95803D01*
X1255504Y95470D01*
X1255254Y95261D01*
X1254962Y95136D01*
X1253921D01*
G01X1254962D02*
X1255587Y93928D01*
G01X1257062Y94970D02*
X1257354Y95261D01*
X1257604Y95428D01*
X1257937Y95511D01*
X1258229Y95428D01*
X1258437Y95261D01*
X1258604Y95011D01*
X1258646Y94720D01*
X1258604Y94470D01*
X1258437Y94220D01*
X1258187Y94011D01*
X1257896Y93928D01*
X1257562Y94011D01*
X1257271Y94261D01*
X1257104Y94636D01*
X1257062Y95053D01*
X1257146Y95595D01*
X1257271Y95886D01*
X1257479Y96178D01*
X1257771Y96386D01*
X1258062Y96428D01*
X1258354Y96345D01*
X1258562Y96136D01*
G01X1260162Y93928D02*
Y96428D01*
X1261746D01*
G01X1261162Y95220D02*
X1260162D01*
G01X1264054Y93928D02*
Y96428D01*
X1263554Y95928D01*
G01Y93928D02*
X1264554D01*
G01X1267154D02*
Y96428D01*
X1266654Y95928D01*
G01Y93928D02*
X1267654D01*
G01X1222468Y53622D02*
X1222218Y53747D01*
X1221926Y53830D01*
X1221593D01*
X1221218Y53705D01*
X1220926Y53497D01*
X1220718Y53247D01*
X1220551Y52830D01*
X1220509Y52455D01*
X1220593Y52080D01*
X1220718Y51830D01*
X1220968Y51580D01*
X1221259Y51413D01*
X1221551Y51330D01*
X1221843D01*
X1222134Y51413D01*
X1222384Y51538D01*
X1222593Y51705D01*
G01X1223859Y52372D02*
X1224151Y52663D01*
X1224401Y52830D01*
X1224734Y52913D01*
X1225026Y52830D01*
X1225234Y52663D01*
X1225401Y52413D01*
X1225443Y52122D01*
X1225401Y51872D01*
X1225234Y51622D01*
X1224984Y51413D01*
X1224693Y51330D01*
X1224359Y51413D01*
X1224068Y51663D01*
X1223901Y52038D01*
X1223859Y52455D01*
X1223943Y52997D01*
X1224068Y53288D01*
X1224276Y53580D01*
X1224568Y53788D01*
X1224859Y53830D01*
X1225151Y53747D01*
X1225359Y53538D01*
G01X1228001Y52580D02*
X1228834D01*
Y51830D01*
X1228584Y51580D01*
X1228293Y51413D01*
X1227876Y51330D01*
X1227459Y51413D01*
X1227168Y51580D01*
X1226918Y51830D01*
X1226751Y52122D01*
X1226668Y52455D01*
Y52747D01*
X1226751Y52997D01*
X1226918Y53288D01*
X1227168Y53538D01*
X1227418Y53705D01*
X1227751Y53830D01*
X1228043D01*
X1228376Y53747D01*
X1228626Y53580D01*
G01X1230851Y51330D02*
Y53830D01*
X1230351Y53330D01*
G01Y51330D02*
X1231351D01*
G01X1234908Y51050D02*
X1234658Y51175D01*
X1234366Y51258D01*
X1234033D01*
X1233658Y51133D01*
X1233366Y50925D01*
X1233158Y50675D01*
X1232991Y50258D01*
X1232949Y49883D01*
X1233033Y49508D01*
X1233158Y49258D01*
X1233408Y49008D01*
X1233699Y48841D01*
X1233991Y48758D01*
X1234283D01*
X1234574Y48841D01*
X1234824Y48966D01*
X1235033Y49133D01*
G01X1236299Y49800D02*
X1236591Y50091D01*
X1236841Y50258D01*
X1237174Y50341D01*
X1237466Y50258D01*
X1237674Y50091D01*
X1237841Y49841D01*
X1237883Y49550D01*
X1237841Y49300D01*
X1237674Y49050D01*
X1237424Y48841D01*
X1237133Y48758D01*
X1236799Y48841D01*
X1236508Y49091D01*
X1236341Y49466D01*
X1236299Y49883D01*
X1236383Y50425D01*
X1236508Y50716D01*
X1236716Y51008D01*
X1237008Y51216D01*
X1237299Y51258D01*
X1237591Y51175D01*
X1237799Y50966D01*
G01X1240441Y50008D02*
X1241274D01*
Y49258D01*
X1241024Y49008D01*
X1240733Y48841D01*
X1240316Y48758D01*
X1239899Y48841D01*
X1239608Y49008D01*
X1239358Y49258D01*
X1239191Y49550D01*
X1239108Y49883D01*
Y50175D01*
X1239191Y50425D01*
X1239358Y50716D01*
X1239608Y50966D01*
X1239858Y51133D01*
X1240191Y51258D01*
X1240483D01*
X1240816Y51175D01*
X1241066Y51008D01*
G01X1242499Y50841D02*
X1242749Y51091D01*
X1243041Y51216D01*
X1243374Y51258D01*
X1243791Y51175D01*
X1244083Y50966D01*
X1244166Y50716D01*
X1244124Y50466D01*
X1243958Y50258D01*
X1243124Y49841D01*
X1242749Y49550D01*
X1242499Y49133D01*
X1242416Y48758D01*
X1244166D01*
G01X1247970Y85870D02*
X1247720Y85995D01*
X1247428Y86078D01*
X1247095D01*
X1246720Y85953D01*
X1246428Y85745D01*
X1246220Y85495D01*
X1246053Y85078D01*
X1246011Y84703D01*
X1246095Y84328D01*
X1246220Y84078D01*
X1246470Y83828D01*
X1246761Y83661D01*
X1247053Y83578D01*
X1247345D01*
X1247636Y83661D01*
X1247886Y83786D01*
X1248095Y83953D01*
G01X1249361Y84620D02*
X1249653Y84911D01*
X1249903Y85078D01*
X1250236Y85161D01*
X1250528Y85078D01*
X1250736Y84911D01*
X1250903Y84661D01*
X1250945Y84370D01*
X1250903Y84120D01*
X1250736Y83870D01*
X1250486Y83661D01*
X1250195Y83578D01*
X1249861Y83661D01*
X1249570Y83911D01*
X1249403Y84286D01*
X1249361Y84703D01*
X1249445Y85245D01*
X1249570Y85536D01*
X1249778Y85828D01*
X1250070Y86036D01*
X1250361Y86078D01*
X1250653Y85995D01*
X1250861Y85786D01*
G01X1252461Y83578D02*
Y86078D01*
X1254045D01*
G01X1253461Y84870D02*
X1252461D01*
G01X1255436Y83953D02*
X1255686Y83745D01*
X1255978Y83620D01*
X1256353Y83578D01*
X1256728Y83661D01*
X1257020Y83828D01*
X1257228Y84120D01*
X1257270Y84453D01*
X1257186Y84786D01*
X1256978Y84995D01*
X1256686Y85161D01*
X1256395Y85203D01*
X1256103Y85161D01*
X1255728Y84995D01*
X1255853Y86078D01*
X1256978D01*
G01X1261202Y85846D02*
X1260952Y85971D01*
X1260660Y86054D01*
X1260327D01*
X1259952Y85929D01*
X1259660Y85721D01*
X1259452Y85471D01*
X1259285Y85054D01*
X1259243Y84679D01*
X1259327Y84304D01*
X1259452Y84054D01*
X1259702Y83804D01*
X1259993Y83637D01*
X1260285Y83554D01*
X1260577D01*
X1260868Y83637D01*
X1261118Y83762D01*
X1261327Y83929D01*
G01X1262593Y84596D02*
X1262885Y84887D01*
X1263135Y85054D01*
X1263468Y85137D01*
X1263760Y85054D01*
X1263968Y84887D01*
X1264135Y84637D01*
X1264177Y84346D01*
X1264135Y84096D01*
X1263968Y83846D01*
X1263718Y83637D01*
X1263427Y83554D01*
X1263093Y83637D01*
X1262802Y83887D01*
X1262635Y84262D01*
X1262593Y84679D01*
X1262677Y85221D01*
X1262802Y85512D01*
X1263010Y85804D01*
X1263302Y86012D01*
X1263593Y86054D01*
X1263885Y85971D01*
X1264093Y85762D01*
G01X1265693Y83554D02*
Y86054D01*
X1267277D01*
G01X1266693Y84846D02*
X1265693D01*
G01X1268793Y84596D02*
X1269085Y84887D01*
X1269335Y85054D01*
X1269668Y85137D01*
X1269960Y85054D01*
X1270168Y84887D01*
X1270335Y84637D01*
X1270377Y84346D01*
X1270335Y84096D01*
X1270168Y83846D01*
X1269918Y83637D01*
X1269627Y83554D01*
X1269293Y83637D01*
X1269002Y83887D01*
X1268835Y84262D01*
X1268793Y84679D01*
X1268877Y85221D01*
X1269002Y85512D01*
X1269210Y85804D01*
X1269502Y86012D01*
X1269793Y86054D01*
X1270085Y85971D01*
X1270293Y85762D01*
G01X1270652Y52500D02*
Y55600D01*
X1270192Y54980D01*
G01Y52500D02*
X1271112D01*
G01X1274212D02*
Y55600D01*
X1272794Y53378D01*
X1274710D01*
G01X1277312Y52500D02*
Y55600D01*
X1275894Y53378D01*
X1277810D01*
G01X1273348Y86372D02*
X1273578Y86682D01*
X1273846Y86837D01*
X1274153Y86889D01*
X1274536Y86786D01*
X1274804Y86527D01*
X1274881Y86217D01*
X1274843Y85907D01*
X1274689Y85649D01*
X1273923Y85132D01*
X1273578Y84771D01*
X1273348Y84254D01*
X1273271Y83789D01*
X1274881D01*
G01X1277176D02*
X1277444Y83841D01*
X1277751Y83996D01*
X1277943Y84254D01*
X1278019Y84616D01*
X1277943Y84977D01*
X1277713Y85287D01*
X1277368Y85442D01*
X1276984D01*
X1276754Y85546D01*
X1276563Y85804D01*
X1276486Y86166D01*
X1276601Y86527D01*
X1276869Y86786D01*
X1277176Y86889D01*
X1277483Y86786D01*
X1277751Y86527D01*
X1277866Y86166D01*
X1277789Y85804D01*
X1277598Y85546D01*
X1277368Y85442D01*
X1276984D01*
X1276639Y85287D01*
X1276409Y84977D01*
X1276333Y84616D01*
X1276409Y84254D01*
X1276601Y83996D01*
X1276908Y83841D01*
X1277176Y83789D01*
G01X1280276D02*
X1280544Y83841D01*
X1280851Y83996D01*
X1281043Y84254D01*
X1281119Y84616D01*
X1281043Y84977D01*
X1280813Y85287D01*
X1280468Y85442D01*
X1280084D01*
X1279854Y85546D01*
X1279663Y85804D01*
X1279586Y86166D01*
X1279701Y86527D01*
X1279969Y86786D01*
X1280276Y86889D01*
X1280583Y86786D01*
X1280851Y86527D01*
X1280966Y86166D01*
X1280889Y85804D01*
X1280698Y85546D01*
X1280468Y85442D01*
X1280084D01*
X1279739Y85287D01*
X1279509Y84977D01*
X1279433Y84616D01*
X1279509Y84254D01*
X1279701Y83996D01*
X1280008Y83841D01*
X1280276Y83789D01*
G01X1270986Y82573D02*
X1295376D01*
Y56983D01*
X1270986D01*
G01X1272424Y48583D02*
X1272654Y48893D01*
X1272922Y49048D01*
X1273229Y49100D01*
X1273612Y48997D01*
X1273880Y48738D01*
X1273957Y48428D01*
X1273919Y48118D01*
X1273765Y47860D01*
X1272999Y47343D01*
X1272654Y46982D01*
X1272424Y46465D01*
X1272347Y46000D01*
X1273957D01*
G01X1276252D02*
X1276520Y46052D01*
X1276827Y46207D01*
X1277019Y46465D01*
X1277095Y46827D01*
X1277019Y47188D01*
X1276789Y47498D01*
X1276444Y47653D01*
X1276060D01*
X1275830Y47757D01*
X1275639Y48015D01*
X1275562Y48377D01*
X1275677Y48738D01*
X1275945Y48997D01*
X1276252Y49100D01*
X1276559Y48997D01*
X1276827Y48738D01*
X1276942Y48377D01*
X1276865Y48015D01*
X1276674Y47757D01*
X1276444Y47653D01*
X1276060D01*
X1275715Y47498D01*
X1275485Y47188D01*
X1275409Y46827D01*
X1275485Y46465D01*
X1275677Y46207D01*
X1275984Y46052D01*
X1276252Y46000D01*
G01X1279352D02*
X1279620Y46052D01*
X1279927Y46207D01*
X1280119Y46465D01*
X1280195Y46827D01*
X1280119Y47188D01*
X1279889Y47498D01*
X1279544Y47653D01*
X1279160D01*
X1278930Y47757D01*
X1278739Y48015D01*
X1278662Y48377D01*
X1278777Y48738D01*
X1279045Y48997D01*
X1279352Y49100D01*
X1279659Y48997D01*
X1279927Y48738D01*
X1280042Y48377D01*
X1279965Y48015D01*
X1279774Y47757D01*
X1279544Y47653D01*
X1279160D01*
X1278815Y47498D01*
X1278585Y47188D01*
X1278509Y46827D01*
X1278585Y46465D01*
X1278777Y46207D01*
X1279084Y46052D01*
X1279352Y46000D01*
G01X1234796Y153479D02*
Y146479D01*
X1240130D01*
G01X1253124Y134046D02*
Y136546D01*
X1254165D01*
X1254499Y136421D01*
X1254707Y136254D01*
X1254790Y135921D01*
X1254707Y135588D01*
X1254457Y135379D01*
X1254165Y135254D01*
X1253124D01*
G01X1254165D02*
X1254790Y134046D01*
G01X1256265Y135088D02*
X1256557Y135379D01*
X1256807Y135546D01*
X1257140Y135629D01*
X1257432Y135546D01*
X1257640Y135379D01*
X1257807Y135129D01*
X1257849Y134838D01*
X1257807Y134588D01*
X1257640Y134338D01*
X1257390Y134129D01*
X1257099Y134046D01*
X1256765Y134129D01*
X1256474Y134379D01*
X1256307Y134754D01*
X1256265Y135171D01*
X1256349Y135713D01*
X1256474Y136004D01*
X1256682Y136296D01*
X1256974Y136504D01*
X1257265Y136546D01*
X1257557Y136463D01*
X1257765Y136254D01*
G01X1259365Y134046D02*
Y136546D01*
X1260949D01*
G01X1260365Y135338D02*
X1259365D01*
G01X1262340Y134421D02*
X1262590Y134213D01*
X1262882Y134088D01*
X1263257Y134046D01*
X1263632Y134129D01*
X1263924Y134296D01*
X1264132Y134588D01*
X1264174Y134921D01*
X1264090Y135254D01*
X1263882Y135463D01*
X1263590Y135629D01*
X1263299Y135671D01*
X1263007Y135629D01*
X1262632Y135463D01*
X1262757Y136546D01*
X1263882D01*
G01X1270147Y147817D02*
Y150317D01*
X1271188D01*
X1271522Y150192D01*
X1271730Y150025D01*
X1271813Y149692D01*
X1271730Y149359D01*
X1271480Y149150D01*
X1271188Y149025D01*
X1270147D01*
G01X1271188D02*
X1271813Y147817D01*
G01X1273288Y148859D02*
X1273580Y149150D01*
X1273830Y149317D01*
X1274163Y149400D01*
X1274455Y149317D01*
X1274663Y149150D01*
X1274830Y148900D01*
X1274872Y148609D01*
X1274830Y148359D01*
X1274663Y148109D01*
X1274413Y147900D01*
X1274122Y147817D01*
X1273788Y147900D01*
X1273497Y148150D01*
X1273330Y148525D01*
X1273288Y148942D01*
X1273372Y149484D01*
X1273497Y149775D01*
X1273705Y150067D01*
X1273997Y150275D01*
X1274288Y150317D01*
X1274580Y150234D01*
X1274788Y150025D01*
G01X1276388Y147817D02*
Y150317D01*
X1277972D01*
G01X1277388Y149109D02*
X1276388D01*
G01X1279363Y148317D02*
X1279613Y148025D01*
X1279947Y147859D01*
X1280322Y147817D01*
X1280655Y147859D01*
X1280988Y148067D01*
X1281197Y148317D01*
X1281238Y148567D01*
X1281155Y148859D01*
X1280863Y149067D01*
X1280572Y149150D01*
X1280197D01*
G01X1280572D02*
X1280822Y149275D01*
X1281030Y149484D01*
X1281113Y149734D01*
X1281030Y149984D01*
X1280822Y150192D01*
X1280447Y150317D01*
X1280072Y150275D01*
X1279697Y150109D01*
G01X1270017Y151667D02*
Y154167D01*
X1271058D01*
X1271392Y154042D01*
X1271600Y153875D01*
X1271683Y153542D01*
X1271600Y153209D01*
X1271350Y153000D01*
X1271058Y152875D01*
X1270017D01*
G01X1271058D02*
X1271683Y151667D01*
G01X1273158Y152709D02*
X1273450Y153000D01*
X1273700Y153167D01*
X1274033Y153250D01*
X1274325Y153167D01*
X1274533Y153000D01*
X1274700Y152750D01*
X1274742Y152459D01*
X1274700Y152209D01*
X1274533Y151959D01*
X1274283Y151750D01*
X1273992Y151667D01*
X1273658Y151750D01*
X1273367Y152000D01*
X1273200Y152375D01*
X1273158Y152792D01*
X1273242Y153334D01*
X1273367Y153625D01*
X1273575Y153917D01*
X1273867Y154125D01*
X1274158Y154167D01*
X1274450Y154084D01*
X1274658Y153875D01*
G01X1276258Y151667D02*
Y154167D01*
X1277842D01*
G01X1277258Y152959D02*
X1276258D01*
G01X1280150Y151667D02*
Y154167D01*
X1279650Y153667D01*
G01Y151667D02*
X1280650D01*
G01X1255917Y101600D02*
Y104100D01*
X1256958D01*
X1257292Y103975D01*
X1257500Y103808D01*
X1257583Y103475D01*
X1257500Y103142D01*
X1257250Y102933D01*
X1256958Y102808D01*
X1255917D01*
G01X1256958D02*
X1257583Y101600D01*
G01X1259058Y102642D02*
X1259350Y102933D01*
X1259600Y103100D01*
X1259933Y103183D01*
X1260225Y103100D01*
X1260433Y102933D01*
X1260600Y102683D01*
X1260642Y102392D01*
X1260600Y102142D01*
X1260433Y101892D01*
X1260183Y101683D01*
X1259892Y101600D01*
X1259558Y101683D01*
X1259267Y101933D01*
X1259100Y102308D01*
X1259058Y102725D01*
X1259142Y103267D01*
X1259267Y103558D01*
X1259475Y103850D01*
X1259767Y104058D01*
X1260058Y104100D01*
X1260350Y104017D01*
X1260558Y103808D01*
G01X1262158Y101600D02*
Y104100D01*
X1263742D01*
G01X1263158Y102892D02*
X1262158D01*
G01X1265258Y102642D02*
X1265550Y102933D01*
X1265800Y103100D01*
X1266133Y103183D01*
X1266425Y103100D01*
X1266633Y102933D01*
X1266800Y102683D01*
X1266842Y102392D01*
X1266800Y102142D01*
X1266633Y101892D01*
X1266383Y101683D01*
X1266092Y101600D01*
X1265758Y101683D01*
X1265467Y101933D01*
X1265300Y102308D01*
X1265258Y102725D01*
X1265342Y103267D01*
X1265467Y103558D01*
X1265675Y103850D01*
X1265967Y104058D01*
X1266258Y104100D01*
X1266550Y104017D01*
X1266758Y103808D01*
G01X1238856Y96587D02*
Y99087D01*
X1239897D01*
X1240231Y98962D01*
X1240439Y98795D01*
X1240522Y98462D01*
X1240439Y98129D01*
X1240189Y97920D01*
X1239897Y97795D01*
X1238856D01*
G01X1239897D02*
X1240522Y96587D01*
G01X1241997Y97629D02*
X1242289Y97920D01*
X1242539Y98087D01*
X1242872Y98170D01*
X1243164Y98087D01*
X1243372Y97920D01*
X1243539Y97670D01*
X1243581Y97379D01*
X1243539Y97129D01*
X1243372Y96879D01*
X1243122Y96670D01*
X1242831Y96587D01*
X1242497Y96670D01*
X1242206Y96920D01*
X1242039Y97295D01*
X1241997Y97712D01*
X1242081Y98254D01*
X1242206Y98545D01*
X1242414Y98837D01*
X1242706Y99045D01*
X1242997Y99087D01*
X1243289Y99004D01*
X1243497Y98795D01*
G01X1245097Y96587D02*
Y99087D01*
X1246681D01*
G01X1246097Y97879D02*
X1245097D01*
G01X1248906Y96587D02*
X1248989Y97129D01*
X1249114Y97587D01*
X1249281Y98004D01*
X1249489Y98462D01*
X1249822Y99087D01*
X1248156D01*
G01X1254060Y97688D02*
Y100188D01*
X1255101D01*
X1255435Y100063D01*
X1255643Y99896D01*
X1255726Y99563D01*
X1255643Y99230D01*
X1255393Y99021D01*
X1255101Y98896D01*
X1254060D01*
G01X1255101D02*
X1255726Y97688D01*
G01X1257201Y98730D02*
X1257493Y99021D01*
X1257743Y99188D01*
X1258076Y99271D01*
X1258368Y99188D01*
X1258576Y99021D01*
X1258743Y98771D01*
X1258785Y98480D01*
X1258743Y98230D01*
X1258576Y97980D01*
X1258326Y97771D01*
X1258035Y97688D01*
X1257701Y97771D01*
X1257410Y98021D01*
X1257243Y98396D01*
X1257201Y98813D01*
X1257285Y99355D01*
X1257410Y99646D01*
X1257618Y99938D01*
X1257910Y100146D01*
X1258201Y100188D01*
X1258493Y100105D01*
X1258701Y99896D01*
G01X1260301Y97688D02*
Y100188D01*
X1261885D01*
G01X1261301Y98980D02*
X1260301D01*
G01X1264193Y97688D02*
X1264485Y97730D01*
X1264818Y97855D01*
X1265026Y98063D01*
X1265110Y98355D01*
X1265026Y98646D01*
X1264776Y98896D01*
X1264401Y99021D01*
X1263985D01*
X1263735Y99105D01*
X1263526Y99313D01*
X1263443Y99605D01*
X1263568Y99896D01*
X1263860Y100105D01*
X1264193Y100188D01*
X1264526Y100105D01*
X1264818Y99896D01*
X1264943Y99605D01*
X1264860Y99313D01*
X1264651Y99105D01*
X1264401Y99021D01*
X1263985D01*
X1263610Y98896D01*
X1263360Y98646D01*
X1263276Y98355D01*
X1263360Y98063D01*
X1263568Y97855D01*
X1263901Y97730D01*
X1264193Y97688D01*
G01X1239046Y100488D02*
Y102988D01*
X1240087D01*
X1240421Y102863D01*
X1240629Y102696D01*
X1240712Y102363D01*
X1240629Y102030D01*
X1240379Y101821D01*
X1240087Y101696D01*
X1239046D01*
G01X1240087D02*
X1240712Y100488D01*
G01X1242187Y101530D02*
X1242479Y101821D01*
X1242729Y101988D01*
X1243062Y102071D01*
X1243354Y101988D01*
X1243562Y101821D01*
X1243729Y101571D01*
X1243771Y101280D01*
X1243729Y101030D01*
X1243562Y100780D01*
X1243312Y100571D01*
X1243021Y100488D01*
X1242687Y100571D01*
X1242396Y100821D01*
X1242229Y101196D01*
X1242187Y101613D01*
X1242271Y102155D01*
X1242396Y102446D01*
X1242604Y102738D01*
X1242896Y102946D01*
X1243187Y102988D01*
X1243479Y102905D01*
X1243687Y102696D01*
G01X1245287Y100488D02*
Y102988D01*
X1246871D01*
G01X1246287Y101780D02*
X1245287D01*
G01X1249179Y100488D02*
Y102988D01*
X1248679Y102488D01*
G01Y100488D02*
X1249679D01*
G01X1252279Y102988D02*
X1251946Y102905D01*
X1251696Y102696D01*
X1251529Y102446D01*
X1251404Y102113D01*
X1251362Y101738D01*
X1251404Y101363D01*
X1251529Y101030D01*
X1251696Y100780D01*
X1251946Y100571D01*
X1252279Y100488D01*
X1252612Y100571D01*
X1252862Y100780D01*
X1253029Y101030D01*
X1253154Y101363D01*
X1253196Y101738D01*
X1253154Y102113D01*
X1253029Y102446D01*
X1252862Y102696D01*
X1252612Y102905D01*
X1252279Y102988D01*
G01X1269199Y143698D02*
Y146198D01*
X1270240D01*
X1270574Y146073D01*
X1270782Y145906D01*
X1270865Y145573D01*
X1270782Y145240D01*
X1270532Y145031D01*
X1270240Y144906D01*
X1269199D01*
G01X1270240D02*
X1270865Y143698D01*
G01X1272340Y144740D02*
X1272632Y145031D01*
X1272882Y145198D01*
X1273215Y145281D01*
X1273507Y145198D01*
X1273715Y145031D01*
X1273882Y144781D01*
X1273924Y144490D01*
X1273882Y144240D01*
X1273715Y143990D01*
X1273465Y143781D01*
X1273174Y143698D01*
X1272840Y143781D01*
X1272549Y144031D01*
X1272382Y144406D01*
X1272340Y144823D01*
X1272424Y145365D01*
X1272549Y145656D01*
X1272757Y145948D01*
X1273049Y146156D01*
X1273340Y146198D01*
X1273632Y146115D01*
X1273840Y145906D01*
G01X1275440Y143698D02*
Y146198D01*
X1277024D01*
G01X1276440Y144990D02*
X1275440D01*
G01X1279832Y143698D02*
Y146198D01*
X1278290Y144406D01*
X1280374D01*
G01X1253927Y137441D02*
Y139941D01*
X1254968D01*
X1255302Y139816D01*
X1255510Y139649D01*
X1255593Y139316D01*
X1255510Y138983D01*
X1255260Y138774D01*
X1254968Y138649D01*
X1253927D01*
G01X1254968D02*
X1255593Y137441D01*
G01X1257068Y138483D02*
X1257360Y138774D01*
X1257610Y138941D01*
X1257943Y139024D01*
X1258235Y138941D01*
X1258443Y138774D01*
X1258610Y138524D01*
X1258652Y138233D01*
X1258610Y137983D01*
X1258443Y137733D01*
X1258193Y137524D01*
X1257902Y137441D01*
X1257568Y137524D01*
X1257277Y137774D01*
X1257110Y138149D01*
X1257068Y138566D01*
X1257152Y139108D01*
X1257277Y139399D01*
X1257485Y139691D01*
X1257777Y139899D01*
X1258068Y139941D01*
X1258360Y139858D01*
X1258568Y139649D01*
G01X1260168Y137441D02*
Y139941D01*
X1261752D01*
G01X1261168Y138733D02*
X1260168D01*
G01X1263268Y139524D02*
X1263518Y139774D01*
X1263810Y139899D01*
X1264143Y139941D01*
X1264560Y139858D01*
X1264852Y139649D01*
X1264935Y139399D01*
X1264893Y139149D01*
X1264727Y138941D01*
X1263893Y138524D01*
X1263518Y138233D01*
X1263268Y137816D01*
X1263185Y137441D01*
X1264935D01*
G01X1246366Y130321D02*
Y132821D01*
X1247407D01*
X1247741Y132696D01*
X1247949Y132529D01*
X1248032Y132196D01*
X1247949Y131863D01*
X1247699Y131654D01*
X1247407Y131529D01*
X1246366D01*
G01X1247407D02*
X1248032Y130321D01*
G01X1249507Y131363D02*
X1249799Y131654D01*
X1250049Y131821D01*
X1250382Y131904D01*
X1250674Y131821D01*
X1250882Y131654D01*
X1251049Y131404D01*
X1251091Y131113D01*
X1251049Y130863D01*
X1250882Y130613D01*
X1250632Y130404D01*
X1250341Y130321D01*
X1250007Y130404D01*
X1249716Y130654D01*
X1249549Y131029D01*
X1249507Y131446D01*
X1249591Y131988D01*
X1249716Y132279D01*
X1249924Y132571D01*
X1250216Y132779D01*
X1250507Y132821D01*
X1250799Y132738D01*
X1251007Y132529D01*
G01X1252149Y132821D02*
X1252732Y130321D01*
X1253399Y132821D01*
X1254066Y130321D01*
X1254649Y132821D01*
G01X1255707Y132404D02*
X1255957Y132654D01*
X1256249Y132779D01*
X1256582Y132821D01*
X1256999Y132738D01*
X1257291Y132529D01*
X1257374Y132279D01*
X1257332Y132029D01*
X1257166Y131821D01*
X1256332Y131404D01*
X1255957Y131113D01*
X1255707Y130696D01*
X1255624Y130321D01*
X1257374D01*
G01X1258891Y130613D02*
X1259182Y130404D01*
X1259516Y130321D01*
X1259849Y130404D01*
X1260141Y130654D01*
X1260349Y131029D01*
X1260432Y131404D01*
Y131863D01*
X1260349Y132238D01*
X1260141Y132571D01*
X1259891Y132738D01*
X1259599Y132821D01*
X1259266Y132738D01*
X1259016Y132571D01*
X1258849Y132321D01*
X1258766Y131988D01*
X1258849Y131696D01*
X1259057Y131404D01*
X1259307Y131238D01*
X1259599Y131196D01*
X1259932Y131279D01*
X1260182Y131488D01*
X1260432Y131863D01*
G01X1272667Y95767D02*
Y98267D01*
X1273708D01*
X1274042Y98142D01*
X1274250Y97975D01*
X1274333Y97642D01*
X1274250Y97309D01*
X1274000Y97100D01*
X1273708Y96975D01*
X1272667D01*
G01X1273708D02*
X1274333Y95767D01*
G01X1276517D02*
X1276600Y96309D01*
X1276725Y96767D01*
X1276892Y97184D01*
X1277100Y97642D01*
X1277433Y98267D01*
X1275767D01*
G01X1278908Y95767D02*
Y98267D01*
X1280492D01*
G01X1279908Y97059D02*
X1278908D01*
G01X1282800Y95767D02*
Y98267D01*
X1282300Y97767D01*
G01Y95767D02*
X1283300D01*
G01X1285900Y98267D02*
X1285567Y98184D01*
X1285317Y97975D01*
X1285150Y97725D01*
X1285025Y97392D01*
X1284983Y97017D01*
X1285025Y96642D01*
X1285150Y96309D01*
X1285317Y96059D01*
X1285567Y95850D01*
X1285900Y95767D01*
X1286233Y95850D01*
X1286483Y96059D01*
X1286650Y96309D01*
X1286775Y96642D01*
X1286817Y97017D01*
X1286775Y97392D01*
X1286650Y97725D01*
X1286483Y97975D01*
X1286233Y98184D01*
X1285900Y98267D01*
G01X1254452Y129298D02*
X1254202Y129423D01*
X1253910Y129506D01*
X1253577D01*
X1253202Y129381D01*
X1252910Y129173D01*
X1252702Y128923D01*
X1252535Y128506D01*
X1252493Y128131D01*
X1252577Y127756D01*
X1252702Y127506D01*
X1252952Y127256D01*
X1253243Y127089D01*
X1253535Y127006D01*
X1253827D01*
X1254118Y127089D01*
X1254368Y127214D01*
X1254577Y127381D01*
G01X1255843Y128048D02*
X1256135Y128339D01*
X1256385Y128506D01*
X1256718Y128589D01*
X1257010Y128506D01*
X1257218Y128339D01*
X1257385Y128089D01*
X1257427Y127798D01*
X1257385Y127548D01*
X1257218Y127298D01*
X1256968Y127089D01*
X1256677Y127006D01*
X1256343Y127089D01*
X1256052Y127339D01*
X1255885Y127714D01*
X1255843Y128131D01*
X1255927Y128673D01*
X1256052Y128964D01*
X1256260Y129256D01*
X1256552Y129464D01*
X1256843Y129506D01*
X1257135Y129423D01*
X1257343Y129214D01*
G01X1258943Y127006D02*
Y129506D01*
X1260527D01*
G01X1259943Y128298D02*
X1258943D01*
G01X1262835Y127006D02*
Y129506D01*
X1262335Y129006D01*
G01Y127006D02*
X1263335D01*
G01X1260797Y111416D02*
X1262589D01*
X1262964Y111583D01*
X1263214Y111916D01*
X1263297Y112333D01*
X1263214Y112750D01*
X1262964Y113083D01*
X1262589Y113250D01*
X1260797D01*
G01X1262255Y114641D02*
X1261964Y114933D01*
X1261797Y115183D01*
X1261714Y115516D01*
X1261797Y115808D01*
X1261964Y116016D01*
X1262214Y116183D01*
X1262505Y116225D01*
X1262755Y116183D01*
X1263005Y116016D01*
X1263214Y115766D01*
X1263297Y115475D01*
X1263214Y115141D01*
X1262964Y114850D01*
X1262589Y114683D01*
X1262172Y114641D01*
X1261630Y114725D01*
X1261339Y114850D01*
X1261047Y115058D01*
X1260839Y115350D01*
X1260797Y115641D01*
X1260880Y115933D01*
X1261089Y116141D01*
G01X1263297Y117741D02*
X1260797D01*
Y119325D01*
G01X1262005Y118741D02*
Y117741D01*
G01X1263297Y121633D02*
X1260797D01*
X1261297Y121133D01*
G01X1263297D02*
Y122133D01*
G01X1276310Y114972D02*
Y122344D01*
G01X1264110Y114973D02*
Y122361D01*
G01X1223708Y145999D02*
X1223583Y145749D01*
X1223500Y145457D01*
Y145124D01*
X1223625Y144749D01*
X1223833Y144457D01*
X1224083Y144249D01*
X1224500Y144082D01*
X1224875Y144040D01*
X1225250Y144124D01*
X1225500Y144249D01*
X1225750Y144499D01*
X1225917Y144790D01*
X1226000Y145082D01*
Y145374D01*
X1225917Y145665D01*
X1225792Y145915D01*
X1225625Y146124D01*
G01X1226000Y148182D02*
X1225958Y148474D01*
X1225833Y148807D01*
X1225625Y149015D01*
X1225333Y149099D01*
X1225042Y149015D01*
X1224792Y148765D01*
X1224667Y148390D01*
Y147974D01*
X1224583Y147724D01*
X1224375Y147515D01*
X1224083Y147432D01*
X1223792Y147557D01*
X1223583Y147849D01*
X1223500Y148182D01*
X1223583Y148515D01*
X1223792Y148807D01*
X1224083Y148932D01*
X1224375Y148849D01*
X1224583Y148640D01*
X1224667Y148390D01*
Y147974D01*
X1224792Y147599D01*
X1225042Y147349D01*
X1225333Y147265D01*
X1225625Y147349D01*
X1225833Y147557D01*
X1225958Y147890D01*
X1226000Y148182D01*
G01Y152115D02*
Y150449D01*
X1223500D01*
Y152115D01*
G01X1224708Y151449D02*
Y150449D01*
G01X1226000Y154382D02*
X1223500D01*
X1224000Y153882D01*
G01X1226000D02*
Y154882D01*
G01X1223500Y157482D02*
X1223583Y157149D01*
X1223792Y156899D01*
X1224042Y156732D01*
X1224375Y156607D01*
X1224750Y156565D01*
X1225125Y156607D01*
X1225458Y156732D01*
X1225708Y156899D01*
X1225917Y157149D01*
X1226000Y157482D01*
X1225917Y157815D01*
X1225708Y158065D01*
X1225458Y158232D01*
X1225125Y158357D01*
X1224750Y158399D01*
X1224375Y158357D01*
X1224042Y158232D01*
X1223792Y158065D01*
X1223583Y157815D01*
X1223500Y157482D01*
G01X1226488Y98924D02*
Y100049D01*
X1225655Y101424D01*
G01X1227321D02*
X1226488Y100049D01*
G01X1228796Y99966D02*
X1229088Y100257D01*
X1229338Y100424D01*
X1229671Y100507D01*
X1229963Y100424D01*
X1230171Y100257D01*
X1230338Y100007D01*
X1230380Y99716D01*
X1230338Y99466D01*
X1230171Y99216D01*
X1229921Y99007D01*
X1229630Y98924D01*
X1229296Y99007D01*
X1229005Y99257D01*
X1228838Y99632D01*
X1228796Y100049D01*
X1228880Y100591D01*
X1229005Y100882D01*
X1229213Y101174D01*
X1229505Y101382D01*
X1229796Y101424D01*
X1230088Y101341D01*
X1230296Y101132D01*
G01X1231896Y98924D02*
Y101424D01*
X1233480D01*
G01X1232896Y100216D02*
X1231896D01*
G01X1235788Y98924D02*
Y101424D01*
X1235288Y100924D01*
G01Y98924D02*
X1236288D01*
G01X1229463Y122320D02*
Y124391D01*
G01X1242849Y105887D02*
Y103919D01*
X1229463D01*
Y105913D01*
G01Y124391D02*
X1242849D01*
Y122269D01*
G01X1219775Y129424D02*
X1222275D01*
G01X1227025Y131674D02*
Y134924D01*
X1223525D01*
G01X1234963Y133927D02*
Y131427D01*
G01X1237213Y138677D02*
X1240463D01*
Y135177D01*
G01X1237213Y126677D02*
X1240463D01*
Y130177D01*
G01X1220108Y146318D02*
X1219983Y146068D01*
X1219900Y145776D01*
Y145443D01*
X1220025Y145068D01*
X1220233Y144776D01*
X1220483Y144568D01*
X1220900Y144401D01*
X1221275Y144359D01*
X1221650Y144443D01*
X1221900Y144568D01*
X1222150Y144818D01*
X1222317Y145109D01*
X1222400Y145401D01*
Y145693D01*
X1222317Y145984D01*
X1222192Y146234D01*
X1222025Y146443D01*
G01X1222400Y148501D02*
X1222358Y148793D01*
X1222233Y149126D01*
X1222025Y149334D01*
X1221733Y149418D01*
X1221442Y149334D01*
X1221192Y149084D01*
X1221067Y148709D01*
Y148293D01*
X1220983Y148043D01*
X1220775Y147834D01*
X1220483Y147751D01*
X1220192Y147876D01*
X1219983Y148168D01*
X1219900Y148501D01*
X1219983Y148834D01*
X1220192Y149126D01*
X1220483Y149251D01*
X1220775Y149168D01*
X1220983Y148959D01*
X1221067Y148709D01*
Y148293D01*
X1221192Y147918D01*
X1221442Y147668D01*
X1221733Y147584D01*
X1222025Y147668D01*
X1222233Y147876D01*
X1222358Y148209D01*
X1222400Y148501D01*
G01Y152434D02*
Y150768D01*
X1219900D01*
Y152434D01*
G01X1221108Y151768D02*
Y150768D01*
G01X1222400Y154701D02*
X1219900D01*
X1220400Y154201D01*
G01X1222400D02*
Y155201D01*
G01Y157801D02*
X1219900D01*
X1220400Y157301D01*
G01X1222400D02*
Y158301D01*
G01X1227798Y145985D02*
X1227673Y145735D01*
X1227590Y145443D01*
Y145110D01*
X1227715Y144735D01*
X1227923Y144443D01*
X1228173Y144235D01*
X1228590Y144068D01*
X1228965Y144026D01*
X1229340Y144110D01*
X1229590Y144235D01*
X1229840Y144485D01*
X1230007Y144776D01*
X1230090Y145068D01*
Y145360D01*
X1230007Y145651D01*
X1229882Y145901D01*
X1229715Y146110D01*
G01X1228007Y147376D02*
X1227757Y147626D01*
X1227632Y147918D01*
X1227590Y148251D01*
X1227673Y148668D01*
X1227882Y148960D01*
X1228132Y149043D01*
X1228382Y149001D01*
X1228590Y148835D01*
X1229007Y148001D01*
X1229298Y147626D01*
X1229715Y147376D01*
X1230090Y147293D01*
Y149043D01*
G01X1228007Y150476D02*
X1227757Y150726D01*
X1227632Y151018D01*
X1227590Y151351D01*
X1227673Y151768D01*
X1227882Y152060D01*
X1228132Y152143D01*
X1228382Y152101D01*
X1228590Y151935D01*
X1229007Y151101D01*
X1229298Y150726D01*
X1229715Y150476D01*
X1230090Y150393D01*
Y152143D01*
G01X1227590Y153118D02*
X1230090Y153701D01*
X1227590Y154368D01*
X1230090Y155035D01*
X1227590Y155618D01*
G01X1230090Y157468D02*
X1227590D01*
X1228090Y156968D01*
G01X1230090D02*
Y157968D01*
G01X1228007Y159776D02*
X1227757Y160026D01*
X1227632Y160318D01*
X1227590Y160651D01*
X1227673Y161068D01*
X1227882Y161360D01*
X1228132Y161443D01*
X1228382Y161401D01*
X1228590Y161235D01*
X1229007Y160401D01*
X1229298Y160026D01*
X1229715Y159776D01*
X1230090Y159693D01*
Y161443D01*
G01X1236310Y157373D02*
Y155707D01*
X1233810D01*
Y157373D01*
G01X1235018Y156707D02*
Y155707D01*
G01X1233810Y158723D02*
X1235602D01*
X1235977Y158890D01*
X1236227Y159223D01*
X1236310Y159640D01*
X1236227Y160057D01*
X1235977Y160390D01*
X1235602Y160557D01*
X1233810D01*
G01X1236310Y162740D02*
X1236268Y163032D01*
X1236143Y163365D01*
X1235935Y163573D01*
X1235643Y163657D01*
X1235352Y163573D01*
X1235102Y163323D01*
X1234977Y162948D01*
Y162532D01*
X1234893Y162282D01*
X1234685Y162073D01*
X1234393Y161990D01*
X1234102Y162115D01*
X1233893Y162407D01*
X1233810Y162740D01*
X1233893Y163073D01*
X1234102Y163365D01*
X1234393Y163490D01*
X1234685Y163407D01*
X1234893Y163198D01*
X1234977Y162948D01*
Y162532D01*
X1235102Y162157D01*
X1235352Y161907D01*
X1235643Y161823D01*
X1235935Y161907D01*
X1236143Y162115D01*
X1236268Y162448D01*
X1236310Y162740D01*
G01Y165048D02*
X1233810D01*
Y166632D01*
G01X1235018Y166048D02*
Y165048D01*
G01X1234227Y168148D02*
X1233977Y168398D01*
X1233852Y168690D01*
X1233810Y169023D01*
X1233893Y169440D01*
X1234102Y169732D01*
X1234352Y169815D01*
X1234602Y169773D01*
X1234810Y169607D01*
X1235227Y168773D01*
X1235518Y168398D01*
X1235935Y168148D01*
X1236310Y168065D01*
Y169815D01*
G01X1246867Y152614D02*
Y155114D01*
X1248451D01*
G01X1247867Y153906D02*
X1246867D01*
G01X1251092Y153947D02*
X1251259Y154072D01*
X1251384Y154281D01*
X1251467Y154572D01*
X1251384Y154822D01*
X1251217Y154989D01*
X1250926Y155114D01*
X1249801D01*
Y152614D01*
X1251176D01*
X1251467Y152781D01*
X1251634Y153031D01*
X1251717Y153322D01*
X1251634Y153614D01*
X1251384Y153864D01*
X1251092Y153947D01*
X1249801D01*
G01X1253151Y152906D02*
X1253442Y152697D01*
X1253776Y152614D01*
X1254109Y152697D01*
X1254401Y152947D01*
X1254609Y153322D01*
X1254692Y153697D01*
Y154156D01*
X1254609Y154531D01*
X1254401Y154864D01*
X1254151Y155031D01*
X1253859Y155114D01*
X1253526Y155031D01*
X1253276Y154864D01*
X1253109Y154614D01*
X1253026Y154281D01*
X1253109Y153989D01*
X1253317Y153697D01*
X1253567Y153531D01*
X1253859Y153489D01*
X1254192Y153572D01*
X1254442Y153781D01*
X1254692Y154156D01*
G01X1257792Y152614D02*
X1256126D01*
Y155114D01*
X1257792D01*
G01X1257126Y153906D02*
X1256126D01*
G01X1260059Y152614D02*
Y155114D01*
X1259559Y154614D01*
G01Y152614D02*
X1260559D01*
G01X1284000Y185500D02*
X1267000D01*
Y192200D01*
G01X1269059Y181769D02*
Y184269D01*
X1270100D01*
X1270434Y184144D01*
X1270642Y183977D01*
X1270725Y183644D01*
X1270642Y183311D01*
X1270392Y183102D01*
X1270100Y182977D01*
X1269059D01*
G01X1270100D02*
X1270725Y181769D01*
G01X1272200Y183852D02*
X1272450Y184102D01*
X1272742Y184227D01*
X1273075Y184269D01*
X1273492Y184186D01*
X1273784Y183977D01*
X1273867Y183727D01*
X1273825Y183477D01*
X1273659Y183269D01*
X1272825Y182852D01*
X1272450Y182561D01*
X1272200Y182144D01*
X1272117Y181769D01*
X1273867D01*
G01X1275175Y182144D02*
X1275425Y181936D01*
X1275717Y181811D01*
X1276092Y181769D01*
X1276467Y181852D01*
X1276759Y182019D01*
X1276967Y182311D01*
X1277009Y182644D01*
X1276925Y182977D01*
X1276717Y183186D01*
X1276425Y183352D01*
X1276134Y183394D01*
X1275842Y183352D01*
X1275467Y183186D01*
X1275592Y184269D01*
X1276717D01*
G01X1277942D02*
X1278525Y181769D01*
X1279192Y184269D01*
X1279859Y181769D01*
X1280442Y184269D01*
G01X1282292Y181769D02*
Y184269D01*
X1281792Y183769D01*
G01Y181769D02*
X1282792D01*
G01X1284600Y183852D02*
X1284850Y184102D01*
X1285142Y184227D01*
X1285475Y184269D01*
X1285892Y184186D01*
X1286184Y183977D01*
X1286267Y183727D01*
X1286225Y183477D01*
X1286059Y183269D01*
X1285225Y182852D01*
X1284850Y182561D01*
X1284600Y182144D01*
X1284517Y181769D01*
X1286267D01*
G01X1288409D02*
X1288492Y182311D01*
X1288617Y182769D01*
X1288784Y183186D01*
X1288992Y183644D01*
X1289325Y184269D01*
X1287659D01*
G01X1268863Y177808D02*
Y180308D01*
X1269904D01*
X1270238Y180183D01*
X1270446Y180016D01*
X1270529Y179683D01*
X1270446Y179350D01*
X1270196Y179141D01*
X1269904Y179016D01*
X1268863D01*
G01X1269904D02*
X1270529Y177808D01*
G01X1272004Y179891D02*
X1272254Y180141D01*
X1272546Y180266D01*
X1272879Y180308D01*
X1273296Y180225D01*
X1273588Y180016D01*
X1273671Y179766D01*
X1273629Y179516D01*
X1273463Y179308D01*
X1272629Y178891D01*
X1272254Y178600D01*
X1272004Y178183D01*
X1271921Y177808D01*
X1273671D01*
G01X1274979Y178183D02*
X1275229Y177975D01*
X1275521Y177850D01*
X1275896Y177808D01*
X1276271Y177891D01*
X1276563Y178058D01*
X1276771Y178350D01*
X1276813Y178683D01*
X1276729Y179016D01*
X1276521Y179225D01*
X1276229Y179391D01*
X1275938Y179433D01*
X1275646Y179391D01*
X1275271Y179225D01*
X1275396Y180308D01*
X1276521D01*
G01X1277746D02*
X1278329Y177808D01*
X1278996Y180308D01*
X1279663Y177808D01*
X1280246Y180308D01*
G01X1282096Y177808D02*
Y180308D01*
X1281596Y179808D01*
G01Y177808D02*
X1282596D01*
G01X1284404Y179891D02*
X1284654Y180141D01*
X1284946Y180266D01*
X1285279Y180308D01*
X1285696Y180225D01*
X1285988Y180016D01*
X1286071Y179766D01*
X1286029Y179516D01*
X1285863Y179308D01*
X1285029Y178891D01*
X1284654Y178600D01*
X1284404Y178183D01*
X1284321Y177808D01*
X1286071D01*
G01X1288296D02*
X1288588Y177850D01*
X1288921Y177975D01*
X1289129Y178183D01*
X1289213Y178475D01*
X1289129Y178766D01*
X1288879Y179016D01*
X1288504Y179141D01*
X1288088D01*
X1287838Y179225D01*
X1287629Y179433D01*
X1287546Y179725D01*
X1287671Y180016D01*
X1287963Y180225D01*
X1288296Y180308D01*
X1288629Y180225D01*
X1288921Y180016D01*
X1289046Y179725D01*
X1288963Y179433D01*
X1288754Y179225D01*
X1288504Y179141D01*
X1288088D01*
X1287713Y179016D01*
X1287463Y178766D01*
X1287379Y178475D01*
X1287463Y178183D01*
X1287671Y177975D01*
X1288004Y177850D01*
X1288296Y177808D01*
G01X1247857Y157470D02*
Y159970D01*
X1248898D01*
X1249232Y159845D01*
X1249440Y159678D01*
X1249523Y159345D01*
X1249440Y159012D01*
X1249190Y158803D01*
X1248898Y158678D01*
X1247857D01*
G01X1248898D02*
X1249523Y157470D01*
G01X1251790D02*
X1252082Y157512D01*
X1252415Y157637D01*
X1252623Y157845D01*
X1252707Y158137D01*
X1252623Y158428D01*
X1252373Y158678D01*
X1251998Y158803D01*
X1251582D01*
X1251332Y158887D01*
X1251123Y159095D01*
X1251040Y159387D01*
X1251165Y159678D01*
X1251457Y159887D01*
X1251790Y159970D01*
X1252123Y159887D01*
X1252415Y159678D01*
X1252540Y159387D01*
X1252457Y159095D01*
X1252248Y158887D01*
X1251998Y158803D01*
X1251582D01*
X1251207Y158678D01*
X1250957Y158428D01*
X1250873Y158137D01*
X1250957Y157845D01*
X1251165Y157637D01*
X1251498Y157512D01*
X1251790Y157470D01*
G01X1254098D02*
Y159970D01*
X1255682D01*
G01X1255098Y158762D02*
X1254098D01*
G01X1257198Y159553D02*
X1257448Y159803D01*
X1257740Y159928D01*
X1258073Y159970D01*
X1258490Y159887D01*
X1258782Y159678D01*
X1258865Y159428D01*
X1258823Y159178D01*
X1258657Y158970D01*
X1257823Y158553D01*
X1257448Y158262D01*
X1257198Y157845D01*
X1257115Y157470D01*
X1258865D01*
G01X1260173Y157845D02*
X1260423Y157637D01*
X1260715Y157512D01*
X1261090Y157470D01*
X1261465Y157553D01*
X1261757Y157720D01*
X1261965Y158012D01*
X1262007Y158345D01*
X1261923Y158678D01*
X1261715Y158887D01*
X1261423Y159053D01*
X1261132Y159095D01*
X1260840Y159053D01*
X1260465Y158887D01*
X1260590Y159970D01*
X1261715D01*
G01X1250489Y180985D02*
Y183485D01*
X1251530D01*
X1251864Y183360D01*
X1252072Y183193D01*
X1252155Y182860D01*
X1252072Y182527D01*
X1251822Y182318D01*
X1251530Y182193D01*
X1250489D01*
G01X1251530D02*
X1252155Y180985D01*
G01X1254422D02*
Y183485D01*
X1253922Y182985D01*
G01Y180985D02*
X1254922D01*
G01X1256272Y183485D02*
X1256855Y180985D01*
X1257522Y183485D01*
X1258189Y180985D01*
X1258772Y183485D01*
G01X1259830Y183068D02*
X1260080Y183318D01*
X1260372Y183443D01*
X1260705Y183485D01*
X1261122Y183402D01*
X1261414Y183193D01*
X1261497Y182943D01*
X1261455Y182693D01*
X1261289Y182485D01*
X1260455Y182068D01*
X1260080Y181777D01*
X1259830Y181360D01*
X1259747Y180985D01*
X1261497D01*
G01X1264222D02*
Y183485D01*
X1262680Y181693D01*
X1264764D01*
G01X1248157Y162550D02*
Y165050D01*
X1249198D01*
X1249532Y164925D01*
X1249740Y164758D01*
X1249823Y164425D01*
X1249740Y164092D01*
X1249490Y163883D01*
X1249198Y163758D01*
X1248157D01*
G01X1249198D02*
X1249823Y162550D01*
G01X1252090D02*
X1252382Y162592D01*
X1252715Y162717D01*
X1252923Y162925D01*
X1253007Y163217D01*
X1252923Y163508D01*
X1252673Y163758D01*
X1252298Y163883D01*
X1251882D01*
X1251632Y163967D01*
X1251423Y164175D01*
X1251340Y164467D01*
X1251465Y164758D01*
X1251757Y164967D01*
X1252090Y165050D01*
X1252423Y164967D01*
X1252715Y164758D01*
X1252840Y164467D01*
X1252757Y164175D01*
X1252548Y163967D01*
X1252298Y163883D01*
X1251882D01*
X1251507Y163758D01*
X1251257Y163508D01*
X1251173Y163217D01*
X1251257Y162925D01*
X1251465Y162717D01*
X1251798Y162592D01*
X1252090Y162550D01*
G01X1254398D02*
Y165050D01*
X1255982D01*
G01X1255398Y163842D02*
X1254398D01*
G01X1257498Y164633D02*
X1257748Y164883D01*
X1258040Y165008D01*
X1258373Y165050D01*
X1258790Y164967D01*
X1259082Y164758D01*
X1259165Y164508D01*
X1259123Y164258D01*
X1258957Y164050D01*
X1258123Y163633D01*
X1257748Y163342D01*
X1257498Y162925D01*
X1257415Y162550D01*
X1259165D01*
G01X1261307D02*
X1261390Y163092D01*
X1261515Y163550D01*
X1261682Y163967D01*
X1261890Y164425D01*
X1262223Y165050D01*
X1260557D01*
G01X1249997Y171970D02*
Y174470D01*
X1251038D01*
X1251372Y174345D01*
X1251580Y174178D01*
X1251663Y173845D01*
X1251580Y173512D01*
X1251330Y173303D01*
X1251038Y173178D01*
X1249997D01*
G01X1251038D02*
X1251663Y171970D01*
G01X1253930D02*
X1254222Y172012D01*
X1254555Y172137D01*
X1254763Y172345D01*
X1254847Y172637D01*
X1254763Y172928D01*
X1254513Y173178D01*
X1254138Y173303D01*
X1253722D01*
X1253472Y173387D01*
X1253263Y173595D01*
X1253180Y173887D01*
X1253305Y174178D01*
X1253597Y174387D01*
X1253930Y174470D01*
X1254263Y174387D01*
X1254555Y174178D01*
X1254680Y173887D01*
X1254597Y173595D01*
X1254388Y173387D01*
X1254138Y173303D01*
X1253722D01*
X1253347Y173178D01*
X1253097Y172928D01*
X1253013Y172637D01*
X1253097Y172345D01*
X1253305Y172137D01*
X1253638Y172012D01*
X1253930Y171970D01*
G01X1256238D02*
Y174470D01*
X1257822D01*
G01X1257238Y173262D02*
X1256238D01*
G01X1259338Y174053D02*
X1259588Y174303D01*
X1259880Y174428D01*
X1260213Y174470D01*
X1260630Y174387D01*
X1260922Y174178D01*
X1261005Y173928D01*
X1260963Y173678D01*
X1260797Y173470D01*
X1259963Y173053D01*
X1259588Y172762D01*
X1259338Y172345D01*
X1259255Y171970D01*
X1261005D01*
G01X1262522Y172262D02*
X1262813Y172053D01*
X1263147Y171970D01*
X1263480Y172053D01*
X1263772Y172303D01*
X1263980Y172678D01*
X1264063Y173053D01*
Y173512D01*
X1263980Y173887D01*
X1263772Y174220D01*
X1263522Y174387D01*
X1263230Y174470D01*
X1262897Y174387D01*
X1262647Y174220D01*
X1262480Y173970D01*
X1262397Y173637D01*
X1262480Y173345D01*
X1262688Y173053D01*
X1262938Y172887D01*
X1263230Y172845D01*
X1263563Y172928D01*
X1263813Y173137D01*
X1264063Y173512D01*
G01X1232581Y178841D02*
X1230081D01*
Y179882D01*
X1230206Y180216D01*
X1230373Y180424D01*
X1230706Y180507D01*
X1231039Y180424D01*
X1231248Y180174D01*
X1231373Y179882D01*
Y178841D01*
G01Y179882D02*
X1232581Y180507D01*
G01X1230498Y181982D02*
X1230248Y182232D01*
X1230123Y182524D01*
X1230081Y182857D01*
X1230164Y183274D01*
X1230373Y183566D01*
X1230623Y183649D01*
X1230873Y183607D01*
X1231081Y183441D01*
X1231498Y182607D01*
X1231789Y182232D01*
X1232206Y181982D01*
X1232581Y181899D01*
Y183649D01*
G01X1230081Y185874D02*
X1232581D01*
G01X1230081Y184916D02*
Y186832D01*
G01X1232581Y189474D02*
X1230081D01*
X1231873Y187932D01*
Y190016D01*
G01X1230498Y191282D02*
X1230248Y191532D01*
X1230123Y191824D01*
X1230081Y192157D01*
X1230164Y192574D01*
X1230373Y192866D01*
X1230623Y192949D01*
X1230873Y192907D01*
X1231081Y192741D01*
X1231498Y191907D01*
X1231789Y191532D01*
X1232206Y191282D01*
X1232581Y191199D01*
Y192949D01*
G01X1237035Y195148D02*
X1234535D01*
Y196189D01*
X1234660Y196523D01*
X1234827Y196731D01*
X1235160Y196814D01*
X1235493Y196731D01*
X1235702Y196481D01*
X1235827Y196189D01*
Y195148D01*
G01Y196189D02*
X1237035Y196814D01*
G01Y199081D02*
X1236993Y199373D01*
X1236868Y199706D01*
X1236660Y199914D01*
X1236368Y199998D01*
X1236077Y199914D01*
X1235827Y199664D01*
X1235702Y199289D01*
Y198873D01*
X1235618Y198623D01*
X1235410Y198414D01*
X1235118Y198331D01*
X1234827Y198456D01*
X1234618Y198748D01*
X1234535Y199081D01*
X1234618Y199414D01*
X1234827Y199706D01*
X1235118Y199831D01*
X1235410Y199748D01*
X1235618Y199539D01*
X1235702Y199289D01*
Y198873D01*
X1235827Y198498D01*
X1236077Y198248D01*
X1236368Y198164D01*
X1236660Y198248D01*
X1236868Y198456D01*
X1236993Y198789D01*
X1237035Y199081D01*
G01X1235785Y202431D02*
Y203264D01*
X1236535D01*
X1236785Y203014D01*
X1236952Y202723D01*
X1237035Y202306D01*
X1236952Y201889D01*
X1236785Y201598D01*
X1236535Y201348D01*
X1236243Y201181D01*
X1235910Y201098D01*
X1235618D01*
X1235368Y201181D01*
X1235077Y201348D01*
X1234827Y201598D01*
X1234660Y201848D01*
X1234535Y202181D01*
Y202473D01*
X1234618Y202806D01*
X1234785Y203056D01*
G01X1237035Y205281D02*
X1234535D01*
X1235035Y204781D01*
G01X1237035D02*
Y205781D01*
G01X1240886Y191109D02*
X1238386D01*
Y192150D01*
X1238511Y192484D01*
X1238678Y192692D01*
X1239011Y192775D01*
X1239344Y192692D01*
X1239553Y192442D01*
X1239678Y192150D01*
Y191109D01*
G01Y192150D02*
X1240886Y192775D01*
G01Y195042D02*
X1240844Y195334D01*
X1240719Y195667D01*
X1240511Y195875D01*
X1240219Y195959D01*
X1239928Y195875D01*
X1239678Y195625D01*
X1239553Y195250D01*
Y194834D01*
X1239469Y194584D01*
X1239261Y194375D01*
X1238969Y194292D01*
X1238678Y194417D01*
X1238469Y194709D01*
X1238386Y195042D01*
X1238469Y195375D01*
X1238678Y195667D01*
X1238969Y195792D01*
X1239261Y195709D01*
X1239469Y195500D01*
X1239553Y195250D01*
Y194834D01*
X1239678Y194459D01*
X1239928Y194209D01*
X1240219Y194125D01*
X1240511Y194209D01*
X1240719Y194417D01*
X1240844Y194750D01*
X1240886Y195042D01*
G01X1239636Y198392D02*
Y199225D01*
X1240386D01*
X1240636Y198975D01*
X1240803Y198684D01*
X1240886Y198267D01*
X1240803Y197850D01*
X1240636Y197559D01*
X1240386Y197309D01*
X1240094Y197142D01*
X1239761Y197059D01*
X1239469D01*
X1239219Y197142D01*
X1238928Y197309D01*
X1238678Y197559D01*
X1238511Y197809D01*
X1238386Y198142D01*
Y198434D01*
X1238469Y198767D01*
X1238636Y199017D01*
G01X1238803Y200450D02*
X1238553Y200700D01*
X1238428Y200992D01*
X1238386Y201325D01*
X1238469Y201742D01*
X1238678Y202034D01*
X1238928Y202117D01*
X1239178Y202075D01*
X1239386Y201909D01*
X1239803Y201075D01*
X1240094Y200700D01*
X1240511Y200450D01*
X1240886Y200367D01*
Y202117D01*
G01X1240511Y203425D02*
X1240719Y203675D01*
X1240844Y203967D01*
X1240886Y204342D01*
X1240803Y204717D01*
X1240636Y205009D01*
X1240344Y205217D01*
X1240011Y205259D01*
X1239678Y205175D01*
X1239469Y204967D01*
X1239303Y204675D01*
X1239261Y204384D01*
X1239303Y204092D01*
X1239469Y203717D01*
X1238386Y203842D01*
Y204967D01*
G01X1246336Y184178D02*
X1243836D01*
Y185219D01*
X1243961Y185553D01*
X1244128Y185761D01*
X1244461Y185844D01*
X1244794Y185761D01*
X1245003Y185511D01*
X1245128Y185219D01*
Y184178D01*
G01Y185219D02*
X1246336Y185844D01*
G01Y188111D02*
X1246294Y188403D01*
X1246169Y188736D01*
X1245961Y188944D01*
X1245669Y189028D01*
X1245378Y188944D01*
X1245128Y188694D01*
X1245003Y188319D01*
Y187903D01*
X1244919Y187653D01*
X1244711Y187444D01*
X1244419Y187361D01*
X1244128Y187486D01*
X1243919Y187778D01*
X1243836Y188111D01*
X1243919Y188444D01*
X1244128Y188736D01*
X1244419Y188861D01*
X1244711Y188778D01*
X1244919Y188569D01*
X1245003Y188319D01*
Y187903D01*
X1245128Y187528D01*
X1245378Y187278D01*
X1245669Y187194D01*
X1245961Y187278D01*
X1246169Y187486D01*
X1246294Y187819D01*
X1246336Y188111D01*
G01X1245086Y191461D02*
Y192294D01*
X1245836D01*
X1246086Y192044D01*
X1246253Y191753D01*
X1246336Y191336D01*
X1246253Y190919D01*
X1246086Y190628D01*
X1245836Y190378D01*
X1245544Y190211D01*
X1245211Y190128D01*
X1244919D01*
X1244669Y190211D01*
X1244378Y190378D01*
X1244128Y190628D01*
X1243961Y190878D01*
X1243836Y191211D01*
Y191503D01*
X1243919Y191836D01*
X1244086Y192086D01*
G01X1244253Y193519D02*
X1244003Y193769D01*
X1243878Y194061D01*
X1243836Y194394D01*
X1243919Y194811D01*
X1244128Y195103D01*
X1244378Y195186D01*
X1244628Y195144D01*
X1244836Y194978D01*
X1245253Y194144D01*
X1245544Y193769D01*
X1245961Y193519D01*
X1246336Y193436D01*
Y195186D01*
G01Y197911D02*
X1243836D01*
X1245628Y196369D01*
Y198453D01*
G01X1237081Y179341D02*
X1234581D01*
Y180382D01*
X1234706Y180716D01*
X1234873Y180924D01*
X1235206Y181007D01*
X1235539Y180924D01*
X1235748Y180674D01*
X1235873Y180382D01*
Y179341D01*
G01Y180382D02*
X1237081Y181007D01*
G01X1234998Y182482D02*
X1234748Y182732D01*
X1234623Y183024D01*
X1234581Y183357D01*
X1234664Y183774D01*
X1234873Y184066D01*
X1235123Y184149D01*
X1235373Y184107D01*
X1235581Y183941D01*
X1235998Y183107D01*
X1236289Y182732D01*
X1236706Y182482D01*
X1237081Y182399D01*
Y184149D01*
G01X1234581Y186374D02*
X1237081D01*
G01X1234581Y185416D02*
Y187332D01*
G01X1237081Y189974D02*
X1234581D01*
X1236373Y188432D01*
Y190516D01*
G01X1236039Y191782D02*
X1235748Y192074D01*
X1235581Y192324D01*
X1235498Y192657D01*
X1235581Y192949D01*
X1235748Y193157D01*
X1235998Y193324D01*
X1236289Y193366D01*
X1236539Y193324D01*
X1236789Y193157D01*
X1236998Y192907D01*
X1237081Y192616D01*
X1236998Y192282D01*
X1236748Y191991D01*
X1236373Y191824D01*
X1235956Y191782D01*
X1235414Y191866D01*
X1235123Y191991D01*
X1234831Y192199D01*
X1234623Y192491D01*
X1234581Y192782D01*
X1234664Y193074D01*
X1234873Y193282D01*
G01X1240235Y165753D02*
X1237735D01*
Y166794D01*
X1237860Y167128D01*
X1238027Y167336D01*
X1238360Y167419D01*
X1238693Y167336D01*
X1238902Y167086D01*
X1239027Y166794D01*
Y165753D01*
G01Y166794D02*
X1240235Y167419D01*
G01Y169686D02*
X1237735D01*
X1238235Y169186D01*
G01X1240235D02*
Y170186D01*
G01X1237735Y171536D02*
X1240235Y172119D01*
X1237735Y172786D01*
X1240235Y173453D01*
X1237735Y174036D01*
G01X1238152Y175094D02*
X1237902Y175344D01*
X1237777Y175636D01*
X1237735Y175969D01*
X1237818Y176386D01*
X1238027Y176678D01*
X1238277Y176761D01*
X1238527Y176719D01*
X1238735Y176553D01*
X1239152Y175719D01*
X1239443Y175344D01*
X1239860Y175094D01*
X1240235Y175011D01*
Y176761D01*
G01X1239860Y178069D02*
X1240068Y178319D01*
X1240193Y178611D01*
X1240235Y178986D01*
X1240152Y179361D01*
X1239985Y179653D01*
X1239693Y179861D01*
X1239360Y179903D01*
X1239027Y179819D01*
X1238818Y179611D01*
X1238652Y179319D01*
X1238610Y179028D01*
X1238652Y178736D01*
X1238818Y178361D01*
X1237735Y178486D01*
Y179611D01*
G01X1271158Y165056D02*
X1270033D01*
X1268658Y164223D01*
G01Y165889D02*
X1270033Y165056D01*
G01X1271158Y168156D02*
X1271116Y168448D01*
X1270991Y168781D01*
X1270783Y168989D01*
X1270491Y169073D01*
X1270200Y168989D01*
X1269950Y168739D01*
X1269825Y168364D01*
Y167948D01*
X1269741Y167698D01*
X1269533Y167489D01*
X1269241Y167406D01*
X1268950Y167531D01*
X1268741Y167823D01*
X1268658Y168156D01*
X1268741Y168489D01*
X1268950Y168781D01*
X1269241Y168906D01*
X1269533Y168823D01*
X1269741Y168614D01*
X1269825Y168364D01*
Y167948D01*
X1269950Y167573D01*
X1270200Y167323D01*
X1270491Y167239D01*
X1270783Y167323D01*
X1270991Y167531D01*
X1271116Y167864D01*
X1271158Y168156D01*
G01Y170464D02*
X1268658D01*
Y172048D01*
G01X1269866Y171464D02*
Y170464D01*
G01X1271158Y174356D02*
X1268658D01*
X1269158Y173856D01*
G01X1271158D02*
Y174856D01*
G01X1249779Y188077D02*
X1249529Y188202D01*
X1249237Y188285D01*
X1248904D01*
X1248529Y188160D01*
X1248237Y187952D01*
X1248029Y187702D01*
X1247862Y187285D01*
X1247820Y186910D01*
X1247904Y186535D01*
X1248029Y186285D01*
X1248279Y186035D01*
X1248570Y185868D01*
X1248862Y185785D01*
X1249154D01*
X1249445Y185868D01*
X1249695Y185993D01*
X1249904Y186160D01*
G01X1251962Y185785D02*
X1252254Y185827D01*
X1252587Y185952D01*
X1252795Y186160D01*
X1252879Y186452D01*
X1252795Y186743D01*
X1252545Y186993D01*
X1252170Y187118D01*
X1251754D01*
X1251504Y187202D01*
X1251295Y187410D01*
X1251212Y187702D01*
X1251337Y187993D01*
X1251629Y188202D01*
X1251962Y188285D01*
X1252295Y188202D01*
X1252587Y187993D01*
X1252712Y187702D01*
X1252629Y187410D01*
X1252420Y187202D01*
X1252170Y187118D01*
X1251754D01*
X1251379Y186993D01*
X1251129Y186743D01*
X1251045Y186452D01*
X1251129Y186160D01*
X1251337Y185952D01*
X1251670Y185827D01*
X1251962Y185785D01*
G01X1254270D02*
Y188285D01*
X1255854D01*
G01X1255270Y187077D02*
X1254270D01*
G01X1258162Y185785D02*
Y188285D01*
X1257662Y187785D01*
G01Y185785D02*
X1258662D01*
G01X1260554Y186077D02*
X1260845Y185868D01*
X1261179Y185785D01*
X1261512Y185868D01*
X1261804Y186118D01*
X1262012Y186493D01*
X1262095Y186868D01*
Y187327D01*
X1262012Y187702D01*
X1261804Y188035D01*
X1261554Y188202D01*
X1261262Y188285D01*
X1260929Y188202D01*
X1260679Y188035D01*
X1260512Y187785D01*
X1260429Y187452D01*
X1260512Y187160D01*
X1260720Y186868D01*
X1260970Y186702D01*
X1261262Y186660D01*
X1261595Y186743D01*
X1261845Y186952D01*
X1262095Y187327D01*
G01X1252132Y179818D02*
X1251882Y179943D01*
X1251590Y180026D01*
X1251257D01*
X1250882Y179901D01*
X1250590Y179693D01*
X1250382Y179443D01*
X1250215Y179026D01*
X1250173Y178651D01*
X1250257Y178276D01*
X1250382Y178026D01*
X1250632Y177776D01*
X1250923Y177609D01*
X1251215Y177526D01*
X1251507D01*
X1251798Y177609D01*
X1252048Y177734D01*
X1252257Y177901D01*
G01X1254315Y177526D02*
X1254607Y177568D01*
X1254940Y177693D01*
X1255148Y177901D01*
X1255232Y178193D01*
X1255148Y178484D01*
X1254898Y178734D01*
X1254523Y178859D01*
X1254107D01*
X1253857Y178943D01*
X1253648Y179151D01*
X1253565Y179443D01*
X1253690Y179734D01*
X1253982Y179943D01*
X1254315Y180026D01*
X1254648Y179943D01*
X1254940Y179734D01*
X1255065Y179443D01*
X1254982Y179151D01*
X1254773Y178943D01*
X1254523Y178859D01*
X1254107D01*
X1253732Y178734D01*
X1253482Y178484D01*
X1253398Y178193D01*
X1253482Y177901D01*
X1253690Y177693D01*
X1254023Y177568D01*
X1254315Y177526D01*
G01X1256623D02*
Y180026D01*
X1258207D01*
G01X1257623Y178818D02*
X1256623D01*
G01X1260515Y177526D02*
Y180026D01*
X1260015Y179526D01*
G01Y177526D02*
X1261015D01*
G01X1263615D02*
X1263907Y177568D01*
X1264240Y177693D01*
X1264448Y177901D01*
X1264532Y178193D01*
X1264448Y178484D01*
X1264198Y178734D01*
X1263823Y178859D01*
X1263407D01*
X1263157Y178943D01*
X1262948Y179151D01*
X1262865Y179443D01*
X1262990Y179734D01*
X1263282Y179943D01*
X1263615Y180026D01*
X1263948Y179943D01*
X1264240Y179734D01*
X1264365Y179443D01*
X1264282Y179151D01*
X1264073Y178943D01*
X1263823Y178859D01*
X1263407D01*
X1263032Y178734D01*
X1262782Y178484D01*
X1262698Y178193D01*
X1262782Y177901D01*
X1262990Y177693D01*
X1263323Y177568D01*
X1263615Y177526D01*
G01X1231549Y218781D02*
X1231357Y219091D01*
X1231127Y219298D01*
X1230859Y219401D01*
X1230552Y219298D01*
X1230322Y219091D01*
X1230092Y218781D01*
X1230015Y218368D01*
Y216301D01*
G01X1231740Y203801D02*
X1230782Y200701D01*
X1229824Y203801D01*
G01X1230169Y202716D02*
X1231395D01*
G01X1278400Y233741D02*
X1285739D01*
Y329488D01*
G01Y331347D02*
Y360350D01*
X1234909D01*
Y233741D01*
X1275000D01*
G01X1236360Y250771D02*
X1236235Y250521D01*
X1236152Y250229D01*
Y249896D01*
X1236277Y249521D01*
X1236485Y249229D01*
X1236735Y249021D01*
X1237152Y248854D01*
X1237527Y248812D01*
X1237902Y248896D01*
X1238152Y249021D01*
X1238402Y249271D01*
X1238569Y249562D01*
X1238652Y249854D01*
Y250146D01*
X1238569Y250437D01*
X1238444Y250687D01*
X1238277Y250896D01*
G01X1238652Y252871D02*
X1238110Y252954D01*
X1237652Y253079D01*
X1237235Y253246D01*
X1236777Y253454D01*
X1236152Y253787D01*
Y252121D01*
G01X1237402Y256304D02*
Y257137D01*
X1238152D01*
X1238402Y256887D01*
X1238569Y256596D01*
X1238652Y256179D01*
X1238569Y255762D01*
X1238402Y255471D01*
X1238152Y255221D01*
X1237860Y255054D01*
X1237527Y254971D01*
X1237235D01*
X1236985Y255054D01*
X1236694Y255221D01*
X1236444Y255471D01*
X1236277Y255721D01*
X1236152Y256054D01*
Y256346D01*
X1236235Y256679D01*
X1236402Y256929D01*
G01X1236569Y258362D02*
X1236319Y258612D01*
X1236194Y258904D01*
X1236152Y259237D01*
X1236235Y259654D01*
X1236444Y259946D01*
X1236694Y260029D01*
X1236944Y259987D01*
X1237152Y259821D01*
X1237569Y258987D01*
X1237860Y258612D01*
X1238277Y258362D01*
X1238652Y258279D01*
Y260029D01*
G01Y262171D02*
X1238110Y262254D01*
X1237652Y262379D01*
X1237235Y262546D01*
X1236777Y262754D01*
X1236152Y263087D01*
Y261421D01*
G01X1264041Y275851D02*
X1261541D01*
Y276892D01*
X1261666Y277226D01*
X1261833Y277434D01*
X1262166Y277517D01*
X1262499Y277434D01*
X1262708Y277184D01*
X1262833Y276892D01*
Y275851D01*
G01Y276892D02*
X1264041Y277517D01*
G01Y279701D02*
X1263499Y279784D01*
X1263041Y279909D01*
X1262624Y280076D01*
X1262166Y280284D01*
X1261541Y280617D01*
Y278951D01*
G01X1264041Y282092D02*
X1261541D01*
Y283676D01*
G01X1262749Y283092D02*
Y282092D01*
G01X1261958Y285192D02*
X1261708Y285442D01*
X1261583Y285734D01*
X1261541Y286067D01*
X1261624Y286484D01*
X1261833Y286776D01*
X1262083Y286859D01*
X1262333Y286817D01*
X1262541Y286651D01*
X1262958Y285817D01*
X1263249Y285442D01*
X1263666Y285192D01*
X1264041Y285109D01*
Y286859D01*
G01X1261958Y288292D02*
X1261708Y288542D01*
X1261583Y288834D01*
X1261541Y289167D01*
X1261624Y289584D01*
X1261833Y289876D01*
X1262083Y289959D01*
X1262333Y289917D01*
X1262541Y289751D01*
X1262958Y288917D01*
X1263249Y288542D01*
X1263666Y288292D01*
X1264041Y288209D01*
Y289959D01*
G01X1260341Y275851D02*
X1257841D01*
Y276892D01*
X1257966Y277226D01*
X1258133Y277434D01*
X1258466Y277517D01*
X1258799Y277434D01*
X1259008Y277184D01*
X1259133Y276892D01*
Y275851D01*
G01Y276892D02*
X1260341Y277517D01*
G01Y279701D02*
X1259799Y279784D01*
X1259341Y279909D01*
X1258924Y280076D01*
X1258466Y280284D01*
X1257841Y280617D01*
Y278951D01*
G01X1260341Y282092D02*
X1257841D01*
Y283676D01*
G01X1259049Y283092D02*
Y282092D01*
G01X1258258Y285192D02*
X1258008Y285442D01*
X1257883Y285734D01*
X1257841Y286067D01*
X1257924Y286484D01*
X1258133Y286776D01*
X1258383Y286859D01*
X1258633Y286817D01*
X1258841Y286651D01*
X1259258Y285817D01*
X1259549Y285442D01*
X1259966Y285192D01*
X1260341Y285109D01*
Y286859D01*
G01Y289584D02*
X1257841D01*
X1259633Y288042D01*
Y290126D01*
G01X1236167Y267990D02*
Y270490D01*
X1237208D01*
X1237542Y270365D01*
X1237750Y270198D01*
X1237833Y269865D01*
X1237750Y269532D01*
X1237500Y269323D01*
X1237208Y269198D01*
X1236167D01*
G01X1237208D02*
X1237833Y267990D01*
G01X1240017D02*
X1240100Y268532D01*
X1240225Y268990D01*
X1240392Y269407D01*
X1240600Y269865D01*
X1240933Y270490D01*
X1239267D01*
G01X1243450Y269240D02*
X1244283D01*
Y268490D01*
X1244033Y268240D01*
X1243742Y268073D01*
X1243325Y267990D01*
X1242908Y268073D01*
X1242617Y268240D01*
X1242367Y268490D01*
X1242200Y268782D01*
X1242117Y269115D01*
Y269407D01*
X1242200Y269657D01*
X1242367Y269948D01*
X1242617Y270198D01*
X1242867Y270365D01*
X1243200Y270490D01*
X1243492D01*
X1243825Y270407D01*
X1244075Y270240D01*
G01X1245592Y268282D02*
X1245883Y268073D01*
X1246217Y267990D01*
X1246550Y268073D01*
X1246842Y268323D01*
X1247050Y268698D01*
X1247133Y269073D01*
Y269532D01*
X1247050Y269907D01*
X1246842Y270240D01*
X1246592Y270407D01*
X1246300Y270490D01*
X1245967Y270407D01*
X1245717Y270240D01*
X1245550Y269990D01*
X1245467Y269657D01*
X1245550Y269365D01*
X1245758Y269073D01*
X1246008Y268907D01*
X1246300Y268865D01*
X1246633Y268948D01*
X1246883Y269157D01*
X1247133Y269532D01*
G01X1235997Y277010D02*
Y279510D01*
X1237038D01*
X1237372Y279385D01*
X1237580Y279218D01*
X1237663Y278885D01*
X1237580Y278552D01*
X1237330Y278343D01*
X1237038Y278218D01*
X1235997D01*
G01X1237038D02*
X1237663Y277010D01*
G01X1239847D02*
X1239930Y277552D01*
X1240055Y278010D01*
X1240222Y278427D01*
X1240430Y278885D01*
X1240763Y279510D01*
X1239097D01*
G01X1243280Y278260D02*
X1244113D01*
Y277510D01*
X1243863Y277260D01*
X1243572Y277093D01*
X1243155Y277010D01*
X1242738Y277093D01*
X1242447Y277260D01*
X1242197Y277510D01*
X1242030Y277802D01*
X1241947Y278135D01*
Y278427D01*
X1242030Y278677D01*
X1242197Y278968D01*
X1242447Y279218D01*
X1242697Y279385D01*
X1243030Y279510D01*
X1243322D01*
X1243655Y279427D01*
X1243905Y279260D01*
G01X1246630Y277010D02*
Y279510D01*
X1245088Y277718D01*
X1247172D01*
G01X1248252Y249821D02*
X1245752D01*
Y250862D01*
X1245877Y251196D01*
X1246044Y251404D01*
X1246377Y251487D01*
X1246710Y251404D01*
X1246919Y251154D01*
X1247044Y250862D01*
Y249821D01*
G01Y250862D02*
X1248252Y251487D01*
G01Y252962D02*
X1245752D01*
Y254546D01*
G01X1246960Y253962D02*
Y252962D01*
G01X1248252Y256854D02*
X1245752D01*
X1246252Y256354D01*
G01X1248252D02*
Y257354D01*
G01X1247877Y259037D02*
X1248085Y259287D01*
X1248210Y259579D01*
X1248252Y259954D01*
X1248169Y260329D01*
X1248002Y260621D01*
X1247710Y260829D01*
X1247377Y260871D01*
X1247044Y260787D01*
X1246835Y260579D01*
X1246669Y260287D01*
X1246627Y259996D01*
X1246669Y259704D01*
X1246835Y259329D01*
X1245752Y259454D01*
Y260579D01*
G01X1268467Y262060D02*
Y264560D01*
X1269508D01*
X1269842Y264435D01*
X1270050Y264268D01*
X1270133Y263935D01*
X1270050Y263602D01*
X1269800Y263393D01*
X1269508Y263268D01*
X1268467D01*
G01X1269508D02*
X1270133Y262060D01*
G01X1272317D02*
X1272400Y262602D01*
X1272525Y263060D01*
X1272692Y263477D01*
X1272900Y263935D01*
X1273233Y264560D01*
X1271567D01*
G01X1275750Y263310D02*
X1276583D01*
Y262560D01*
X1276333Y262310D01*
X1276042Y262143D01*
X1275625Y262060D01*
X1275208Y262143D01*
X1274917Y262310D01*
X1274667Y262560D01*
X1274500Y262852D01*
X1274417Y263185D01*
Y263477D01*
X1274500Y263727D01*
X1274667Y264018D01*
X1274917Y264268D01*
X1275167Y264435D01*
X1275500Y264560D01*
X1275792D01*
X1276125Y264477D01*
X1276375Y264310D01*
G01X1278600Y262060D02*
X1278892Y262102D01*
X1279225Y262227D01*
X1279433Y262435D01*
X1279517Y262727D01*
X1279433Y263018D01*
X1279183Y263268D01*
X1278808Y263393D01*
X1278392D01*
X1278142Y263477D01*
X1277933Y263685D01*
X1277850Y263977D01*
X1277975Y264268D01*
X1278267Y264477D01*
X1278600Y264560D01*
X1278933Y264477D01*
X1279225Y264268D01*
X1279350Y263977D01*
X1279267Y263685D01*
X1279058Y263477D01*
X1278808Y263393D01*
X1278392D01*
X1278017Y263268D01*
X1277767Y263018D01*
X1277683Y262727D01*
X1277767Y262435D01*
X1277975Y262227D01*
X1278308Y262102D01*
X1278600Y262060D01*
G01X1268780Y253978D02*
Y256478D01*
X1269821D01*
X1270155Y256353D01*
X1270363Y256186D01*
X1270446Y255853D01*
X1270363Y255520D01*
X1270113Y255311D01*
X1269821Y255186D01*
X1268780D01*
G01X1269821D02*
X1270446Y253978D01*
G01X1272630D02*
X1272713Y254520D01*
X1272838Y254978D01*
X1273005Y255395D01*
X1273213Y255853D01*
X1273546Y256478D01*
X1271880D01*
G01X1276063Y255228D02*
X1276896D01*
Y254478D01*
X1276646Y254228D01*
X1276355Y254061D01*
X1275938Y253978D01*
X1275521Y254061D01*
X1275230Y254228D01*
X1274980Y254478D01*
X1274813Y254770D01*
X1274730Y255103D01*
Y255395D01*
X1274813Y255645D01*
X1274980Y255936D01*
X1275230Y256186D01*
X1275480Y256353D01*
X1275813Y256478D01*
X1276105D01*
X1276438Y256395D01*
X1276688Y256228D01*
G01X1278913Y253978D02*
Y256478D01*
X1278413Y255978D01*
G01Y253978D02*
X1279413D01*
G01X1282013Y256478D02*
X1281680Y256395D01*
X1281430Y256186D01*
X1281263Y255936D01*
X1281138Y255603D01*
X1281096Y255228D01*
X1281138Y254853D01*
X1281263Y254520D01*
X1281430Y254270D01*
X1281680Y254061D01*
X1282013Y253978D01*
X1282346Y254061D01*
X1282596Y254270D01*
X1282763Y254520D01*
X1282888Y254853D01*
X1282930Y255228D01*
X1282888Y255603D01*
X1282763Y255936D01*
X1282596Y256186D01*
X1282346Y256395D01*
X1282013Y256478D01*
G01X1251952Y249821D02*
X1249452D01*
Y250862D01*
X1249577Y251196D01*
X1249744Y251404D01*
X1250077Y251487D01*
X1250410Y251404D01*
X1250619Y251154D01*
X1250744Y250862D01*
Y249821D01*
G01Y250862D02*
X1251952Y251487D01*
G01Y252962D02*
X1249452D01*
Y254546D01*
G01X1250660Y253962D02*
Y252962D01*
G01X1251952Y256854D02*
X1249452D01*
X1249952Y256354D01*
G01X1251952D02*
Y257354D01*
G01X1250910Y259162D02*
X1250619Y259454D01*
X1250452Y259704D01*
X1250369Y260037D01*
X1250452Y260329D01*
X1250619Y260537D01*
X1250869Y260704D01*
X1251160Y260746D01*
X1251410Y260704D01*
X1251660Y260537D01*
X1251869Y260287D01*
X1251952Y259996D01*
X1251869Y259662D01*
X1251619Y259371D01*
X1251244Y259204D01*
X1250827Y259162D01*
X1250285Y259246D01*
X1249994Y259371D01*
X1249702Y259579D01*
X1249494Y259871D01*
X1249452Y260162D01*
X1249535Y260454D01*
X1249744Y260662D01*
G01X1236167Y271990D02*
Y274490D01*
X1237208D01*
X1237542Y274365D01*
X1237750Y274198D01*
X1237833Y273865D01*
X1237750Y273532D01*
X1237500Y273323D01*
X1237208Y273198D01*
X1236167D01*
G01X1237208D02*
X1237833Y271990D01*
G01X1240100D02*
Y274490D01*
X1239600Y273990D01*
G01Y271990D02*
X1240600D01*
G01X1242408Y274073D02*
X1242658Y274323D01*
X1242950Y274448D01*
X1243283Y274490D01*
X1243700Y274407D01*
X1243992Y274198D01*
X1244075Y273948D01*
X1244033Y273698D01*
X1243867Y273490D01*
X1243033Y273073D01*
X1242658Y272782D01*
X1242408Y272365D01*
X1242325Y271990D01*
X1244075D01*
G01X1245050Y274490D02*
X1245633Y271990D01*
X1246300Y274490D01*
X1246967Y271990D01*
X1247550Y274490D01*
G01X1248608Y274073D02*
X1248858Y274323D01*
X1249150Y274448D01*
X1249483Y274490D01*
X1249900Y274407D01*
X1250192Y274198D01*
X1250275Y273948D01*
X1250233Y273698D01*
X1250067Y273490D01*
X1249233Y273073D01*
X1248858Y272782D01*
X1248608Y272365D01*
X1248525Y271990D01*
X1250275D01*
G01X1252417D02*
X1252500Y272532D01*
X1252625Y272990D01*
X1252792Y273407D01*
X1253000Y273865D01*
X1253333Y274490D01*
X1251667D01*
G01X1236100Y238131D02*
X1235975Y237881D01*
X1235892Y237589D01*
Y237256D01*
X1236017Y236881D01*
X1236225Y236589D01*
X1236475Y236381D01*
X1236892Y236214D01*
X1237267Y236172D01*
X1237642Y236256D01*
X1237892Y236381D01*
X1238142Y236631D01*
X1238309Y236922D01*
X1238392Y237214D01*
Y237506D01*
X1238309Y237797D01*
X1238184Y238047D01*
X1238017Y238256D01*
G01X1235892Y240314D02*
X1238392D01*
G01X1235892Y239356D02*
Y241272D01*
G01X1238017Y242497D02*
X1238225Y242747D01*
X1238350Y243039D01*
X1238392Y243414D01*
X1238309Y243789D01*
X1238142Y244081D01*
X1237850Y244289D01*
X1237517Y244331D01*
X1237184Y244247D01*
X1236975Y244039D01*
X1236809Y243747D01*
X1236767Y243456D01*
X1236809Y243164D01*
X1236975Y242789D01*
X1235892Y242914D01*
Y244039D01*
G01Y246514D02*
X1235975Y246181D01*
X1236184Y245931D01*
X1236434Y245764D01*
X1236767Y245639D01*
X1237142Y245597D01*
X1237517Y245639D01*
X1237850Y245764D01*
X1238100Y245931D01*
X1238309Y246181D01*
X1238392Y246514D01*
X1238309Y246847D01*
X1238100Y247097D01*
X1237850Y247264D01*
X1237517Y247389D01*
X1237142Y247431D01*
X1236767Y247389D01*
X1236434Y247264D01*
X1236184Y247097D01*
X1235975Y246847D01*
X1235892Y246514D01*
G01X1242767Y263959D02*
X1242517Y264084D01*
X1242225Y264167D01*
X1241892D01*
X1241517Y264042D01*
X1241225Y263834D01*
X1241017Y263584D01*
X1240850Y263167D01*
X1240808Y262792D01*
X1240892Y262417D01*
X1241017Y262167D01*
X1241267Y261917D01*
X1241558Y261750D01*
X1241850Y261667D01*
X1242142D01*
X1242433Y261750D01*
X1242683Y261875D01*
X1242892Y262042D01*
G01X1244867Y261667D02*
X1244950Y262209D01*
X1245075Y262667D01*
X1245242Y263084D01*
X1245450Y263542D01*
X1245783Y264167D01*
X1244117D01*
G01X1248300Y262917D02*
X1249133D01*
Y262167D01*
X1248883Y261917D01*
X1248592Y261750D01*
X1248175Y261667D01*
X1247758Y261750D01*
X1247467Y261917D01*
X1247217Y262167D01*
X1247050Y262459D01*
X1246967Y262792D01*
Y263084D01*
X1247050Y263334D01*
X1247217Y263625D01*
X1247467Y263875D01*
X1247717Y264042D01*
X1248050Y264167D01*
X1248342D01*
X1248675Y264084D01*
X1248925Y263917D01*
G01X1251650Y261667D02*
Y264167D01*
X1250108Y262375D01*
X1252192D01*
G01X1254449Y276201D02*
X1254324Y275951D01*
X1254241Y275659D01*
Y275326D01*
X1254366Y274951D01*
X1254574Y274659D01*
X1254824Y274451D01*
X1255241Y274284D01*
X1255616Y274242D01*
X1255991Y274326D01*
X1256241Y274451D01*
X1256491Y274701D01*
X1256658Y274992D01*
X1256741Y275284D01*
Y275576D01*
X1256658Y275867D01*
X1256533Y276117D01*
X1256366Y276326D01*
G01X1256741Y278301D02*
X1256199Y278384D01*
X1255741Y278509D01*
X1255324Y278676D01*
X1254866Y278884D01*
X1254241Y279217D01*
Y277551D01*
G01X1256741Y280692D02*
X1254241D01*
Y282276D01*
G01X1255449Y281692D02*
Y280692D01*
G01X1256741Y284584D02*
X1254241D01*
X1254741Y284084D01*
G01X1256741D02*
Y285084D01*
G01Y288184D02*
X1254241D01*
X1256033Y286642D01*
Y288726D01*
G01X1270701Y239260D02*
X1270451Y239385D01*
X1270159Y239468D01*
X1269826D01*
X1269451Y239343D01*
X1269159Y239135D01*
X1268951Y238885D01*
X1268784Y238468D01*
X1268742Y238093D01*
X1268826Y237718D01*
X1268951Y237468D01*
X1269201Y237218D01*
X1269492Y237051D01*
X1269784Y236968D01*
X1270076D01*
X1270367Y237051D01*
X1270617Y237176D01*
X1270826Y237343D01*
G01X1272801Y236968D02*
X1272884Y237510D01*
X1273009Y237968D01*
X1273176Y238385D01*
X1273384Y238843D01*
X1273717Y239468D01*
X1272051D01*
G01X1276234Y238218D02*
X1277067D01*
Y237468D01*
X1276817Y237218D01*
X1276526Y237051D01*
X1276109Y236968D01*
X1275692Y237051D01*
X1275401Y237218D01*
X1275151Y237468D01*
X1274984Y237760D01*
X1274901Y238093D01*
Y238385D01*
X1274984Y238635D01*
X1275151Y238926D01*
X1275401Y239176D01*
X1275651Y239343D01*
X1275984Y239468D01*
X1276276D01*
X1276609Y239385D01*
X1276859Y239218D01*
G01X1278167Y237468D02*
X1278417Y237176D01*
X1278751Y237010D01*
X1279126Y236968D01*
X1279459Y237010D01*
X1279792Y237218D01*
X1280001Y237468D01*
X1280042Y237718D01*
X1279959Y238010D01*
X1279667Y238218D01*
X1279376Y238301D01*
X1279001D01*
G01X1279376D02*
X1279626Y238426D01*
X1279834Y238635D01*
X1279917Y238885D01*
X1279834Y239135D01*
X1279626Y239343D01*
X1279251Y239468D01*
X1278876Y239426D01*
X1278501Y239260D01*
G01X1281267Y237468D02*
X1281517Y237176D01*
X1281851Y237010D01*
X1282226Y236968D01*
X1282559Y237010D01*
X1282892Y237218D01*
X1283101Y237468D01*
X1283142Y237718D01*
X1283059Y238010D01*
X1282767Y238218D01*
X1282476Y238301D01*
X1282101D01*
G01X1282476D02*
X1282726Y238426D01*
X1282934Y238635D01*
X1283017Y238885D01*
X1282934Y239135D01*
X1282726Y239343D01*
X1282351Y239468D01*
X1281976Y239426D01*
X1281601Y239260D01*
G01X1257001Y243460D02*
X1256751Y243585D01*
X1256459Y243668D01*
X1256126D01*
X1255751Y243543D01*
X1255459Y243335D01*
X1255251Y243085D01*
X1255084Y242668D01*
X1255042Y242293D01*
X1255126Y241918D01*
X1255251Y241668D01*
X1255501Y241418D01*
X1255792Y241251D01*
X1256084Y241168D01*
X1256376D01*
X1256667Y241251D01*
X1256917Y241376D01*
X1257126Y241543D01*
G01X1259101Y241168D02*
X1259184Y241710D01*
X1259309Y242168D01*
X1259476Y242585D01*
X1259684Y243043D01*
X1260017Y243668D01*
X1258351D01*
G01X1262534Y242418D02*
X1263367D01*
Y241668D01*
X1263117Y241418D01*
X1262826Y241251D01*
X1262409Y241168D01*
X1261992Y241251D01*
X1261701Y241418D01*
X1261451Y241668D01*
X1261284Y241960D01*
X1261201Y242293D01*
Y242585D01*
X1261284Y242835D01*
X1261451Y243126D01*
X1261701Y243376D01*
X1261951Y243543D01*
X1262284Y243668D01*
X1262576D01*
X1262909Y243585D01*
X1263159Y243418D01*
G01X1264467Y241668D02*
X1264717Y241376D01*
X1265051Y241210D01*
X1265426Y241168D01*
X1265759Y241210D01*
X1266092Y241418D01*
X1266301Y241668D01*
X1266342Y241918D01*
X1266259Y242210D01*
X1265967Y242418D01*
X1265676Y242501D01*
X1265301D01*
G01X1265676D02*
X1265926Y242626D01*
X1266134Y242835D01*
X1266217Y243085D01*
X1266134Y243335D01*
X1265926Y243543D01*
X1265551Y243668D01*
X1265176Y243626D01*
X1264801Y243460D01*
G01X1268984Y241168D02*
Y243668D01*
X1267442Y241876D01*
X1269526D01*
G01X1272403Y260270D02*
X1272153Y260395D01*
X1271861Y260478D01*
X1271528D01*
X1271153Y260353D01*
X1270861Y260145D01*
X1270653Y259895D01*
X1270486Y259478D01*
X1270444Y259103D01*
X1270528Y258728D01*
X1270653Y258478D01*
X1270903Y258228D01*
X1271194Y258061D01*
X1271486Y257978D01*
X1271778D01*
X1272069Y258061D01*
X1272319Y258186D01*
X1272528Y258353D01*
G01X1274503Y257978D02*
X1274586Y258520D01*
X1274711Y258978D01*
X1274878Y259395D01*
X1275086Y259853D01*
X1275419Y260478D01*
X1273753D01*
G01X1277936Y259228D02*
X1278769D01*
Y258478D01*
X1278519Y258228D01*
X1278228Y258061D01*
X1277811Y257978D01*
X1277394Y258061D01*
X1277103Y258228D01*
X1276853Y258478D01*
X1276686Y258770D01*
X1276603Y259103D01*
Y259395D01*
X1276686Y259645D01*
X1276853Y259936D01*
X1277103Y260186D01*
X1277353Y260353D01*
X1277686Y260478D01*
X1277978D01*
X1278311Y260395D01*
X1278561Y260228D01*
G01X1279869Y258478D02*
X1280119Y258186D01*
X1280453Y258020D01*
X1280828Y257978D01*
X1281161Y258020D01*
X1281494Y258228D01*
X1281703Y258478D01*
X1281744Y258728D01*
X1281661Y259020D01*
X1281369Y259228D01*
X1281078Y259311D01*
X1280703D01*
G01X1281078D02*
X1281328Y259436D01*
X1281536Y259645D01*
X1281619Y259895D01*
X1281536Y260145D01*
X1281328Y260353D01*
X1280953Y260478D01*
X1280578Y260436D01*
X1280203Y260270D01*
G01X1277595Y269911D02*
X1277470Y269661D01*
X1277387Y269369D01*
Y269036D01*
X1277512Y268661D01*
X1277720Y268369D01*
X1277970Y268161D01*
X1278387Y267994D01*
X1278762Y267952D01*
X1279137Y268036D01*
X1279387Y268161D01*
X1279637Y268411D01*
X1279804Y268702D01*
X1279887Y268994D01*
Y269286D01*
X1279804Y269577D01*
X1279679Y269827D01*
X1279512Y270036D01*
G01X1279887Y272094D02*
X1277387D01*
X1277887Y271594D01*
G01X1279887D02*
Y272594D01*
G01X1277804Y274402D02*
X1277554Y274652D01*
X1277429Y274944D01*
X1277387Y275277D01*
X1277470Y275694D01*
X1277679Y275986D01*
X1277929Y276069D01*
X1278179Y276027D01*
X1278387Y275861D01*
X1278804Y275027D01*
X1279095Y274652D01*
X1279512Y274402D01*
X1279887Y274319D01*
Y276069D01*
G01X1277387Y277044D02*
X1279887Y277627D01*
X1277387Y278294D01*
X1279887Y278961D01*
X1277387Y279544D01*
G01X1279887Y281394D02*
X1277387D01*
X1277887Y280894D01*
G01X1279887D02*
Y281894D01*
G01X1274201Y243960D02*
X1273951Y244085D01*
X1273659Y244168D01*
X1273326D01*
X1272951Y244043D01*
X1272659Y243835D01*
X1272451Y243585D01*
X1272284Y243168D01*
X1272242Y242793D01*
X1272326Y242418D01*
X1272451Y242168D01*
X1272701Y241918D01*
X1272992Y241751D01*
X1273284Y241668D01*
X1273576D01*
X1273867Y241751D01*
X1274117Y241876D01*
X1274326Y242043D01*
G01X1276384Y244168D02*
Y241668D01*
G01X1275426Y244168D02*
X1277342D01*
G01X1278567Y242043D02*
X1278817Y241835D01*
X1279109Y241710D01*
X1279484Y241668D01*
X1279859Y241751D01*
X1280151Y241918D01*
X1280359Y242210D01*
X1280401Y242543D01*
X1280317Y242876D01*
X1280109Y243085D01*
X1279817Y243251D01*
X1279526Y243293D01*
X1279234Y243251D01*
X1278859Y243085D01*
X1278984Y244168D01*
X1280109D01*
G01X1282584Y241668D02*
Y244168D01*
X1282084Y243668D01*
G01Y241668D02*
X1283084D01*
G01X1232025Y280148D02*
X1231872Y279993D01*
X1231757Y279734D01*
X1231680Y279373D01*
X1231757Y279063D01*
X1231910Y278856D01*
X1232179Y278701D01*
X1233214D01*
Y281801D01*
X1231949D01*
X1231680Y281594D01*
X1231527Y281284D01*
X1231450Y280923D01*
X1231527Y280561D01*
X1231757Y280251D01*
X1232025Y280148D01*
X1233214D01*
G01X1230190Y281801D02*
X1229232Y278701D01*
X1228274Y281801D01*
G01X1228619Y280716D02*
X1229845D01*
G01X1233290Y266201D02*
X1232332Y263101D01*
X1231374Y266201D01*
G01X1231719Y265116D02*
X1232945D01*
G01X1230114Y266201D02*
Y263101D01*
X1228350Y266201D01*
Y263101D01*
G01X1233290Y250601D02*
X1232332Y247501D01*
X1231374Y250601D01*
G01X1231719Y249516D02*
X1232945D01*
G01X1228465Y250601D02*
X1229999D01*
Y247501D01*
X1228465D01*
G01X1229079Y248999D02*
X1229999D01*
G01X1231625Y231901D02*
Y234123D01*
X1231472Y234588D01*
X1231165Y234898D01*
X1230782Y235001D01*
X1230399Y234898D01*
X1230092Y234588D01*
X1229939Y234123D01*
Y231901D01*
G01X1246100Y237931D02*
X1245975Y237681D01*
X1245892Y237389D01*
Y237056D01*
X1246017Y236681D01*
X1246225Y236389D01*
X1246475Y236181D01*
X1246892Y236014D01*
X1247267Y235972D01*
X1247642Y236056D01*
X1247892Y236181D01*
X1248142Y236431D01*
X1248309Y236722D01*
X1248392Y237014D01*
Y237306D01*
X1248309Y237597D01*
X1248184Y237847D01*
X1248017Y238056D01*
G01X1248392Y239322D02*
X1245892D01*
Y240906D01*
G01X1247100Y240322D02*
Y239322D01*
G01X1248392Y243214D02*
X1245892D01*
X1246392Y242714D01*
G01X1248392D02*
Y243714D01*
G01X1248017Y245397D02*
X1248225Y245647D01*
X1248350Y245939D01*
X1248392Y246314D01*
X1248309Y246689D01*
X1248142Y246981D01*
X1247850Y247189D01*
X1247517Y247231D01*
X1247184Y247147D01*
X1246975Y246939D01*
X1246809Y246647D01*
X1246767Y246356D01*
X1246809Y246064D01*
X1246975Y245689D01*
X1245892Y245814D01*
Y246939D01*
G01X1249800Y237931D02*
X1249675Y237681D01*
X1249592Y237389D01*
Y237056D01*
X1249717Y236681D01*
X1249925Y236389D01*
X1250175Y236181D01*
X1250592Y236014D01*
X1250967Y235972D01*
X1251342Y236056D01*
X1251592Y236181D01*
X1251842Y236431D01*
X1252009Y236722D01*
X1252092Y237014D01*
Y237306D01*
X1252009Y237597D01*
X1251884Y237847D01*
X1251717Y238056D01*
G01X1252092Y239322D02*
X1249592D01*
Y240906D01*
G01X1250800Y240322D02*
Y239322D01*
G01X1252092Y243214D02*
X1249592D01*
X1250092Y242714D01*
G01X1252092D02*
Y243714D01*
G01X1251050Y245522D02*
X1250759Y245814D01*
X1250592Y246064D01*
X1250509Y246397D01*
X1250592Y246689D01*
X1250759Y246897D01*
X1251009Y247064D01*
X1251300Y247106D01*
X1251550Y247064D01*
X1251800Y246897D01*
X1252009Y246647D01*
X1252092Y246356D01*
X1252009Y246022D01*
X1251759Y245731D01*
X1251384Y245564D01*
X1250967Y245522D01*
X1250425Y245606D01*
X1250134Y245731D01*
X1249842Y245939D01*
X1249634Y246231D01*
X1249592Y246522D01*
X1249675Y246814D01*
X1249884Y247022D01*
G01X1242092Y236381D02*
X1239592D01*
Y237422D01*
X1239717Y237756D01*
X1239884Y237964D01*
X1240217Y238047D01*
X1240550Y237964D01*
X1240759Y237714D01*
X1240884Y237422D01*
Y236381D01*
G01Y237422D02*
X1242092Y238047D01*
G01X1239592Y240314D02*
X1242092D01*
G01X1239592Y239356D02*
Y241272D01*
G01X1241592Y242497D02*
X1241884Y242747D01*
X1242050Y243081D01*
X1242092Y243456D01*
X1242050Y243789D01*
X1241842Y244122D01*
X1241592Y244331D01*
X1241342Y244372D01*
X1241050Y244289D01*
X1240842Y243997D01*
X1240759Y243706D01*
Y243331D01*
G01Y243706D02*
X1240634Y243956D01*
X1240425Y244164D01*
X1240175Y244247D01*
X1239925Y244164D01*
X1239717Y243956D01*
X1239592Y243581D01*
X1239634Y243206D01*
X1239800Y242831D01*
G01X1242092Y247014D02*
X1239592D01*
X1241384Y245472D01*
Y247556D01*
G01X1264334Y262133D02*
Y260467D01*
X1261834D01*
Y262133D01*
G01X1263042Y261467D02*
Y260467D01*
G01X1261834Y263483D02*
X1263626D01*
X1264001Y263650D01*
X1264251Y263983D01*
X1264334Y264400D01*
X1264251Y264817D01*
X1264001Y265150D01*
X1263626Y265317D01*
X1261834D01*
G01X1264334Y267417D02*
X1263792Y267500D01*
X1263334Y267625D01*
X1262917Y267792D01*
X1262459Y268000D01*
X1261834Y268333D01*
Y266667D01*
G01X1263084Y270850D02*
Y271683D01*
X1263834D01*
X1264084Y271433D01*
X1264251Y271142D01*
X1264334Y270725D01*
X1264251Y270308D01*
X1264084Y270017D01*
X1263834Y269767D01*
X1263542Y269600D01*
X1263209Y269517D01*
X1262917D01*
X1262667Y269600D01*
X1262376Y269767D01*
X1262126Y270017D01*
X1261959Y270267D01*
X1261834Y270600D01*
Y270892D01*
X1261917Y271225D01*
X1262084Y271475D01*
G01X1264334Y273700D02*
X1261834D01*
X1262334Y273200D01*
G01X1264334D02*
Y274200D01*
G01X1271487Y297233D02*
Y300383D01*
X1268820Y304233D01*
G01X1274154D02*
X1271487Y300383D01*
G01X1244467Y306667D02*
Y309167D01*
X1245508D01*
X1245842Y309042D01*
X1246050Y308875D01*
X1246133Y308542D01*
X1246050Y308209D01*
X1245800Y308000D01*
X1245508Y307875D01*
X1244467D01*
G01X1245508D02*
X1246133Y306667D01*
G01X1248317D02*
X1248400Y307209D01*
X1248525Y307667D01*
X1248692Y308084D01*
X1248900Y308542D01*
X1249233Y309167D01*
X1247567D01*
G01X1250708Y306667D02*
Y309167D01*
X1252292D01*
G01X1251708Y307959D02*
X1250708D01*
G01X1253808Y308750D02*
X1254058Y309000D01*
X1254350Y309125D01*
X1254683Y309167D01*
X1255100Y309084D01*
X1255392Y308875D01*
X1255475Y308625D01*
X1255433Y308375D01*
X1255267Y308167D01*
X1254433Y307750D01*
X1254058Y307459D01*
X1253808Y307042D01*
X1253725Y306667D01*
X1255475D01*
G01X1256783Y307167D02*
X1257033Y306875D01*
X1257367Y306709D01*
X1257742Y306667D01*
X1258075Y306709D01*
X1258408Y306917D01*
X1258617Y307167D01*
X1258658Y307417D01*
X1258575Y307709D01*
X1258283Y307917D01*
X1257992Y308000D01*
X1257617D01*
G01X1257992D02*
X1258242Y308125D01*
X1258450Y308334D01*
X1258533Y308584D01*
X1258450Y308834D01*
X1258242Y309042D01*
X1257867Y309167D01*
X1257492Y309125D01*
X1257117Y308959D01*
G01X1244550Y335476D02*
Y337976D01*
X1245591D01*
X1245925Y337851D01*
X1246133Y337684D01*
X1246216Y337351D01*
X1246133Y337018D01*
X1245883Y336809D01*
X1245591Y336684D01*
X1244550D01*
G01X1245591D02*
X1246216Y335476D01*
G01X1248400D02*
X1248483Y336018D01*
X1248608Y336476D01*
X1248775Y336893D01*
X1248983Y337351D01*
X1249316Y337976D01*
X1247650D01*
G01X1250791Y335476D02*
Y337976D01*
X1252375D01*
G01X1251791Y336768D02*
X1250791D01*
G01X1253766Y335976D02*
X1254016Y335684D01*
X1254350Y335518D01*
X1254725Y335476D01*
X1255058Y335518D01*
X1255391Y335726D01*
X1255600Y335976D01*
X1255641Y336226D01*
X1255558Y336518D01*
X1255266Y336726D01*
X1254975Y336809D01*
X1254600D01*
G01X1254975D02*
X1255225Y336934D01*
X1255433Y337143D01*
X1255516Y337393D01*
X1255433Y337643D01*
X1255225Y337851D01*
X1254850Y337976D01*
X1254475Y337934D01*
X1254100Y337768D01*
G01X1256866Y335851D02*
X1257116Y335643D01*
X1257408Y335518D01*
X1257783Y335476D01*
X1258158Y335559D01*
X1258450Y335726D01*
X1258658Y336018D01*
X1258700Y336351D01*
X1258616Y336684D01*
X1258408Y336893D01*
X1258116Y337059D01*
X1257825Y337101D01*
X1257533Y337059D01*
X1257158Y336893D01*
X1257283Y337976D01*
X1258408D01*
G01X1235967Y296357D02*
Y298857D01*
X1237008D01*
X1237342Y298732D01*
X1237550Y298565D01*
X1237633Y298232D01*
X1237550Y297899D01*
X1237300Y297690D01*
X1237008Y297565D01*
X1235967D01*
G01X1237008D02*
X1237633Y296357D01*
G01X1239817D02*
X1239900Y296899D01*
X1240025Y297357D01*
X1240192Y297774D01*
X1240400Y298232D01*
X1240733Y298857D01*
X1239067D01*
G01X1242208Y296357D02*
Y298857D01*
X1243792D01*
G01X1243208Y297649D02*
X1242208D01*
G01X1245308Y298440D02*
X1245558Y298690D01*
X1245850Y298815D01*
X1246183Y298857D01*
X1246600Y298774D01*
X1246892Y298565D01*
X1246975Y298315D01*
X1246933Y298065D01*
X1246767Y297857D01*
X1245933Y297440D01*
X1245558Y297149D01*
X1245308Y296732D01*
X1245225Y296357D01*
X1246975D01*
G01X1249117D02*
X1249200Y296899D01*
X1249325Y297357D01*
X1249492Y297774D01*
X1249700Y298232D01*
X1250033Y298857D01*
X1248367D01*
G01X1263273Y338663D02*
X1260773D01*
Y339704D01*
X1260898Y340038D01*
X1261065Y340246D01*
X1261398Y340329D01*
X1261731Y340246D01*
X1261940Y339996D01*
X1262065Y339704D01*
Y338663D01*
G01Y339704D02*
X1263273Y340329D01*
G01Y342513D02*
X1262731Y342596D01*
X1262273Y342721D01*
X1261856Y342888D01*
X1261398Y343096D01*
X1260773Y343429D01*
Y341763D01*
G01X1263273Y344904D02*
X1260773D01*
Y346488D01*
G01X1261981Y345904D02*
Y344904D01*
G01X1263273Y348796D02*
X1260773D01*
X1261273Y348296D01*
G01X1263273D02*
Y349296D01*
G01Y351896D02*
X1263231Y352188D01*
X1263106Y352521D01*
X1262898Y352729D01*
X1262606Y352813D01*
X1262315Y352729D01*
X1262065Y352479D01*
X1261940Y352104D01*
Y351688D01*
X1261856Y351438D01*
X1261648Y351229D01*
X1261356Y351146D01*
X1261065Y351271D01*
X1260856Y351563D01*
X1260773Y351896D01*
X1260856Y352229D01*
X1261065Y352521D01*
X1261356Y352646D01*
X1261648Y352563D01*
X1261856Y352354D01*
X1261940Y352104D01*
Y351688D01*
X1262065Y351313D01*
X1262315Y351063D01*
X1262606Y350979D01*
X1262898Y351063D01*
X1263106Y351271D01*
X1263231Y351604D01*
X1263273Y351896D01*
G01X1252173Y339523D02*
X1249673D01*
Y340564D01*
X1249798Y340898D01*
X1249965Y341106D01*
X1250298Y341189D01*
X1250631Y341106D01*
X1250840Y340856D01*
X1250965Y340564D01*
Y339523D01*
G01Y340564D02*
X1252173Y341189D01*
G01Y343373D02*
X1251631Y343456D01*
X1251173Y343581D01*
X1250756Y343748D01*
X1250298Y343956D01*
X1249673Y344289D01*
Y342623D01*
G01X1252173Y345764D02*
X1249673D01*
Y347348D01*
G01X1250881Y346764D02*
Y345764D01*
G01X1252173Y349656D02*
X1249673D01*
X1250173Y349156D01*
G01X1252173D02*
Y350156D01*
G01Y353256D02*
X1249673D01*
X1251465Y351714D01*
Y353798D01*
G01X1235997Y285010D02*
Y287510D01*
X1237038D01*
X1237372Y287385D01*
X1237580Y287218D01*
X1237663Y286885D01*
X1237580Y286552D01*
X1237330Y286343D01*
X1237038Y286218D01*
X1235997D01*
G01X1237038D02*
X1237663Y285010D01*
G01X1239847D02*
X1239930Y285552D01*
X1240055Y286010D01*
X1240222Y286427D01*
X1240430Y286885D01*
X1240763Y287510D01*
X1239097D01*
G01X1243280Y286260D02*
X1244113D01*
Y285510D01*
X1243863Y285260D01*
X1243572Y285093D01*
X1243155Y285010D01*
X1242738Y285093D01*
X1242447Y285260D01*
X1242197Y285510D01*
X1242030Y285802D01*
X1241947Y286135D01*
Y286427D01*
X1242030Y286677D01*
X1242197Y286968D01*
X1242447Y287218D01*
X1242697Y287385D01*
X1243030Y287510D01*
X1243322D01*
X1243655Y287427D01*
X1243905Y287260D01*
G01X1245338Y287093D02*
X1245588Y287343D01*
X1245880Y287468D01*
X1246213Y287510D01*
X1246630Y287427D01*
X1246922Y287218D01*
X1247005Y286968D01*
X1246963Y286718D01*
X1246797Y286510D01*
X1245963Y286093D01*
X1245588Y285802D01*
X1245338Y285385D01*
X1245255Y285010D01*
X1247005D01*
G01X1249730D02*
Y287510D01*
X1248188Y285718D01*
X1250272D01*
G01X1235997Y281010D02*
Y283510D01*
X1237038D01*
X1237372Y283385D01*
X1237580Y283218D01*
X1237663Y282885D01*
X1237580Y282552D01*
X1237330Y282343D01*
X1237038Y282218D01*
X1235997D01*
G01X1237038D02*
X1237663Y281010D01*
G01X1239847D02*
X1239930Y281552D01*
X1240055Y282010D01*
X1240222Y282427D01*
X1240430Y282885D01*
X1240763Y283510D01*
X1239097D01*
G01X1243280Y282260D02*
X1244113D01*
Y281510D01*
X1243863Y281260D01*
X1243572Y281093D01*
X1243155Y281010D01*
X1242738Y281093D01*
X1242447Y281260D01*
X1242197Y281510D01*
X1242030Y281802D01*
X1241947Y282135D01*
Y282427D01*
X1242030Y282677D01*
X1242197Y282968D01*
X1242447Y283218D01*
X1242697Y283385D01*
X1243030Y283510D01*
X1243322D01*
X1243655Y283427D01*
X1243905Y283260D01*
G01X1245338Y283093D02*
X1245588Y283343D01*
X1245880Y283468D01*
X1246213Y283510D01*
X1246630Y283427D01*
X1246922Y283218D01*
X1247005Y282968D01*
X1246963Y282718D01*
X1246797Y282510D01*
X1245963Y282093D01*
X1245588Y281802D01*
X1245338Y281385D01*
X1245255Y281010D01*
X1247005D01*
G01X1239302Y328905D02*
X1236802D01*
Y329946D01*
X1236927Y330280D01*
X1237094Y330488D01*
X1237427Y330571D01*
X1237760Y330488D01*
X1237969Y330238D01*
X1238094Y329946D01*
Y328905D01*
G01Y329946D02*
X1239302Y330571D01*
G01Y332755D02*
X1238760Y332838D01*
X1238302Y332963D01*
X1237885Y333130D01*
X1237427Y333338D01*
X1236802Y333671D01*
Y332005D01*
G01X1239302Y335146D02*
X1236802D01*
Y336730D01*
G01X1238010Y336146D02*
Y335146D01*
G01X1239302Y339038D02*
X1236802D01*
X1237302Y338538D01*
G01X1239302D02*
Y339538D01*
G01Y342055D02*
X1238760Y342138D01*
X1238302Y342263D01*
X1237885Y342430D01*
X1237427Y342638D01*
X1236802Y342971D01*
Y341305D01*
G01X1245137Y331436D02*
Y333936D01*
X1246178D01*
X1246512Y333811D01*
X1246720Y333644D01*
X1246803Y333311D01*
X1246720Y332978D01*
X1246470Y332769D01*
X1246178Y332644D01*
X1245137D01*
G01X1246178D02*
X1246803Y331436D01*
G01X1248987D02*
X1249070Y331978D01*
X1249195Y332436D01*
X1249362Y332853D01*
X1249570Y333311D01*
X1249903Y333936D01*
X1248237D01*
G01X1251378Y331436D02*
Y333936D01*
X1252962D01*
G01X1252378Y332728D02*
X1251378D01*
G01X1254478Y333519D02*
X1254728Y333769D01*
X1255020Y333894D01*
X1255353Y333936D01*
X1255770Y333853D01*
X1256062Y333644D01*
X1256145Y333394D01*
X1256103Y333144D01*
X1255937Y332936D01*
X1255103Y332519D01*
X1254728Y332228D01*
X1254478Y331811D01*
X1254395Y331436D01*
X1256145D01*
G01X1258370Y333936D02*
X1258037Y333853D01*
X1257787Y333644D01*
X1257620Y333394D01*
X1257495Y333061D01*
X1257453Y332686D01*
X1257495Y332311D01*
X1257620Y331978D01*
X1257787Y331728D01*
X1258037Y331519D01*
X1258370Y331436D01*
X1258703Y331519D01*
X1258953Y331728D01*
X1259120Y331978D01*
X1259245Y332311D01*
X1259287Y332686D01*
X1259245Y333061D01*
X1259120Y333394D01*
X1258953Y333644D01*
X1258703Y333853D01*
X1258370Y333936D01*
G01X1243114Y312127D02*
X1240614D01*
Y313168D01*
X1240739Y313502D01*
X1240906Y313710D01*
X1241239Y313793D01*
X1241572Y313710D01*
X1241781Y313460D01*
X1241906Y313168D01*
Y312127D01*
G01Y313168D02*
X1243114Y313793D01*
G01Y315977D02*
X1242572Y316060D01*
X1242114Y316185D01*
X1241697Y316352D01*
X1241239Y316560D01*
X1240614Y316893D01*
Y315227D01*
G01X1243114Y318368D02*
X1240614D01*
Y319952D01*
G01X1241822Y319368D02*
Y318368D01*
G01X1242614Y321343D02*
X1242906Y321593D01*
X1243072Y321927D01*
X1243114Y322302D01*
X1243072Y322635D01*
X1242864Y322968D01*
X1242614Y323177D01*
X1242364Y323218D01*
X1242072Y323135D01*
X1241864Y322843D01*
X1241781Y322552D01*
Y322177D01*
G01Y322552D02*
X1241656Y322802D01*
X1241447Y323010D01*
X1241197Y323093D01*
X1240947Y323010D01*
X1240739Y322802D01*
X1240614Y322427D01*
X1240656Y322052D01*
X1240822Y321677D01*
G01X1242072Y324568D02*
X1241781Y324860D01*
X1241614Y325110D01*
X1241531Y325443D01*
X1241614Y325735D01*
X1241781Y325943D01*
X1242031Y326110D01*
X1242322Y326152D01*
X1242572Y326110D01*
X1242822Y325943D01*
X1243031Y325693D01*
X1243114Y325402D01*
X1243031Y325068D01*
X1242781Y324777D01*
X1242406Y324610D01*
X1241989Y324568D01*
X1241447Y324652D01*
X1241156Y324777D01*
X1240864Y324985D01*
X1240656Y325277D01*
X1240614Y325568D01*
X1240697Y325860D01*
X1240906Y326068D01*
G01X1265467Y335807D02*
Y338307D01*
X1266508D01*
X1266842Y338182D01*
X1267050Y338015D01*
X1267133Y337682D01*
X1267050Y337349D01*
X1266800Y337140D01*
X1266508Y337015D01*
X1265467D01*
G01X1266508D02*
X1267133Y335807D01*
G01X1269317D02*
X1269400Y336349D01*
X1269525Y336807D01*
X1269692Y337224D01*
X1269900Y337682D01*
X1270233Y338307D01*
X1268567D01*
G01X1271708Y335807D02*
Y338307D01*
X1273292D01*
G01X1272708Y337099D02*
X1271708D01*
G01X1274808Y337890D02*
X1275058Y338140D01*
X1275350Y338265D01*
X1275683Y338307D01*
X1276100Y338224D01*
X1276392Y338015D01*
X1276475Y337765D01*
X1276433Y337515D01*
X1276267Y337307D01*
X1275433Y336890D01*
X1275058Y336599D01*
X1274808Y336182D01*
X1274725Y335807D01*
X1276475D01*
G01X1278700D02*
Y338307D01*
X1278200Y337807D01*
G01Y335807D02*
X1279200D01*
G01X1235997Y293010D02*
Y295510D01*
X1237038D01*
X1237372Y295385D01*
X1237580Y295218D01*
X1237663Y294885D01*
X1237580Y294552D01*
X1237330Y294343D01*
X1237038Y294218D01*
X1235997D01*
G01X1237038D02*
X1237663Y293010D01*
G01X1239930D02*
Y295510D01*
X1239430Y295010D01*
G01Y293010D02*
X1240430D01*
G01X1242238Y295093D02*
X1242488Y295343D01*
X1242780Y295468D01*
X1243113Y295510D01*
X1243530Y295427D01*
X1243822Y295218D01*
X1243905Y294968D01*
X1243863Y294718D01*
X1243697Y294510D01*
X1242863Y294093D01*
X1242488Y293802D01*
X1242238Y293385D01*
X1242155Y293010D01*
X1243905D01*
G01X1244880Y295510D02*
X1245463Y293010D01*
X1246130Y295510D01*
X1246797Y293010D01*
X1247380Y295510D01*
G01X1248438Y295093D02*
X1248688Y295343D01*
X1248980Y295468D01*
X1249313Y295510D01*
X1249730Y295427D01*
X1250022Y295218D01*
X1250105Y294968D01*
X1250063Y294718D01*
X1249897Y294510D01*
X1249063Y294093D01*
X1248688Y293802D01*
X1248438Y293385D01*
X1248355Y293010D01*
X1250105D01*
G01X1251413Y293385D02*
X1251663Y293177D01*
X1251955Y293052D01*
X1252330Y293010D01*
X1252705Y293093D01*
X1252997Y293260D01*
X1253205Y293552D01*
X1253247Y293885D01*
X1253163Y294218D01*
X1252955Y294427D01*
X1252663Y294593D01*
X1252372Y294635D01*
X1252080Y294593D01*
X1251705Y294427D01*
X1251830Y295510D01*
X1252955D01*
G01X1235997Y289010D02*
Y291510D01*
X1237038D01*
X1237372Y291385D01*
X1237580Y291218D01*
X1237663Y290885D01*
X1237580Y290552D01*
X1237330Y290343D01*
X1237038Y290218D01*
X1235997D01*
G01X1237038D02*
X1237663Y289010D01*
G01X1239930D02*
Y291510D01*
X1239430Y291010D01*
G01Y289010D02*
X1240430D01*
G01X1242238Y291093D02*
X1242488Y291343D01*
X1242780Y291468D01*
X1243113Y291510D01*
X1243530Y291427D01*
X1243822Y291218D01*
X1243905Y290968D01*
X1243863Y290718D01*
X1243697Y290510D01*
X1242863Y290093D01*
X1242488Y289802D01*
X1242238Y289385D01*
X1242155Y289010D01*
X1243905D01*
G01X1244880Y291510D02*
X1245463Y289010D01*
X1246130Y291510D01*
X1246797Y289010D01*
X1247380Y291510D01*
G01X1248438Y291093D02*
X1248688Y291343D01*
X1248980Y291468D01*
X1249313Y291510D01*
X1249730Y291427D01*
X1250022Y291218D01*
X1250105Y290968D01*
X1250063Y290718D01*
X1249897Y290510D01*
X1249063Y290093D01*
X1248688Y289802D01*
X1248438Y289385D01*
X1248355Y289010D01*
X1250105D01*
G01X1251538Y290052D02*
X1251830Y290343D01*
X1252080Y290510D01*
X1252413Y290593D01*
X1252705Y290510D01*
X1252913Y290343D01*
X1253080Y290093D01*
X1253122Y289802D01*
X1253080Y289552D01*
X1252913Y289302D01*
X1252663Y289093D01*
X1252372Y289010D01*
X1252038Y289093D01*
X1251747Y289343D01*
X1251580Y289718D01*
X1251538Y290135D01*
X1251622Y290677D01*
X1251747Y290968D01*
X1251955Y291260D01*
X1252247Y291468D01*
X1252538Y291510D01*
X1252830Y291427D01*
X1253038Y291218D01*
G01X1253581Y341273D02*
X1253456Y341023D01*
X1253373Y340731D01*
Y340398D01*
X1253498Y340023D01*
X1253706Y339731D01*
X1253956Y339523D01*
X1254373Y339356D01*
X1254748Y339314D01*
X1255123Y339398D01*
X1255373Y339523D01*
X1255623Y339773D01*
X1255790Y340064D01*
X1255873Y340356D01*
Y340648D01*
X1255790Y340939D01*
X1255665Y341189D01*
X1255498Y341398D01*
G01X1255873Y343373D02*
X1255331Y343456D01*
X1254873Y343581D01*
X1254456Y343748D01*
X1253998Y343956D01*
X1253373Y344289D01*
Y342623D01*
G01X1255873Y345764D02*
X1253373D01*
Y347348D01*
G01X1254581Y346764D02*
Y345764D01*
G01X1255873Y349656D02*
X1255831Y349948D01*
X1255706Y350281D01*
X1255498Y350489D01*
X1255206Y350573D01*
X1254915Y350489D01*
X1254665Y350239D01*
X1254540Y349864D01*
Y349448D01*
X1254456Y349198D01*
X1254248Y348989D01*
X1253956Y348906D01*
X1253665Y349031D01*
X1253456Y349323D01*
X1253373Y349656D01*
X1253456Y349989D01*
X1253665Y350281D01*
X1253956Y350406D01*
X1254248Y350323D01*
X1254456Y350114D01*
X1254540Y349864D01*
Y349448D01*
X1254665Y349073D01*
X1254915Y348823D01*
X1255206Y348739D01*
X1255498Y348823D01*
X1255706Y349031D01*
X1255831Y349364D01*
X1255873Y349656D01*
G01X1257281Y341273D02*
X1257156Y341023D01*
X1257073Y340731D01*
Y340398D01*
X1257198Y340023D01*
X1257406Y339731D01*
X1257656Y339523D01*
X1258073Y339356D01*
X1258448Y339314D01*
X1258823Y339398D01*
X1259073Y339523D01*
X1259323Y339773D01*
X1259490Y340064D01*
X1259573Y340356D01*
Y340648D01*
X1259490Y340939D01*
X1259365Y341189D01*
X1259198Y341398D01*
G01X1259573Y343373D02*
X1259031Y343456D01*
X1258573Y343581D01*
X1258156Y343748D01*
X1257698Y343956D01*
X1257073Y344289D01*
Y342623D01*
G01X1259573Y345764D02*
X1257073D01*
Y347348D01*
G01X1258281Y346764D02*
Y345764D01*
G01X1259573Y349656D02*
X1257073D01*
X1257573Y349156D01*
G01X1259573D02*
Y350156D01*
G01X1257073Y352756D02*
X1257156Y352423D01*
X1257365Y352173D01*
X1257615Y352006D01*
X1257948Y351881D01*
X1258323Y351839D01*
X1258698Y351881D01*
X1259031Y352006D01*
X1259281Y352173D01*
X1259490Y352423D01*
X1259573Y352756D01*
X1259490Y353089D01*
X1259281Y353339D01*
X1259031Y353506D01*
X1258698Y353631D01*
X1258323Y353673D01*
X1257948Y353631D01*
X1257615Y353506D01*
X1257365Y353339D01*
X1257156Y353089D01*
X1257073Y352756D01*
G01X1277790Y287788D02*
X1277665Y287538D01*
X1277582Y287246D01*
Y286913D01*
X1277707Y286538D01*
X1277915Y286246D01*
X1278165Y286038D01*
X1278582Y285871D01*
X1278957Y285829D01*
X1279332Y285913D01*
X1279582Y286038D01*
X1279832Y286288D01*
X1279999Y286579D01*
X1280082Y286871D01*
Y287163D01*
X1279999Y287454D01*
X1279874Y287704D01*
X1279707Y287913D01*
G01X1280082Y289888D02*
X1279540Y289971D01*
X1279082Y290096D01*
X1278665Y290263D01*
X1278207Y290471D01*
X1277582Y290804D01*
Y289138D01*
G01X1280082Y292279D02*
X1277582D01*
Y293863D01*
G01X1278790Y293279D02*
Y292279D01*
G01X1280082Y296171D02*
X1277582D01*
X1278082Y295671D01*
G01X1280082D02*
Y296671D01*
G01Y299188D02*
X1279540Y299271D01*
X1279082Y299396D01*
X1278665Y299563D01*
X1278207Y299771D01*
X1277582Y300104D01*
Y298438D01*
G01X1277420Y305931D02*
X1277295Y305681D01*
X1277212Y305389D01*
Y305056D01*
X1277337Y304681D01*
X1277545Y304389D01*
X1277795Y304181D01*
X1278212Y304014D01*
X1278587Y303972D01*
X1278962Y304056D01*
X1279212Y304181D01*
X1279462Y304431D01*
X1279629Y304722D01*
X1279712Y305014D01*
Y305306D01*
X1279629Y305597D01*
X1279504Y305847D01*
X1279337Y306056D01*
G01X1279712Y308031D02*
X1279170Y308114D01*
X1278712Y308239D01*
X1278295Y308406D01*
X1277837Y308614D01*
X1277212Y308947D01*
Y307281D01*
G01X1279712Y310422D02*
X1277212D01*
Y312006D01*
G01X1278420Y311422D02*
Y310422D01*
G01X1279712Y314314D02*
X1277212D01*
X1277712Y313814D01*
G01X1279712D02*
Y314814D01*
G01X1279337Y316497D02*
X1279545Y316747D01*
X1279670Y317039D01*
X1279712Y317414D01*
X1279629Y317789D01*
X1279462Y318081D01*
X1279170Y318289D01*
X1278837Y318331D01*
X1278504Y318247D01*
X1278295Y318039D01*
X1278129Y317747D01*
X1278087Y317456D01*
X1278129Y317164D01*
X1278295Y316789D01*
X1277212Y316914D01*
Y318039D01*
G01X1240710Y330655D02*
X1240585Y330405D01*
X1240502Y330113D01*
Y329780D01*
X1240627Y329405D01*
X1240835Y329113D01*
X1241085Y328905D01*
X1241502Y328738D01*
X1241877Y328696D01*
X1242252Y328780D01*
X1242502Y328905D01*
X1242752Y329155D01*
X1242919Y329446D01*
X1243002Y329738D01*
Y330030D01*
X1242919Y330321D01*
X1242794Y330571D01*
X1242627Y330780D01*
G01X1243002Y332755D02*
X1242460Y332838D01*
X1242002Y332963D01*
X1241585Y333130D01*
X1241127Y333338D01*
X1240502Y333671D01*
Y332005D01*
G01X1243002Y335146D02*
X1240502D01*
Y336730D01*
G01X1241710Y336146D02*
Y335146D01*
G01X1243002Y339038D02*
X1240502D01*
X1241002Y338538D01*
G01X1243002D02*
Y339538D01*
G01X1242502Y341221D02*
X1242794Y341471D01*
X1242960Y341805D01*
X1243002Y342180D01*
X1242960Y342513D01*
X1242752Y342846D01*
X1242502Y343055D01*
X1242252Y343096D01*
X1241960Y343013D01*
X1241752Y342721D01*
X1241669Y342430D01*
Y342055D01*
G01Y342430D02*
X1241544Y342680D01*
X1241335Y342888D01*
X1241085Y342971D01*
X1240835Y342888D01*
X1240627Y342680D01*
X1240502Y342305D01*
X1240544Y341930D01*
X1240710Y341555D01*
G01X1231489Y341359D02*
X1231719Y341204D01*
X1231987Y341101D01*
X1232294D01*
X1232639Y341256D01*
X1232907Y341514D01*
X1233099Y341824D01*
X1233252Y342341D01*
X1233290Y342806D01*
X1233214Y343271D01*
X1233099Y343581D01*
X1232869Y343891D01*
X1232600Y344098D01*
X1232332Y344201D01*
X1232064D01*
X1231795Y344098D01*
X1231565Y343943D01*
X1231374Y343736D01*
G01X1230114Y344201D02*
Y341101D01*
X1228350Y344201D01*
Y341101D01*
G01X1231489Y325759D02*
X1231719Y325604D01*
X1231987Y325501D01*
X1232294D01*
X1232639Y325656D01*
X1232907Y325914D01*
X1233099Y326224D01*
X1233252Y326741D01*
X1233290Y327206D01*
X1233214Y327671D01*
X1233099Y327981D01*
X1232869Y328291D01*
X1232600Y328498D01*
X1232332Y328601D01*
X1232064D01*
X1231795Y328498D01*
X1231565Y328343D01*
X1231374Y328136D01*
G01X1228465Y328601D02*
X1229999D01*
Y325501D01*
X1228465D01*
G01X1229079Y326999D02*
X1229999D01*
G01X1232025Y311348D02*
X1231872Y311193D01*
X1231757Y310934D01*
X1231680Y310573D01*
X1231757Y310263D01*
X1231910Y310056D01*
X1232179Y309901D01*
X1233214D01*
Y313001D01*
X1231949D01*
X1231680Y312794D01*
X1231527Y312484D01*
X1231450Y312123D01*
X1231527Y311761D01*
X1231757Y311451D01*
X1232025Y311348D01*
X1233214D01*
G01X1230075Y309901D02*
Y312123D01*
X1229922Y312588D01*
X1229615Y312898D01*
X1229232Y313001D01*
X1228849Y312898D01*
X1228542Y312588D01*
X1228389Y312123D01*
Y309901D01*
G01X1232025Y295748D02*
X1231872Y295593D01*
X1231757Y295334D01*
X1231680Y294973D01*
X1231757Y294663D01*
X1231910Y294456D01*
X1232179Y294301D01*
X1233214D01*
Y297401D01*
X1231949D01*
X1231680Y297194D01*
X1231527Y296884D01*
X1231450Y296523D01*
X1231527Y296161D01*
X1231757Y295851D01*
X1232025Y295748D01*
X1233214D01*
G01X1229999Y296781D02*
X1229807Y297091D01*
X1229577Y297298D01*
X1229309Y297401D01*
X1229002Y297298D01*
X1228772Y297091D01*
X1228542Y296781D01*
X1228465Y296368D01*
Y294301D01*
G01X1261180Y402100D02*
Y405200D01*
X1260720Y404580D01*
G01Y402100D02*
X1261640D01*
G01X1273337Y402365D02*
X1273567Y402107D01*
X1273835Y401952D01*
X1274180Y401900D01*
X1274525Y402003D01*
X1274793Y402210D01*
X1274985Y402572D01*
X1275023Y402985D01*
X1274947Y403398D01*
X1274755Y403657D01*
X1274487Y403863D01*
X1274218Y403915D01*
X1273950Y403863D01*
X1273605Y403657D01*
X1273720Y405000D01*
X1274755D01*
G01X1266337Y402520D02*
X1266567Y402158D01*
X1266873Y401952D01*
X1267218Y401900D01*
X1267525Y401952D01*
X1267832Y402210D01*
X1268023Y402520D01*
X1268062Y402830D01*
X1267985Y403192D01*
X1267717Y403450D01*
X1267448Y403553D01*
X1267103D01*
G01X1267448D02*
X1267678Y403708D01*
X1267870Y403967D01*
X1267947Y404277D01*
X1267870Y404587D01*
X1267678Y404845D01*
X1267333Y405000D01*
X1266988Y404948D01*
X1266643Y404742D01*
G01X1239328Y379132D02*
X1237933D01*
X1236228Y378365D01*
G01Y379899D02*
X1237933Y379132D01*
G01X1239328Y382999D02*
Y381465D01*
X1236228D01*
Y382999D01*
G01X1237726Y382385D02*
Y381465D01*
G01X1236228Y384565D02*
X1239328D01*
Y386099D01*
G01X1236228Y387665D02*
X1239328D01*
Y389199D01*
G01Y391532D02*
X1239276Y391225D01*
X1239070Y390957D01*
X1238760Y390727D01*
X1238398Y390574D01*
X1237985Y390497D01*
X1237571D01*
X1237158Y390574D01*
X1236796Y390727D01*
X1236486Y390957D01*
X1236280Y391225D01*
X1236228Y391532D01*
X1236280Y391839D01*
X1236486Y392107D01*
X1236796Y392337D01*
X1237158Y392490D01*
X1237571Y392567D01*
X1237985D01*
X1238398Y392490D01*
X1238760Y392337D01*
X1239070Y392107D01*
X1239276Y391839D01*
X1239328Y391532D01*
G01X1236228Y393482D02*
X1239328Y394019D01*
X1236228Y394632D01*
X1239328Y395245D01*
X1236228Y395782D01*
G01Y400065D02*
X1239328D01*
Y401599D01*
G01Y402974D02*
X1236228Y403932D01*
X1239328Y404890D01*
G01X1238243Y404545D02*
Y403319D01*
G01X1236228Y407032D02*
X1239328D01*
G01X1236228Y406150D02*
Y407914D01*
G01X1236486Y410975D02*
X1236331Y410745D01*
X1236228Y410477D01*
Y410170D01*
X1236383Y409825D01*
X1236641Y409557D01*
X1236951Y409365D01*
X1237468Y409212D01*
X1237933Y409174D01*
X1238398Y409250D01*
X1238708Y409365D01*
X1239018Y409595D01*
X1239225Y409864D01*
X1239328Y410132D01*
Y410400D01*
X1239225Y410669D01*
X1239070Y410899D01*
X1238863Y411090D01*
G01X1239328Y412427D02*
X1236228D01*
G01Y414037D02*
X1239328D01*
G01X1237778D02*
Y412427D01*
G01X1235300Y403600D02*
Y415100D01*
X1240500D01*
Y377300D01*
X1235300D01*
Y403600D01*
G01X1278030Y399800D02*
Y413800D01*
X1258030D01*
Y399800D01*
X1302030D01*
Y406800D01*
G01X1248167Y356950D02*
Y359450D01*
X1249208D01*
X1249542Y359325D01*
X1249750Y359158D01*
X1249833Y358825D01*
X1249750Y358492D01*
X1249500Y358283D01*
X1249208Y358158D01*
X1248167D01*
G01X1249208D02*
X1249833Y356950D01*
G01X1252017D02*
X1252100Y357492D01*
X1252225Y357950D01*
X1252392Y358367D01*
X1252600Y358825D01*
X1252933Y359450D01*
X1251267D01*
G01X1254408Y356950D02*
Y359450D01*
X1255992D01*
G01X1255408Y358242D02*
X1254408D01*
G01X1257592Y357242D02*
X1257883Y357033D01*
X1258217Y356950D01*
X1258550Y357033D01*
X1258842Y357283D01*
X1259050Y357658D01*
X1259133Y358033D01*
Y358492D01*
X1259050Y358867D01*
X1258842Y359200D01*
X1258592Y359367D01*
X1258300Y359450D01*
X1257967Y359367D01*
X1257717Y359200D01*
X1257550Y358950D01*
X1257467Y358617D01*
X1257550Y358325D01*
X1257758Y358033D01*
X1258008Y357867D01*
X1258300Y357825D01*
X1258633Y357908D01*
X1258883Y358117D01*
X1259133Y358492D01*
G01X1238972Y345045D02*
X1236472D01*
Y346086D01*
X1236597Y346420D01*
X1236764Y346628D01*
X1237097Y346711D01*
X1237430Y346628D01*
X1237639Y346378D01*
X1237764Y346086D01*
Y345045D01*
G01Y346086D02*
X1238972Y346711D01*
G01Y348895D02*
X1238430Y348978D01*
X1237972Y349103D01*
X1237555Y349270D01*
X1237097Y349478D01*
X1236472Y349811D01*
Y348145D01*
G01X1238972Y351286D02*
X1236472D01*
Y352870D01*
G01X1237680Y352286D02*
Y351286D01*
G01X1238972Y355178D02*
X1236472D01*
X1236972Y354678D01*
G01X1238972D02*
Y355678D01*
G01X1236889Y357486D02*
X1236639Y357736D01*
X1236514Y358028D01*
X1236472Y358361D01*
X1236555Y358778D01*
X1236764Y359070D01*
X1237014Y359153D01*
X1237264Y359111D01*
X1237472Y358945D01*
X1237889Y358111D01*
X1238180Y357736D01*
X1238597Y357486D01*
X1238972Y357403D01*
Y359153D01*
G01X1242672Y345045D02*
X1240172D01*
Y346086D01*
X1240297Y346420D01*
X1240464Y346628D01*
X1240797Y346711D01*
X1241130Y346628D01*
X1241339Y346378D01*
X1241464Y346086D01*
Y345045D01*
G01Y346086D02*
X1242672Y346711D01*
G01Y348895D02*
X1242130Y348978D01*
X1241672Y349103D01*
X1241255Y349270D01*
X1240797Y349478D01*
X1240172Y349811D01*
Y348145D01*
G01X1242672Y351286D02*
X1240172D01*
Y352870D01*
G01X1241380Y352286D02*
Y351286D01*
G01X1242672Y355178D02*
X1240172D01*
X1240672Y354678D01*
G01X1242672D02*
Y355678D01*
G01X1242172Y357361D02*
X1242464Y357611D01*
X1242630Y357945D01*
X1242672Y358320D01*
X1242630Y358653D01*
X1242422Y358986D01*
X1242172Y359195D01*
X1241922Y359236D01*
X1241630Y359153D01*
X1241422Y358861D01*
X1241339Y358570D01*
Y358195D01*
G01Y358570D02*
X1241214Y358820D01*
X1241005Y359028D01*
X1240755Y359111D01*
X1240505Y359028D01*
X1240297Y358820D01*
X1240172Y358445D01*
X1240214Y358070D01*
X1240380Y357695D01*
G01X1246334Y344967D02*
X1243834D01*
Y346008D01*
X1243959Y346342D01*
X1244126Y346550D01*
X1244459Y346633D01*
X1244792Y346550D01*
X1245001Y346300D01*
X1245126Y346008D01*
Y344967D01*
G01Y346008D02*
X1246334Y346633D01*
G01Y348817D02*
X1245792Y348900D01*
X1245334Y349025D01*
X1244917Y349192D01*
X1244459Y349400D01*
X1243834Y349733D01*
Y348067D01*
G01X1246334Y351208D02*
X1243834D01*
Y352792D01*
G01X1245042Y352208D02*
Y351208D01*
G01X1246334Y355100D02*
X1243834D01*
X1244334Y354600D01*
G01X1246334D02*
Y355600D01*
G01Y358200D02*
X1243834D01*
X1244334Y357700D01*
G01X1246334D02*
Y358700D01*
G01X1274517Y358082D02*
X1274267Y358207D01*
X1273975Y358290D01*
X1273642D01*
X1273267Y358165D01*
X1272975Y357957D01*
X1272767Y357707D01*
X1272600Y357290D01*
X1272558Y356915D01*
X1272642Y356540D01*
X1272767Y356290D01*
X1273017Y356040D01*
X1273308Y355873D01*
X1273600Y355790D01*
X1273892D01*
X1274183Y355873D01*
X1274433Y355998D01*
X1274642Y356165D01*
G01X1276617Y355790D02*
X1276700Y356332D01*
X1276825Y356790D01*
X1276992Y357207D01*
X1277200Y357665D01*
X1277533Y358290D01*
X1275867D01*
G01X1279008Y355790D02*
Y358290D01*
X1280592D01*
G01X1280008Y357082D02*
X1279008D01*
G01X1282192Y356082D02*
X1282483Y355873D01*
X1282817Y355790D01*
X1283150Y355873D01*
X1283442Y356123D01*
X1283650Y356498D01*
X1283733Y356873D01*
Y357332D01*
X1283650Y357707D01*
X1283442Y358040D01*
X1283192Y358207D01*
X1282900Y358290D01*
X1282567Y358207D01*
X1282317Y358040D01*
X1282150Y357790D01*
X1282067Y357457D01*
X1282150Y357165D01*
X1282358Y356873D01*
X1282608Y356707D01*
X1282900Y356665D01*
X1283233Y356748D01*
X1283483Y356957D01*
X1283733Y357332D01*
G01X1271917Y354032D02*
X1271667Y354157D01*
X1271375Y354240D01*
X1271042D01*
X1270667Y354115D01*
X1270375Y353907D01*
X1270167Y353657D01*
X1270000Y353240D01*
X1269958Y352865D01*
X1270042Y352490D01*
X1270167Y352240D01*
X1270417Y351990D01*
X1270708Y351823D01*
X1271000Y351740D01*
X1271292D01*
X1271583Y351823D01*
X1271833Y351948D01*
X1272042Y352115D01*
G01X1274017Y351740D02*
X1274100Y352282D01*
X1274225Y352740D01*
X1274392Y353157D01*
X1274600Y353615D01*
X1274933Y354240D01*
X1273267D01*
G01X1276408Y351740D02*
Y354240D01*
X1277992D01*
G01X1277408Y353032D02*
X1276408D01*
G01X1280300Y351740D02*
Y354240D01*
X1279800Y353740D01*
G01Y351740D02*
X1280800D01*
G01X1282608Y353823D02*
X1282858Y354073D01*
X1283150Y354198D01*
X1283483Y354240D01*
X1283900Y354157D01*
X1284192Y353948D01*
X1284275Y353698D01*
X1284233Y353448D01*
X1284067Y353240D01*
X1283233Y352823D01*
X1282858Y352532D01*
X1282608Y352115D01*
X1282525Y351740D01*
X1284275D01*
G01X1233204Y396859D02*
Y393759D01*
X1232438D01*
X1232131Y393914D01*
X1231901Y394121D01*
X1231709Y394431D01*
X1231556Y394792D01*
X1231518Y395309D01*
X1231556Y395826D01*
X1231709Y396187D01*
X1231901Y396497D01*
X1232131Y396704D01*
X1232438Y396859D01*
X1233204D01*
G01X1229261D02*
Y395464D01*
X1230028Y393759D01*
G01X1228494D02*
X1229261Y395464D01*
G01X1233175Y391001D02*
Y387901D01*
X1232409D01*
X1232102Y388056D01*
X1231872Y388263D01*
X1231680Y388573D01*
X1231527Y388934D01*
X1231489Y389451D01*
X1231527Y389968D01*
X1231680Y390329D01*
X1231872Y390639D01*
X1232102Y390846D01*
X1232409Y391001D01*
X1233175D01*
G01X1230075Y387901D02*
Y390123D01*
X1229922Y390588D01*
X1229615Y390898D01*
X1229232Y391001D01*
X1228849Y390898D01*
X1228542Y390588D01*
X1228389Y390123D01*
Y387901D01*
G01X1233175Y375401D02*
Y372301D01*
X1232409D01*
X1232102Y372456D01*
X1231872Y372663D01*
X1231680Y372973D01*
X1231527Y373334D01*
X1231489Y373851D01*
X1231527Y374368D01*
X1231680Y374729D01*
X1231872Y375039D01*
X1232102Y375246D01*
X1232409Y375401D01*
X1233175D01*
G01X1229999Y374781D02*
X1229807Y375091D01*
X1229577Y375298D01*
X1229309Y375401D01*
X1229002Y375298D01*
X1228772Y375091D01*
X1228542Y374781D01*
X1228465Y374368D01*
Y372301D01*
G01X1233175Y359801D02*
Y356701D01*
X1232409D01*
X1232102Y356856D01*
X1231872Y357063D01*
X1231680Y357373D01*
X1231527Y357734D01*
X1231489Y358251D01*
X1231527Y358768D01*
X1231680Y359129D01*
X1231872Y359439D01*
X1232102Y359646D01*
X1232409Y359801D01*
X1233175D01*
G01X1230190D02*
X1229232Y356701D01*
X1228274Y359801D01*
G01X1228619Y358716D02*
X1229845D01*
G01X1280312Y426310D02*
Y429410D01*
X1281768D01*
G01X1281232Y427912D02*
X1280312D01*
G01X1284140Y426310D02*
Y429410D01*
X1283680Y428790D01*
G01Y426310D02*
X1284600D01*
G01X1281380Y409100D02*
X1281648Y409152D01*
X1281955Y409307D01*
X1282147Y409565D01*
X1282223Y409927D01*
X1282147Y410288D01*
X1281917Y410598D01*
X1281572Y410753D01*
X1281188D01*
X1280958Y410857D01*
X1280767Y411115D01*
X1280690Y411477D01*
X1280805Y411838D01*
X1281073Y412097D01*
X1281380Y412200D01*
X1281687Y412097D01*
X1281955Y411838D01*
X1282070Y411477D01*
X1281993Y411115D01*
X1281802Y410857D01*
X1281572Y410753D01*
X1281188D01*
X1280843Y410598D01*
X1280613Y410288D01*
X1280537Y409927D01*
X1280613Y409565D01*
X1280805Y409307D01*
X1281112Y409152D01*
X1281380Y409100D01*
G01X1260252Y411683D02*
X1260482Y411993D01*
X1260750Y412148D01*
X1261057Y412200D01*
X1261440Y412097D01*
X1261708Y411838D01*
X1261785Y411528D01*
X1261747Y411218D01*
X1261593Y410960D01*
X1260827Y410443D01*
X1260482Y410082D01*
X1260252Y409565D01*
X1260175Y409100D01*
X1261785D01*
G01X1273652Y410192D02*
X1273920Y410553D01*
X1274150Y410760D01*
X1274457Y410863D01*
X1274725Y410760D01*
X1274917Y410553D01*
X1275070Y410243D01*
X1275108Y409882D01*
X1275070Y409572D01*
X1274917Y409262D01*
X1274687Y409003D01*
X1274418Y408900D01*
X1274112Y409003D01*
X1273843Y409313D01*
X1273690Y409778D01*
X1273652Y410295D01*
X1273728Y410967D01*
X1273843Y411328D01*
X1274035Y411690D01*
X1274303Y411948D01*
X1274572Y412000D01*
X1274840Y411897D01*
X1275032Y411638D01*
G01X1267840Y408900D02*
Y412000D01*
X1266422Y409778D01*
X1268338D01*
G01X1248193Y416577D02*
X1248385Y416267D01*
X1248615Y416060D01*
X1248883Y415957D01*
X1249190Y416060D01*
X1249420Y416267D01*
X1249650Y416577D01*
X1249727Y416990D01*
Y419057D01*
G01X1251983Y415957D02*
X1252060Y416629D01*
X1252175Y417197D01*
X1252328Y417714D01*
X1252520Y418282D01*
X1252827Y419057D01*
X1251293D01*
G01X1255390Y417507D02*
X1256157D01*
Y416577D01*
X1255927Y416267D01*
X1255658Y416060D01*
X1255275Y415957D01*
X1254892Y416060D01*
X1254623Y416267D01*
X1254393Y416577D01*
X1254240Y416939D01*
X1254163Y417352D01*
Y417714D01*
X1254240Y418024D01*
X1254393Y418385D01*
X1254623Y418695D01*
X1254853Y418902D01*
X1255160Y419057D01*
X1255428D01*
X1255735Y418954D01*
X1255965Y418747D01*
G01X1257417Y416577D02*
X1257647Y416215D01*
X1257953Y416009D01*
X1258298Y415957D01*
X1258605Y416009D01*
X1258912Y416267D01*
X1259103Y416577D01*
X1259142Y416887D01*
X1259065Y417249D01*
X1258797Y417507D01*
X1258528Y417610D01*
X1258183D01*
G01X1258528D02*
X1258758Y417765D01*
X1258950Y418024D01*
X1259027Y418334D01*
X1258950Y418644D01*
X1258758Y418902D01*
X1258413Y419057D01*
X1258068Y419005D01*
X1257723Y418799D01*
G01X1261283Y415389D02*
X1261437Y416060D01*
G01X1263693Y416577D02*
X1263885Y416267D01*
X1264115Y416060D01*
X1264383Y415957D01*
X1264690Y416060D01*
X1264920Y416267D01*
X1265150Y416577D01*
X1265227Y416990D01*
Y419057D01*
G01X1267560Y415957D02*
X1267828Y416009D01*
X1268135Y416164D01*
X1268327Y416422D01*
X1268403Y416784D01*
X1268327Y417145D01*
X1268097Y417455D01*
X1267752Y417610D01*
X1267368D01*
X1267138Y417714D01*
X1266947Y417972D01*
X1266870Y418334D01*
X1266985Y418695D01*
X1267253Y418954D01*
X1267560Y419057D01*
X1267867Y418954D01*
X1268135Y418695D01*
X1268250Y418334D01*
X1268173Y417972D01*
X1267982Y417714D01*
X1267752Y417610D01*
X1267368D01*
X1267023Y417455D01*
X1266793Y417145D01*
X1266717Y416784D01*
X1266793Y416422D01*
X1266985Y416164D01*
X1267292Y416009D01*
X1267560Y415957D01*
G01X1270890Y417507D02*
X1271657D01*
Y416577D01*
X1271427Y416267D01*
X1271158Y416060D01*
X1270775Y415957D01*
X1270392Y416060D01*
X1270123Y416267D01*
X1269893Y416577D01*
X1269740Y416939D01*
X1269663Y417352D01*
Y417714D01*
X1269740Y418024D01*
X1269893Y418385D01*
X1270123Y418695D01*
X1270353Y418902D01*
X1270660Y419057D01*
X1270928D01*
X1271235Y418954D01*
X1271465Y418747D01*
G01X1273032Y418540D02*
X1273262Y418850D01*
X1273530Y419005D01*
X1273837Y419057D01*
X1274220Y418954D01*
X1274488Y418695D01*
X1274565Y418385D01*
X1274527Y418075D01*
X1274373Y417817D01*
X1273607Y417300D01*
X1273262Y416939D01*
X1273032Y416422D01*
X1272955Y415957D01*
X1274565D01*
G01X1276783Y415389D02*
X1276937Y416060D01*
G01X1279193Y416577D02*
X1279385Y416267D01*
X1279615Y416060D01*
X1279883Y415957D01*
X1280190Y416060D01*
X1280420Y416267D01*
X1280650Y416577D01*
X1280727Y416990D01*
Y419057D01*
G01X1282408Y416319D02*
X1282677Y416060D01*
X1282983Y415957D01*
X1283290Y416060D01*
X1283558Y416370D01*
X1283750Y416835D01*
X1283827Y417300D01*
Y417869D01*
X1283750Y418334D01*
X1283558Y418747D01*
X1283328Y418954D01*
X1283060Y419057D01*
X1282753Y418954D01*
X1282523Y418747D01*
X1282370Y418437D01*
X1282293Y418024D01*
X1282370Y417662D01*
X1282562Y417300D01*
X1282792Y417094D01*
X1283060Y417042D01*
X1283367Y417145D01*
X1283597Y417404D01*
X1283827Y417869D01*
G01X1286390Y417507D02*
X1287157D01*
Y416577D01*
X1286927Y416267D01*
X1286658Y416060D01*
X1286275Y415957D01*
X1285892Y416060D01*
X1285623Y416267D01*
X1285393Y416577D01*
X1285240Y416939D01*
X1285163Y417352D01*
Y417714D01*
X1285240Y418024D01*
X1285393Y418385D01*
X1285623Y418695D01*
X1285853Y418902D01*
X1286160Y419057D01*
X1286428D01*
X1286735Y418954D01*
X1286965Y418747D01*
G01X1289260Y415957D02*
Y419057D01*
X1288800Y418437D01*
G01Y415957D02*
X1289720D01*
G01X1294693D02*
Y419057D01*
X1295613D01*
X1295920Y418902D01*
X1296150Y418540D01*
X1296227Y418127D01*
X1296150Y417714D01*
X1295958Y417404D01*
X1295613Y417249D01*
X1294693D01*
G01X1298560Y418024D02*
Y415957D01*
G01Y418850D02*
X1298483Y418902D01*
Y419005D01*
X1298560Y419057D01*
X1298637Y419005D01*
Y418902D01*
X1298560Y418850D01*
G01X1301008Y415957D02*
Y418024D01*
G01Y417507D02*
X1301162Y417765D01*
X1301392Y417972D01*
X1301698Y418024D01*
X1301967Y417972D01*
X1302197Y417765D01*
X1302312Y417404D01*
Y415957D01*
G01X1304760D02*
X1304530Y416009D01*
X1304300Y416215D01*
X1304147Y416577D01*
X1304070Y416990D01*
X1304147Y417404D01*
X1304300Y417765D01*
X1304530Y417972D01*
X1304760Y418024D01*
X1304990Y417972D01*
X1305220Y417765D01*
X1305373Y417404D01*
X1305412Y416990D01*
X1305373Y416577D01*
X1305220Y416215D01*
X1304990Y416009D01*
X1304760Y415957D01*
G01X1307208Y418024D02*
Y416577D01*
X1307362Y416215D01*
X1307592Y416009D01*
X1307860Y415957D01*
X1308128Y416009D01*
X1308358Y416215D01*
X1308512Y416577D01*
G01Y415957D02*
Y418024D01*
G01X1310960Y419057D02*
Y415957D01*
G01X1310423Y418024D02*
X1311497D01*
G01X1278030Y413800D02*
X1302030D01*
Y406800D01*
X1258030D01*
G01X1280867Y465959D02*
X1280617Y466084D01*
X1280325Y466167D01*
X1279992D01*
X1279617Y466042D01*
X1279325Y465834D01*
X1279117Y465584D01*
X1278950Y465167D01*
X1278908Y464792D01*
X1278992Y464417D01*
X1279117Y464167D01*
X1279367Y463917D01*
X1279658Y463750D01*
X1279950Y463667D01*
X1280242D01*
X1280533Y463750D01*
X1280783Y463875D01*
X1280992Y464042D01*
G01X1283050Y463667D02*
X1283342Y463709D01*
X1283675Y463834D01*
X1283883Y464042D01*
X1283967Y464334D01*
X1283883Y464625D01*
X1283633Y464875D01*
X1283258Y465000D01*
X1282842D01*
X1282592Y465084D01*
X1282383Y465292D01*
X1282300Y465584D01*
X1282425Y465875D01*
X1282717Y466084D01*
X1283050Y466167D01*
X1283383Y466084D01*
X1283675Y465875D01*
X1283800Y465584D01*
X1283717Y465292D01*
X1283508Y465084D01*
X1283258Y465000D01*
X1282842D01*
X1282467Y464875D01*
X1282217Y464625D01*
X1282133Y464334D01*
X1282217Y464042D01*
X1282425Y463834D01*
X1282758Y463709D01*
X1283050Y463667D01*
G01X1286650D02*
Y466167D01*
X1285108Y464375D01*
X1287192D01*
G01X1288333Y464167D02*
X1288583Y463875D01*
X1288917Y463709D01*
X1289292Y463667D01*
X1289625Y463709D01*
X1289958Y463917D01*
X1290167Y464167D01*
X1290208Y464417D01*
X1290125Y464709D01*
X1289833Y464917D01*
X1289542Y465000D01*
X1289167D01*
G01X1289542D02*
X1289792Y465125D01*
X1290000Y465334D01*
X1290083Y465584D01*
X1290000Y465834D01*
X1289792Y466042D01*
X1289417Y466167D01*
X1289042Y466125D01*
X1288667Y465959D01*
G01X1248967Y443596D02*
X1248717Y443721D01*
X1248425Y443804D01*
X1248092D01*
X1247717Y443679D01*
X1247425Y443471D01*
X1247217Y443221D01*
X1247050Y442804D01*
X1247008Y442429D01*
X1247092Y442054D01*
X1247217Y441804D01*
X1247467Y441554D01*
X1247758Y441387D01*
X1248050Y441304D01*
X1248342D01*
X1248633Y441387D01*
X1248883Y441512D01*
X1249092Y441679D01*
G01X1251150Y441304D02*
X1251442Y441346D01*
X1251775Y441471D01*
X1251983Y441679D01*
X1252067Y441971D01*
X1251983Y442262D01*
X1251733Y442512D01*
X1251358Y442637D01*
X1250942D01*
X1250692Y442721D01*
X1250483Y442929D01*
X1250400Y443221D01*
X1250525Y443512D01*
X1250817Y443721D01*
X1251150Y443804D01*
X1251483Y443721D01*
X1251775Y443512D01*
X1251900Y443221D01*
X1251817Y442929D01*
X1251608Y442721D01*
X1251358Y442637D01*
X1250942D01*
X1250567Y442512D01*
X1250317Y442262D01*
X1250233Y441971D01*
X1250317Y441679D01*
X1250525Y441471D01*
X1250858Y441346D01*
X1251150Y441304D01*
G01X1253333Y441804D02*
X1253583Y441512D01*
X1253917Y441346D01*
X1254292Y441304D01*
X1254625Y441346D01*
X1254958Y441554D01*
X1255167Y441804D01*
X1255208Y442054D01*
X1255125Y442346D01*
X1254833Y442554D01*
X1254542Y442637D01*
X1254167D01*
G01X1254542D02*
X1254792Y442762D01*
X1255000Y442971D01*
X1255083Y443221D01*
X1255000Y443471D01*
X1254792Y443679D01*
X1254417Y443804D01*
X1254042Y443762D01*
X1253667Y443596D01*
G01X1256558Y443387D02*
X1256808Y443637D01*
X1257100Y443762D01*
X1257433Y443804D01*
X1257850Y443721D01*
X1258142Y443512D01*
X1258225Y443262D01*
X1258183Y443012D01*
X1258017Y442804D01*
X1257183Y442387D01*
X1256808Y442096D01*
X1256558Y441679D01*
X1256475Y441304D01*
X1258225D01*
G01X1250767Y448796D02*
X1250517Y448921D01*
X1250225Y449004D01*
X1249892D01*
X1249517Y448879D01*
X1249225Y448671D01*
X1249017Y448421D01*
X1248850Y448004D01*
X1248808Y447629D01*
X1248892Y447254D01*
X1249017Y447004D01*
X1249267Y446754D01*
X1249558Y446587D01*
X1249850Y446504D01*
X1250142D01*
X1250433Y446587D01*
X1250683Y446712D01*
X1250892Y446879D01*
G01X1252950Y446504D02*
X1253242Y446546D01*
X1253575Y446671D01*
X1253783Y446879D01*
X1253867Y447171D01*
X1253783Y447462D01*
X1253533Y447712D01*
X1253158Y447837D01*
X1252742D01*
X1252492Y447921D01*
X1252283Y448129D01*
X1252200Y448421D01*
X1252325Y448712D01*
X1252617Y448921D01*
X1252950Y449004D01*
X1253283Y448921D01*
X1253575Y448712D01*
X1253700Y448421D01*
X1253617Y448129D01*
X1253408Y447921D01*
X1253158Y447837D01*
X1252742D01*
X1252367Y447712D01*
X1252117Y447462D01*
X1252033Y447171D01*
X1252117Y446879D01*
X1252325Y446671D01*
X1252658Y446546D01*
X1252950Y446504D01*
G01X1255133Y447004D02*
X1255383Y446712D01*
X1255717Y446546D01*
X1256092Y446504D01*
X1256425Y446546D01*
X1256758Y446754D01*
X1256967Y447004D01*
X1257008Y447254D01*
X1256925Y447546D01*
X1256633Y447754D01*
X1256342Y447837D01*
X1255967D01*
G01X1256342D02*
X1256592Y447962D01*
X1256800Y448171D01*
X1256883Y448421D01*
X1256800Y448671D01*
X1256592Y448879D01*
X1256217Y449004D01*
X1255842Y448962D01*
X1255467Y448796D01*
G01X1258233Y447004D02*
X1258483Y446712D01*
X1258817Y446546D01*
X1259192Y446504D01*
X1259525Y446546D01*
X1259858Y446754D01*
X1260067Y447004D01*
X1260108Y447254D01*
X1260025Y447546D01*
X1259733Y447754D01*
X1259442Y447837D01*
X1259067D01*
G01X1259442D02*
X1259692Y447962D01*
X1259900Y448171D01*
X1259983Y448421D01*
X1259900Y448671D01*
X1259692Y448879D01*
X1259317Y449004D01*
X1258942Y448962D01*
X1258567Y448796D01*
G01X1261817Y443606D02*
X1261567Y443731D01*
X1261275Y443814D01*
X1260942D01*
X1260567Y443689D01*
X1260275Y443481D01*
X1260067Y443231D01*
X1259900Y442814D01*
X1259858Y442439D01*
X1259942Y442064D01*
X1260067Y441814D01*
X1260317Y441564D01*
X1260608Y441397D01*
X1260900Y441314D01*
X1261192D01*
X1261483Y441397D01*
X1261733Y441522D01*
X1261942Y441689D01*
G01X1263208Y442356D02*
X1263500Y442647D01*
X1263750Y442814D01*
X1264083Y442897D01*
X1264375Y442814D01*
X1264583Y442647D01*
X1264750Y442397D01*
X1264792Y442106D01*
X1264750Y441856D01*
X1264583Y441606D01*
X1264333Y441397D01*
X1264042Y441314D01*
X1263708Y441397D01*
X1263417Y441647D01*
X1263250Y442022D01*
X1263208Y442439D01*
X1263292Y442981D01*
X1263417Y443272D01*
X1263625Y443564D01*
X1263917Y443772D01*
X1264208Y443814D01*
X1264500Y443731D01*
X1264708Y443522D01*
G01X1267433Y442647D02*
X1267600Y442772D01*
X1267725Y442981D01*
X1267808Y443272D01*
X1267725Y443522D01*
X1267558Y443689D01*
X1267267Y443814D01*
X1266142D01*
Y441314D01*
X1267517D01*
X1267808Y441481D01*
X1267975Y441731D01*
X1268058Y442022D01*
X1267975Y442314D01*
X1267725Y442564D01*
X1267433Y442647D01*
X1266142D01*
G01X1270200Y441314D02*
Y443814D01*
X1269700Y443314D01*
G01Y441314D02*
X1270700D01*
G01X1273800D02*
Y443814D01*
X1272258Y442022D01*
X1274342D01*
G01X1263617Y448806D02*
X1263367Y448931D01*
X1263075Y449014D01*
X1262742D01*
X1262367Y448889D01*
X1262075Y448681D01*
X1261867Y448431D01*
X1261700Y448014D01*
X1261658Y447639D01*
X1261742Y447264D01*
X1261867Y447014D01*
X1262117Y446764D01*
X1262408Y446597D01*
X1262700Y446514D01*
X1262992D01*
X1263283Y446597D01*
X1263533Y446722D01*
X1263742Y446889D01*
G01X1265008Y447556D02*
X1265300Y447847D01*
X1265550Y448014D01*
X1265883Y448097D01*
X1266175Y448014D01*
X1266383Y447847D01*
X1266550Y447597D01*
X1266592Y447306D01*
X1266550Y447056D01*
X1266383Y446806D01*
X1266133Y446597D01*
X1265842Y446514D01*
X1265508Y446597D01*
X1265217Y446847D01*
X1265050Y447222D01*
X1265008Y447639D01*
X1265092Y448181D01*
X1265217Y448472D01*
X1265425Y448764D01*
X1265717Y448972D01*
X1266008Y449014D01*
X1266300Y448931D01*
X1266508Y448722D01*
G01X1269233Y447847D02*
X1269400Y447972D01*
X1269525Y448181D01*
X1269608Y448472D01*
X1269525Y448722D01*
X1269358Y448889D01*
X1269067Y449014D01*
X1267942D01*
Y446514D01*
X1269317D01*
X1269608Y446681D01*
X1269775Y446931D01*
X1269858Y447222D01*
X1269775Y447514D01*
X1269525Y447764D01*
X1269233Y447847D01*
X1267942D01*
G01X1272000Y446514D02*
Y449014D01*
X1271500Y448514D01*
G01Y446514D02*
X1272500D01*
G01X1274183Y447014D02*
X1274433Y446722D01*
X1274767Y446556D01*
X1275142Y446514D01*
X1275475Y446556D01*
X1275808Y446764D01*
X1276017Y447014D01*
X1276058Y447264D01*
X1275975Y447556D01*
X1275683Y447764D01*
X1275392Y447847D01*
X1275017D01*
G01X1275392D02*
X1275642Y447972D01*
X1275850Y448181D01*
X1275933Y448431D01*
X1275850Y448681D01*
X1275642Y448889D01*
X1275267Y449014D01*
X1274892Y448972D01*
X1274517Y448806D01*
G01X1255847Y459332D02*
X1255597Y459457D01*
X1255305Y459540D01*
X1254972D01*
X1254597Y459415D01*
X1254305Y459207D01*
X1254097Y458957D01*
X1253930Y458540D01*
X1253888Y458165D01*
X1253972Y457790D01*
X1254097Y457540D01*
X1254347Y457290D01*
X1254638Y457123D01*
X1254930Y457040D01*
X1255222D01*
X1255513Y457123D01*
X1255763Y457248D01*
X1255972Y457415D01*
G01X1258030Y457040D02*
X1258322Y457082D01*
X1258655Y457207D01*
X1258863Y457415D01*
X1258947Y457707D01*
X1258863Y457998D01*
X1258613Y458248D01*
X1258238Y458373D01*
X1257822D01*
X1257572Y458457D01*
X1257363Y458665D01*
X1257280Y458957D01*
X1257405Y459248D01*
X1257697Y459457D01*
X1258030Y459540D01*
X1258363Y459457D01*
X1258655Y459248D01*
X1258780Y458957D01*
X1258697Y458665D01*
X1258488Y458457D01*
X1258238Y458373D01*
X1257822D01*
X1257447Y458248D01*
X1257197Y457998D01*
X1257113Y457707D01*
X1257197Y457415D01*
X1257405Y457207D01*
X1257738Y457082D01*
X1258030Y457040D01*
G01X1261630D02*
Y459540D01*
X1260088Y457748D01*
X1262172D01*
G01X1264230Y459540D02*
X1263897Y459457D01*
X1263647Y459248D01*
X1263480Y458998D01*
X1263355Y458665D01*
X1263313Y458290D01*
X1263355Y457915D01*
X1263480Y457582D01*
X1263647Y457332D01*
X1263897Y457123D01*
X1264230Y457040D01*
X1264563Y457123D01*
X1264813Y457332D01*
X1264980Y457582D01*
X1265105Y457915D01*
X1265147Y458290D01*
X1265105Y458665D01*
X1264980Y458998D01*
X1264813Y459248D01*
X1264563Y459457D01*
X1264230Y459540D01*
G01X1256247Y455632D02*
X1255997Y455757D01*
X1255705Y455840D01*
X1255372D01*
X1254997Y455715D01*
X1254705Y455507D01*
X1254497Y455257D01*
X1254330Y454840D01*
X1254288Y454465D01*
X1254372Y454090D01*
X1254497Y453840D01*
X1254747Y453590D01*
X1255038Y453423D01*
X1255330Y453340D01*
X1255622D01*
X1255913Y453423D01*
X1256163Y453548D01*
X1256372Y453715D01*
G01X1258430Y453340D02*
X1258722Y453382D01*
X1259055Y453507D01*
X1259263Y453715D01*
X1259347Y454007D01*
X1259263Y454298D01*
X1259013Y454548D01*
X1258638Y454673D01*
X1258222D01*
X1257972Y454757D01*
X1257763Y454965D01*
X1257680Y455257D01*
X1257805Y455548D01*
X1258097Y455757D01*
X1258430Y455840D01*
X1258763Y455757D01*
X1259055Y455548D01*
X1259180Y455257D01*
X1259097Y454965D01*
X1258888Y454757D01*
X1258638Y454673D01*
X1258222D01*
X1257847Y454548D01*
X1257597Y454298D01*
X1257513Y454007D01*
X1257597Y453715D01*
X1257805Y453507D01*
X1258138Y453382D01*
X1258430Y453340D01*
G01X1262030D02*
Y455840D01*
X1260488Y454048D01*
X1262572D01*
G01X1264630Y453340D02*
Y455840D01*
X1264130Y455340D01*
G01Y453340D02*
X1265130D01*
G01X1269047Y459332D02*
X1268797Y459457D01*
X1268505Y459540D01*
X1268172D01*
X1267797Y459415D01*
X1267505Y459207D01*
X1267297Y458957D01*
X1267130Y458540D01*
X1267088Y458165D01*
X1267172Y457790D01*
X1267297Y457540D01*
X1267547Y457290D01*
X1267838Y457123D01*
X1268130Y457040D01*
X1268422D01*
X1268713Y457123D01*
X1268963Y457248D01*
X1269172Y457415D01*
G01X1270438Y458082D02*
X1270730Y458373D01*
X1270980Y458540D01*
X1271313Y458623D01*
X1271605Y458540D01*
X1271813Y458373D01*
X1271980Y458123D01*
X1272022Y457832D01*
X1271980Y457582D01*
X1271813Y457332D01*
X1271563Y457123D01*
X1271272Y457040D01*
X1270938Y457123D01*
X1270647Y457373D01*
X1270480Y457748D01*
X1270438Y458165D01*
X1270522Y458707D01*
X1270647Y458998D01*
X1270855Y459290D01*
X1271147Y459498D01*
X1271438Y459540D01*
X1271730Y459457D01*
X1271938Y459248D01*
G01X1274663Y458373D02*
X1274830Y458498D01*
X1274955Y458707D01*
X1275038Y458998D01*
X1274955Y459248D01*
X1274788Y459415D01*
X1274497Y459540D01*
X1273372D01*
Y457040D01*
X1274747D01*
X1275038Y457207D01*
X1275205Y457457D01*
X1275288Y457748D01*
X1275205Y458040D01*
X1274955Y458290D01*
X1274663Y458373D01*
X1273372D01*
G01X1277430Y457040D02*
Y459540D01*
X1276930Y459040D01*
G01Y457040D02*
X1277930D01*
G01X1280530D02*
Y459540D01*
X1280030Y459040D01*
G01Y457040D02*
X1281030D01*
G01X1268847Y455632D02*
X1268597Y455757D01*
X1268305Y455840D01*
X1267972D01*
X1267597Y455715D01*
X1267305Y455507D01*
X1267097Y455257D01*
X1266930Y454840D01*
X1266888Y454465D01*
X1266972Y454090D01*
X1267097Y453840D01*
X1267347Y453590D01*
X1267638Y453423D01*
X1267930Y453340D01*
X1268222D01*
X1268513Y453423D01*
X1268763Y453548D01*
X1268972Y453715D01*
G01X1270238Y454382D02*
X1270530Y454673D01*
X1270780Y454840D01*
X1271113Y454923D01*
X1271405Y454840D01*
X1271613Y454673D01*
X1271780Y454423D01*
X1271822Y454132D01*
X1271780Y453882D01*
X1271613Y453632D01*
X1271363Y453423D01*
X1271072Y453340D01*
X1270738Y453423D01*
X1270447Y453673D01*
X1270280Y454048D01*
X1270238Y454465D01*
X1270322Y455007D01*
X1270447Y455298D01*
X1270655Y455590D01*
X1270947Y455798D01*
X1271238Y455840D01*
X1271530Y455757D01*
X1271738Y455548D01*
G01X1274463Y454673D02*
X1274630Y454798D01*
X1274755Y455007D01*
X1274838Y455298D01*
X1274755Y455548D01*
X1274588Y455715D01*
X1274297Y455840D01*
X1273172D01*
Y453340D01*
X1274547D01*
X1274838Y453507D01*
X1275005Y453757D01*
X1275088Y454048D01*
X1275005Y454340D01*
X1274755Y454590D01*
X1274463Y454673D01*
X1273172D01*
G01X1277230Y453340D02*
Y455840D01*
X1276730Y455340D01*
G01Y453340D02*
X1277730D01*
G01X1279538Y455423D02*
X1279788Y455673D01*
X1280080Y455798D01*
X1280413Y455840D01*
X1280830Y455757D01*
X1281122Y455548D01*
X1281205Y455298D01*
X1281163Y455048D01*
X1280997Y454840D01*
X1280163Y454423D01*
X1279788Y454132D01*
X1279538Y453715D01*
X1279455Y453340D01*
X1281205D01*
G01X1224940Y436398D02*
Y438898D01*
X1225774D01*
X1226107Y438773D01*
X1226357Y438606D01*
X1226565Y438356D01*
X1226732Y438065D01*
X1226774Y437648D01*
X1226732Y437231D01*
X1226565Y436940D01*
X1226357Y436690D01*
X1226107Y436523D01*
X1225774Y436398D01*
X1224940D01*
G01X1228082Y436731D02*
X1228415Y436523D01*
X1228790Y436398D01*
X1229124D01*
X1229457Y436523D01*
X1229707Y436731D01*
X1229832Y437023D01*
X1229749Y437315D01*
X1229540Y437565D01*
X1229165Y437731D01*
X1228665Y437815D01*
X1228374Y437981D01*
X1228249Y438273D01*
X1228332Y438565D01*
X1228540Y438773D01*
X1228832Y438898D01*
X1229124D01*
X1229415Y438815D01*
X1229665Y438606D01*
G01X1231349Y436690D02*
X1231640Y436481D01*
X1231974Y436398D01*
X1232307Y436481D01*
X1232599Y436731D01*
X1232807Y437106D01*
X1232890Y437481D01*
Y437940D01*
X1232807Y438315D01*
X1232599Y438648D01*
X1232349Y438815D01*
X1232057Y438898D01*
X1231724Y438815D01*
X1231474Y438648D01*
X1231307Y438398D01*
X1231224Y438065D01*
X1231307Y437773D01*
X1231515Y437481D01*
X1231765Y437315D01*
X1232057Y437273D01*
X1232390Y437356D01*
X1232640Y437565D01*
X1232890Y437940D01*
G01X1234115Y436398D02*
X1235157Y438898D01*
X1236199Y436398D01*
G01X1235824Y437273D02*
X1234490D01*
G01X1238174Y436398D02*
X1238257Y436940D01*
X1238382Y437398D01*
X1238549Y437815D01*
X1238757Y438273D01*
X1239090Y438898D01*
X1237424D01*
G01X1229493Y440736D02*
Y443236D01*
X1230327D01*
X1230660Y443111D01*
X1230910Y442944D01*
X1231118Y442694D01*
X1231285Y442403D01*
X1231327Y441986D01*
X1231285Y441569D01*
X1231118Y441278D01*
X1230910Y441028D01*
X1230660Y440861D01*
X1230327Y440736D01*
X1229493D01*
G01X1232635Y441069D02*
X1232968Y440861D01*
X1233343Y440736D01*
X1233677D01*
X1234010Y440861D01*
X1234260Y441069D01*
X1234385Y441361D01*
X1234302Y441653D01*
X1234093Y441903D01*
X1233718Y442069D01*
X1233218Y442153D01*
X1232927Y442319D01*
X1232802Y442611D01*
X1232885Y442903D01*
X1233093Y443111D01*
X1233385Y443236D01*
X1233677D01*
X1233968Y443153D01*
X1234218Y442944D01*
G01X1235902Y441028D02*
X1236193Y440819D01*
X1236527Y440736D01*
X1236860Y440819D01*
X1237152Y441069D01*
X1237360Y441444D01*
X1237443Y441819D01*
Y442278D01*
X1237360Y442653D01*
X1237152Y442986D01*
X1236902Y443153D01*
X1236610Y443236D01*
X1236277Y443153D01*
X1236027Y442986D01*
X1235860Y442736D01*
X1235777Y442403D01*
X1235860Y442111D01*
X1236068Y441819D01*
X1236318Y441653D01*
X1236610Y441611D01*
X1236943Y441694D01*
X1237193Y441903D01*
X1237443Y442278D01*
G01X1238668Y440736D02*
X1239710Y443236D01*
X1240752Y440736D01*
G01X1240377Y441611D02*
X1239043D01*
G01X1243310Y440736D02*
Y443236D01*
X1241768Y441444D01*
X1243852D01*
G01X1280333Y435917D02*
X1280583Y436125D01*
X1280750Y436375D01*
X1280833Y436667D01*
X1280750Y437000D01*
X1280583Y437250D01*
X1280333Y437500D01*
X1280000Y437583D01*
X1278333D01*
G01X1279791Y439058D02*
X1279500Y439350D01*
X1279333Y439600D01*
X1279250Y439933D01*
X1279333Y440225D01*
X1279500Y440433D01*
X1279750Y440600D01*
X1280041Y440642D01*
X1280291Y440600D01*
X1280541Y440433D01*
X1280750Y440183D01*
X1280833Y439892D01*
X1280750Y439558D01*
X1280500Y439267D01*
X1280125Y439100D01*
X1279708Y439058D01*
X1279166Y439142D01*
X1278875Y439267D01*
X1278583Y439475D01*
X1278375Y439767D01*
X1278333Y440058D01*
X1278416Y440350D01*
X1278625Y440558D01*
G01X1279500Y443283D02*
X1279375Y443450D01*
X1279166Y443575D01*
X1278875Y443658D01*
X1278625Y443575D01*
X1278458Y443408D01*
X1278333Y443117D01*
Y441992D01*
X1280833D01*
Y443367D01*
X1280666Y443658D01*
X1280416Y443825D01*
X1280125Y443908D01*
X1279833Y443825D01*
X1279583Y443575D01*
X1279500Y443283D01*
Y441992D01*
G01X1280833Y446050D02*
X1278333D01*
X1278833Y445550D01*
G01X1280833D02*
Y446550D01*
G01X1230117Y407122D02*
X1231651D01*
Y404022D01*
X1230117D01*
G01X1230731Y405520D02*
X1231651D01*
G01X1227017Y407122D02*
X1228551D01*
Y404022D01*
X1227017D01*
G01X1227631Y405520D02*
X1228551D01*
G01X1229094Y452687D02*
Y455187D01*
X1229928D01*
X1230261Y455062D01*
X1230511Y454895D01*
X1230719Y454645D01*
X1230886Y454354D01*
X1230928Y453937D01*
X1230886Y453520D01*
X1230719Y453229D01*
X1230511Y452979D01*
X1230261Y452812D01*
X1229928Y452687D01*
X1229094D01*
G01X1232236Y453020D02*
X1232569Y452812D01*
X1232944Y452687D01*
X1233278D01*
X1233611Y452812D01*
X1233861Y453020D01*
X1233986Y453312D01*
X1233903Y453604D01*
X1233694Y453854D01*
X1233319Y454020D01*
X1232819Y454104D01*
X1232528Y454270D01*
X1232403Y454562D01*
X1232486Y454854D01*
X1232694Y455062D01*
X1232986Y455187D01*
X1233278D01*
X1233569Y455104D01*
X1233819Y454895D01*
G01X1235503Y452979D02*
X1235794Y452770D01*
X1236128Y452687D01*
X1236461Y452770D01*
X1236753Y453020D01*
X1236961Y453395D01*
X1237044Y453770D01*
Y454229D01*
X1236961Y454604D01*
X1236753Y454937D01*
X1236503Y455104D01*
X1236211Y455187D01*
X1235878Y455104D01*
X1235628Y454937D01*
X1235461Y454687D01*
X1235378Y454354D01*
X1235461Y454062D01*
X1235669Y453770D01*
X1235919Y453604D01*
X1236211Y453562D01*
X1236544Y453645D01*
X1236794Y453854D01*
X1237044Y454229D01*
G01X1238269Y452687D02*
X1239311Y455187D01*
X1240353Y452687D01*
G01X1239978Y453562D02*
X1238644D01*
G01X1242411Y452687D02*
Y455187D01*
X1241911Y454687D01*
G01Y452687D02*
X1242911D01*
G01X1229181Y444492D02*
Y446992D01*
X1230015D01*
X1230348Y446867D01*
X1230598Y446700D01*
X1230806Y446450D01*
X1230973Y446159D01*
X1231015Y445742D01*
X1230973Y445325D01*
X1230806Y445034D01*
X1230598Y444784D01*
X1230348Y444617D01*
X1230015Y444492D01*
X1229181D01*
G01X1232323Y444825D02*
X1232656Y444617D01*
X1233031Y444492D01*
X1233365D01*
X1233698Y444617D01*
X1233948Y444825D01*
X1234073Y445117D01*
X1233990Y445409D01*
X1233781Y445659D01*
X1233406Y445825D01*
X1232906Y445909D01*
X1232615Y446075D01*
X1232490Y446367D01*
X1232573Y446659D01*
X1232781Y446867D01*
X1233073Y446992D01*
X1233365D01*
X1233656Y446909D01*
X1233906Y446700D01*
G01X1235590Y444784D02*
X1235881Y444575D01*
X1236215Y444492D01*
X1236548Y444575D01*
X1236840Y444825D01*
X1237048Y445200D01*
X1237131Y445575D01*
Y446034D01*
X1237048Y446409D01*
X1236840Y446742D01*
X1236590Y446909D01*
X1236298Y446992D01*
X1235965Y446909D01*
X1235715Y446742D01*
X1235548Y446492D01*
X1235465Y446159D01*
X1235548Y445867D01*
X1235756Y445575D01*
X1236006Y445409D01*
X1236298Y445367D01*
X1236631Y445450D01*
X1236881Y445659D01*
X1237131Y446034D01*
G01X1238356Y444492D02*
X1239398Y446992D01*
X1240440Y444492D01*
G01X1240065Y445367D02*
X1238731D01*
G01X1241581Y444992D02*
X1241831Y444700D01*
X1242165Y444534D01*
X1242540Y444492D01*
X1242873Y444534D01*
X1243206Y444742D01*
X1243415Y444992D01*
X1243456Y445242D01*
X1243373Y445534D01*
X1243081Y445742D01*
X1242790Y445825D01*
X1242415D01*
G01X1242790D02*
X1243040Y445950D01*
X1243248Y446159D01*
X1243331Y446409D01*
X1243248Y446659D01*
X1243040Y446867D01*
X1242665Y446992D01*
X1242290Y446950D01*
X1241915Y446784D01*
G01X1229233Y448498D02*
Y450998D01*
X1230067D01*
X1230400Y450873D01*
X1230650Y450706D01*
X1230858Y450456D01*
X1231025Y450165D01*
X1231067Y449748D01*
X1231025Y449331D01*
X1230858Y449040D01*
X1230650Y448790D01*
X1230400Y448623D01*
X1230067Y448498D01*
X1229233D01*
G01X1232375Y448831D02*
X1232708Y448623D01*
X1233083Y448498D01*
X1233417D01*
X1233750Y448623D01*
X1234000Y448831D01*
X1234125Y449123D01*
X1234042Y449415D01*
X1233833Y449665D01*
X1233458Y449831D01*
X1232958Y449915D01*
X1232667Y450081D01*
X1232542Y450373D01*
X1232625Y450665D01*
X1232833Y450873D01*
X1233125Y450998D01*
X1233417D01*
X1233708Y450915D01*
X1233958Y450706D01*
G01X1235642Y448790D02*
X1235933Y448581D01*
X1236267Y448498D01*
X1236600Y448581D01*
X1236892Y448831D01*
X1237100Y449206D01*
X1237183Y449581D01*
Y450040D01*
X1237100Y450415D01*
X1236892Y450748D01*
X1236642Y450915D01*
X1236350Y450998D01*
X1236017Y450915D01*
X1235767Y450748D01*
X1235600Y450498D01*
X1235517Y450165D01*
X1235600Y449873D01*
X1235808Y449581D01*
X1236058Y449415D01*
X1236350Y449373D01*
X1236683Y449456D01*
X1236933Y449665D01*
X1237183Y450040D01*
G01X1238408Y448498D02*
X1239450Y450998D01*
X1240492Y448498D01*
G01X1240117Y449373D02*
X1238783D01*
G01X1241758Y450581D02*
X1242008Y450831D01*
X1242300Y450956D01*
X1242633Y450998D01*
X1243050Y450915D01*
X1243342Y450706D01*
X1243425Y450456D01*
X1243383Y450206D01*
X1243217Y449998D01*
X1242383Y449581D01*
X1242008Y449290D01*
X1241758Y448873D01*
X1241675Y448498D01*
X1243425D01*
G01X1222528Y427831D02*
X1222486Y427498D01*
X1222320Y427206D01*
X1222070Y426956D01*
X1221778Y426789D01*
X1221445Y426706D01*
X1221111D01*
X1220778Y426789D01*
X1220486Y426956D01*
X1220236Y427206D01*
X1220070Y427498D01*
X1220028Y427831D01*
X1220070Y428164D01*
X1220236Y428456D01*
X1220486Y428706D01*
X1220778Y428873D01*
X1221111Y428956D01*
X1221445D01*
X1221778Y428873D01*
X1222070Y428706D01*
X1222320Y428456D01*
X1222486Y428164D01*
X1222528Y427831D01*
G01X1221861Y428164D02*
X1222528Y428664D01*
G01X1222236Y430223D02*
X1222445Y430514D01*
X1222528Y430848D01*
X1222445Y431181D01*
X1222195Y431473D01*
X1221820Y431681D01*
X1221445Y431764D01*
X1220986D01*
X1220611Y431681D01*
X1220278Y431473D01*
X1220111Y431223D01*
X1220028Y430931D01*
X1220111Y430598D01*
X1220278Y430348D01*
X1220528Y430181D01*
X1220861Y430098D01*
X1221153Y430181D01*
X1221445Y430389D01*
X1221611Y430639D01*
X1221653Y430931D01*
X1221570Y431264D01*
X1221361Y431514D01*
X1220986Y431764D01*
G01X1222528Y432989D02*
X1220028Y434031D01*
X1222528Y435073D01*
G01X1221653Y434698D02*
Y433364D01*
G01X1222028Y436214D02*
X1222320Y436464D01*
X1222486Y436798D01*
X1222528Y437173D01*
X1222486Y437506D01*
X1222278Y437839D01*
X1222028Y438048D01*
X1221778Y438089D01*
X1221486Y438006D01*
X1221278Y437714D01*
X1221195Y437423D01*
Y437048D01*
G01Y437423D02*
X1221070Y437673D01*
X1220861Y437881D01*
X1220611Y437964D01*
X1220361Y437881D01*
X1220153Y437673D01*
X1220028Y437298D01*
X1220070Y436923D01*
X1220236Y436548D01*
G01X1279708Y496967D02*
X1279583Y496717D01*
X1279500Y496425D01*
Y496092D01*
X1279625Y495717D01*
X1279833Y495425D01*
X1280083Y495217D01*
X1280500Y495050D01*
X1280875Y495008D01*
X1281250Y495092D01*
X1281500Y495217D01*
X1281750Y495467D01*
X1281917Y495758D01*
X1282000Y496050D01*
Y496342D01*
X1281917Y496633D01*
X1281792Y496883D01*
X1281625Y497092D01*
G01X1280958Y498358D02*
X1280667Y498650D01*
X1280500Y498900D01*
X1280417Y499233D01*
X1280500Y499525D01*
X1280667Y499733D01*
X1280917Y499900D01*
X1281208Y499942D01*
X1281458Y499900D01*
X1281708Y499733D01*
X1281917Y499483D01*
X1282000Y499192D01*
X1281917Y498858D01*
X1281667Y498567D01*
X1281292Y498400D01*
X1280875Y498358D01*
X1280333Y498442D01*
X1280042Y498567D01*
X1279750Y498775D01*
X1279542Y499067D01*
X1279500Y499358D01*
X1279583Y499650D01*
X1279792Y499858D01*
G01X1280667Y502583D02*
X1280542Y502750D01*
X1280333Y502875D01*
X1280042Y502958D01*
X1279792Y502875D01*
X1279625Y502708D01*
X1279500Y502417D01*
Y501292D01*
X1282000D01*
Y502667D01*
X1281833Y502958D01*
X1281583Y503125D01*
X1281292Y503208D01*
X1281000Y503125D01*
X1280750Y502875D01*
X1280667Y502583D01*
Y501292D01*
G01X1281500Y504433D02*
X1281792Y504683D01*
X1281958Y505017D01*
X1282000Y505392D01*
X1281958Y505725D01*
X1281750Y506058D01*
X1281500Y506267D01*
X1281250Y506308D01*
X1280958Y506225D01*
X1280750Y505933D01*
X1280667Y505642D01*
Y505267D01*
G01Y505642D02*
X1280542Y505892D01*
X1280333Y506100D01*
X1280083Y506183D01*
X1279833Y506100D01*
X1279625Y505892D01*
X1279500Y505517D01*
X1279542Y505142D01*
X1279708Y504767D01*
G01X1277000Y491417D02*
X1274500D01*
Y492458D01*
X1274625Y492792D01*
X1274792Y493000D01*
X1275125Y493083D01*
X1275458Y493000D01*
X1275667Y492750D01*
X1275792Y492458D01*
Y491417D01*
G01Y492458D02*
X1277000Y493083D01*
G01X1275958Y494558D02*
X1275667Y494850D01*
X1275500Y495100D01*
X1275417Y495433D01*
X1275500Y495725D01*
X1275667Y495933D01*
X1275917Y496100D01*
X1276208Y496142D01*
X1276458Y496100D01*
X1276708Y495933D01*
X1276917Y495683D01*
X1277000Y495392D01*
X1276917Y495058D01*
X1276667Y494767D01*
X1276292Y494600D01*
X1275875Y494558D01*
X1275333Y494642D01*
X1275042Y494767D01*
X1274750Y494975D01*
X1274542Y495267D01*
X1274500Y495558D01*
X1274583Y495850D01*
X1274792Y496058D01*
G01X1275667Y498783D02*
X1275542Y498950D01*
X1275333Y499075D01*
X1275042Y499158D01*
X1274792Y499075D01*
X1274625Y498908D01*
X1274500Y498617D01*
Y497492D01*
X1277000D01*
Y498867D01*
X1276833Y499158D01*
X1276583Y499325D01*
X1276292Y499408D01*
X1276000Y499325D01*
X1275750Y499075D01*
X1275667Y498783D01*
Y497492D01*
G01X1276625Y500633D02*
X1276833Y500883D01*
X1276958Y501175D01*
X1277000Y501550D01*
X1276917Y501925D01*
X1276750Y502217D01*
X1276458Y502425D01*
X1276125Y502467D01*
X1275792Y502383D01*
X1275583Y502175D01*
X1275417Y501883D01*
X1275375Y501592D01*
X1275417Y501300D01*
X1275583Y500925D01*
X1274500Y501050D01*
Y502175D01*
G01X1233117Y511400D02*
Y513900D01*
X1234158D01*
X1234492Y513775D01*
X1234700Y513608D01*
X1234783Y513275D01*
X1234700Y512942D01*
X1234450Y512733D01*
X1234158Y512608D01*
X1233117D01*
G01X1234158D02*
X1234783Y511400D01*
G01X1236258Y512442D02*
X1236550Y512733D01*
X1236800Y512900D01*
X1237133Y512983D01*
X1237425Y512900D01*
X1237633Y512733D01*
X1237800Y512483D01*
X1237842Y512192D01*
X1237800Y511942D01*
X1237633Y511692D01*
X1237383Y511483D01*
X1237092Y511400D01*
X1236758Y511483D01*
X1236467Y511733D01*
X1236300Y512108D01*
X1236258Y512525D01*
X1236342Y513067D01*
X1236467Y513358D01*
X1236675Y513650D01*
X1236967Y513858D01*
X1237258Y513900D01*
X1237550Y513817D01*
X1237758Y513608D01*
G01X1240483Y512733D02*
X1240650Y512858D01*
X1240775Y513067D01*
X1240858Y513358D01*
X1240775Y513608D01*
X1240608Y513775D01*
X1240317Y513900D01*
X1239192D01*
Y511400D01*
X1240567D01*
X1240858Y511567D01*
X1241025Y511817D01*
X1241108Y512108D01*
X1241025Y512400D01*
X1240775Y512650D01*
X1240483Y512733D01*
X1239192D01*
G01X1242458Y513483D02*
X1242708Y513733D01*
X1243000Y513858D01*
X1243333Y513900D01*
X1243750Y513817D01*
X1244042Y513608D01*
X1244125Y513358D01*
X1244083Y513108D01*
X1243917Y512900D01*
X1243083Y512483D01*
X1242708Y512192D01*
X1242458Y511775D01*
X1242375Y511400D01*
X1244125D01*
G01X1273500Y489817D02*
X1271000D01*
Y490858D01*
X1271125Y491192D01*
X1271292Y491400D01*
X1271625Y491483D01*
X1271958Y491400D01*
X1272167Y491150D01*
X1272292Y490858D01*
Y489817D01*
G01Y490858D02*
X1273500Y491483D01*
G01X1272458Y492958D02*
X1272167Y493250D01*
X1272000Y493500D01*
X1271917Y493833D01*
X1272000Y494125D01*
X1272167Y494333D01*
X1272417Y494500D01*
X1272708Y494542D01*
X1272958Y494500D01*
X1273208Y494333D01*
X1273417Y494083D01*
X1273500Y493792D01*
X1273417Y493458D01*
X1273167Y493167D01*
X1272792Y493000D01*
X1272375Y492958D01*
X1271833Y493042D01*
X1271542Y493167D01*
X1271250Y493375D01*
X1271042Y493667D01*
X1271000Y493958D01*
X1271083Y494250D01*
X1271292Y494458D01*
G01X1272167Y497183D02*
X1272042Y497350D01*
X1271833Y497475D01*
X1271542Y497558D01*
X1271292Y497475D01*
X1271125Y497308D01*
X1271000Y497017D01*
Y495892D01*
X1273500D01*
Y497267D01*
X1273333Y497558D01*
X1273083Y497725D01*
X1272792Y497808D01*
X1272500Y497725D01*
X1272250Y497475D01*
X1272167Y497183D01*
Y495892D01*
G01X1273500Y500450D02*
X1271000D01*
X1272792Y498908D01*
Y500992D01*
G01X1266562Y497583D02*
X1264062D01*
Y498624D01*
X1264187Y498958D01*
X1264354Y499166D01*
X1264687Y499249D01*
X1265020Y499166D01*
X1265229Y498916D01*
X1265354Y498624D01*
Y497583D01*
G01Y498624D02*
X1266562Y499249D01*
G01X1265520Y500724D02*
X1265229Y501016D01*
X1265062Y501266D01*
X1264979Y501599D01*
X1265062Y501891D01*
X1265229Y502099D01*
X1265479Y502266D01*
X1265770Y502308D01*
X1266020Y502266D01*
X1266270Y502099D01*
X1266479Y501849D01*
X1266562Y501558D01*
X1266479Y501224D01*
X1266229Y500933D01*
X1265854Y500766D01*
X1265437Y500724D01*
X1264895Y500808D01*
X1264604Y500933D01*
X1264312Y501141D01*
X1264104Y501433D01*
X1264062Y501724D01*
X1264145Y502016D01*
X1264354Y502224D01*
G01X1265229Y504949D02*
X1265104Y505116D01*
X1264895Y505241D01*
X1264604Y505324D01*
X1264354Y505241D01*
X1264187Y505074D01*
X1264062Y504783D01*
Y503658D01*
X1266562D01*
Y505033D01*
X1266395Y505324D01*
X1266145Y505491D01*
X1265854Y505574D01*
X1265562Y505491D01*
X1265312Y505241D01*
X1265229Y504949D01*
Y503658D01*
G01X1266062Y506799D02*
X1266354Y507049D01*
X1266520Y507383D01*
X1266562Y507758D01*
X1266520Y508091D01*
X1266312Y508424D01*
X1266062Y508633D01*
X1265812Y508674D01*
X1265520Y508591D01*
X1265312Y508299D01*
X1265229Y508008D01*
Y507633D01*
G01Y508008D02*
X1265104Y508258D01*
X1264895Y508466D01*
X1264645Y508549D01*
X1264395Y508466D01*
X1264187Y508258D01*
X1264062Y507883D01*
X1264104Y507508D01*
X1264270Y507133D01*
G01X1227467Y514940D02*
Y517440D01*
X1228508D01*
X1228842Y517315D01*
X1229050Y517148D01*
X1229133Y516815D01*
X1229050Y516482D01*
X1228800Y516273D01*
X1228508Y516148D01*
X1227467D01*
G01X1228508D02*
X1229133Y514940D01*
G01X1230608Y515982D02*
X1230900Y516273D01*
X1231150Y516440D01*
X1231483Y516523D01*
X1231775Y516440D01*
X1231983Y516273D01*
X1232150Y516023D01*
X1232192Y515732D01*
X1232150Y515482D01*
X1231983Y515232D01*
X1231733Y515023D01*
X1231442Y514940D01*
X1231108Y515023D01*
X1230817Y515273D01*
X1230650Y515648D01*
X1230608Y516065D01*
X1230692Y516607D01*
X1230817Y516898D01*
X1231025Y517190D01*
X1231317Y517398D01*
X1231608Y517440D01*
X1231900Y517357D01*
X1232108Y517148D01*
G01X1234833Y516273D02*
X1235000Y516398D01*
X1235125Y516607D01*
X1235208Y516898D01*
X1235125Y517148D01*
X1234958Y517315D01*
X1234667Y517440D01*
X1233542D01*
Y514940D01*
X1234917D01*
X1235208Y515107D01*
X1235375Y515357D01*
X1235458Y515648D01*
X1235375Y515940D01*
X1235125Y516190D01*
X1234833Y516273D01*
X1233542D01*
G01X1237600Y514940D02*
Y517440D01*
X1237100Y516940D01*
G01Y514940D02*
X1238100D01*
G01X1280167Y469958D02*
X1279917Y470083D01*
X1279625Y470166D01*
X1279292D01*
X1278917Y470041D01*
X1278625Y469833D01*
X1278417Y469583D01*
X1278250Y469166D01*
X1278208Y468791D01*
X1278292Y468416D01*
X1278417Y468166D01*
X1278667Y467916D01*
X1278958Y467749D01*
X1279250Y467666D01*
X1279542D01*
X1279833Y467749D01*
X1280083Y467874D01*
X1280292Y468041D01*
G01X1282350Y467666D02*
X1282642Y467708D01*
X1282975Y467833D01*
X1283183Y468041D01*
X1283267Y468333D01*
X1283183Y468624D01*
X1282933Y468874D01*
X1282558Y468999D01*
X1282142D01*
X1281892Y469083D01*
X1281683Y469291D01*
X1281600Y469583D01*
X1281725Y469874D01*
X1282017Y470083D01*
X1282350Y470166D01*
X1282683Y470083D01*
X1282975Y469874D01*
X1283100Y469583D01*
X1283017Y469291D01*
X1282808Y469083D01*
X1282558Y468999D01*
X1282142D01*
X1281767Y468874D01*
X1281517Y468624D01*
X1281433Y468333D01*
X1281517Y468041D01*
X1281725Y467833D01*
X1282058Y467708D01*
X1282350Y467666D01*
G01X1285950D02*
Y470166D01*
X1284408Y468374D01*
X1286492D01*
G01X1287758Y469749D02*
X1288008Y469999D01*
X1288300Y470124D01*
X1288633Y470166D01*
X1289050Y470083D01*
X1289342Y469874D01*
X1289425Y469624D01*
X1289383Y469374D01*
X1289217Y469166D01*
X1288383Y468749D01*
X1288008Y468458D01*
X1287758Y468041D01*
X1287675Y467666D01*
X1289425D01*
G01X1226867Y489692D02*
X1226617Y489817D01*
X1226325Y489900D01*
X1225992D01*
X1225617Y489775D01*
X1225325Y489567D01*
X1225117Y489317D01*
X1224950Y488900D01*
X1224908Y488525D01*
X1224992Y488150D01*
X1225117Y487900D01*
X1225367Y487650D01*
X1225658Y487483D01*
X1225950Y487400D01*
X1226242D01*
X1226533Y487483D01*
X1226783Y487608D01*
X1226992Y487775D01*
G01X1229050Y487400D02*
X1229342Y487442D01*
X1229675Y487567D01*
X1229883Y487775D01*
X1229967Y488067D01*
X1229883Y488358D01*
X1229633Y488608D01*
X1229258Y488733D01*
X1228842D01*
X1228592Y488817D01*
X1228383Y489025D01*
X1228300Y489317D01*
X1228425Y489608D01*
X1228717Y489817D01*
X1229050Y489900D01*
X1229383Y489817D01*
X1229675Y489608D01*
X1229800Y489317D01*
X1229717Y489025D01*
X1229508Y488817D01*
X1229258Y488733D01*
X1228842D01*
X1228467Y488608D01*
X1228217Y488358D01*
X1228133Y488067D01*
X1228217Y487775D01*
X1228425Y487567D01*
X1228758Y487442D01*
X1229050Y487400D01*
G01X1231233Y487900D02*
X1231483Y487608D01*
X1231817Y487442D01*
X1232192Y487400D01*
X1232525Y487442D01*
X1232858Y487650D01*
X1233067Y487900D01*
X1233108Y488150D01*
X1233025Y488442D01*
X1232733Y488650D01*
X1232442Y488733D01*
X1232067D01*
G01X1232442D02*
X1232692Y488858D01*
X1232900Y489067D01*
X1232983Y489317D01*
X1232900Y489567D01*
X1232692Y489775D01*
X1232317Y489900D01*
X1231942Y489858D01*
X1231567Y489692D01*
G01X1235250Y489900D02*
X1234917Y489817D01*
X1234667Y489608D01*
X1234500Y489358D01*
X1234375Y489025D01*
X1234333Y488650D01*
X1234375Y488275D01*
X1234500Y487942D01*
X1234667Y487692D01*
X1234917Y487483D01*
X1235250Y487400D01*
X1235583Y487483D01*
X1235833Y487692D01*
X1236000Y487942D01*
X1236125Y488275D01*
X1236167Y488650D01*
X1236125Y489025D01*
X1236000Y489358D01*
X1235833Y489608D01*
X1235583Y489817D01*
X1235250Y489900D01*
G01X1241437Y489692D02*
X1241187Y489817D01*
X1240895Y489900D01*
X1240562D01*
X1240187Y489775D01*
X1239895Y489567D01*
X1239687Y489317D01*
X1239520Y488900D01*
X1239478Y488525D01*
X1239562Y488150D01*
X1239687Y487900D01*
X1239937Y487650D01*
X1240228Y487483D01*
X1240520Y487400D01*
X1240812D01*
X1241103Y487483D01*
X1241353Y487608D01*
X1241562Y487775D01*
G01X1242828Y488442D02*
X1243120Y488733D01*
X1243370Y488900D01*
X1243703Y488983D01*
X1243995Y488900D01*
X1244203Y488733D01*
X1244370Y488483D01*
X1244412Y488192D01*
X1244370Y487942D01*
X1244203Y487692D01*
X1243953Y487483D01*
X1243662Y487400D01*
X1243328Y487483D01*
X1243037Y487733D01*
X1242870Y488108D01*
X1242828Y488525D01*
X1242912Y489067D01*
X1243037Y489358D01*
X1243245Y489650D01*
X1243537Y489858D01*
X1243828Y489900D01*
X1244120Y489817D01*
X1244328Y489608D01*
G01X1247053Y488733D02*
X1247220Y488858D01*
X1247345Y489067D01*
X1247428Y489358D01*
X1247345Y489608D01*
X1247178Y489775D01*
X1246887Y489900D01*
X1245762D01*
Y487400D01*
X1247137D01*
X1247428Y487567D01*
X1247595Y487817D01*
X1247678Y488108D01*
X1247595Y488400D01*
X1247345Y488650D01*
X1247053Y488733D01*
X1245762D01*
G01X1250320Y487400D02*
Y489900D01*
X1248778Y488108D01*
X1250862D01*
G01X1226967Y486092D02*
X1226717Y486217D01*
X1226425Y486300D01*
X1226092D01*
X1225717Y486175D01*
X1225425Y485967D01*
X1225217Y485717D01*
X1225050Y485300D01*
X1225008Y484925D01*
X1225092Y484550D01*
X1225217Y484300D01*
X1225467Y484050D01*
X1225758Y483883D01*
X1226050Y483800D01*
X1226342D01*
X1226633Y483883D01*
X1226883Y484008D01*
X1227092Y484175D01*
G01X1229150Y483800D02*
X1229442Y483842D01*
X1229775Y483967D01*
X1229983Y484175D01*
X1230067Y484467D01*
X1229983Y484758D01*
X1229733Y485008D01*
X1229358Y485133D01*
X1228942D01*
X1228692Y485217D01*
X1228483Y485425D01*
X1228400Y485717D01*
X1228525Y486008D01*
X1228817Y486217D01*
X1229150Y486300D01*
X1229483Y486217D01*
X1229775Y486008D01*
X1229900Y485717D01*
X1229817Y485425D01*
X1229608Y485217D01*
X1229358Y485133D01*
X1228942D01*
X1228567Y485008D01*
X1228317Y484758D01*
X1228233Y484467D01*
X1228317Y484175D01*
X1228525Y483967D01*
X1228858Y483842D01*
X1229150Y483800D01*
G01X1231333Y484300D02*
X1231583Y484008D01*
X1231917Y483842D01*
X1232292Y483800D01*
X1232625Y483842D01*
X1232958Y484050D01*
X1233167Y484300D01*
X1233208Y484550D01*
X1233125Y484842D01*
X1232833Y485050D01*
X1232542Y485133D01*
X1232167D01*
G01X1232542D02*
X1232792Y485258D01*
X1233000Y485467D01*
X1233083Y485717D01*
X1233000Y485967D01*
X1232792Y486175D01*
X1232417Y486300D01*
X1232042Y486258D01*
X1231667Y486092D01*
G01X1235350Y483800D02*
Y486300D01*
X1234850Y485800D01*
G01Y483800D02*
X1235850D01*
G01X1241567Y486092D02*
X1241317Y486217D01*
X1241025Y486300D01*
X1240692D01*
X1240317Y486175D01*
X1240025Y485967D01*
X1239817Y485717D01*
X1239650Y485300D01*
X1239608Y484925D01*
X1239692Y484550D01*
X1239817Y484300D01*
X1240067Y484050D01*
X1240358Y483883D01*
X1240650Y483800D01*
X1240942D01*
X1241233Y483883D01*
X1241483Y484008D01*
X1241692Y484175D01*
G01X1242958Y484842D02*
X1243250Y485133D01*
X1243500Y485300D01*
X1243833Y485383D01*
X1244125Y485300D01*
X1244333Y485133D01*
X1244500Y484883D01*
X1244542Y484592D01*
X1244500Y484342D01*
X1244333Y484092D01*
X1244083Y483883D01*
X1243792Y483800D01*
X1243458Y483883D01*
X1243167Y484133D01*
X1243000Y484508D01*
X1242958Y484925D01*
X1243042Y485467D01*
X1243167Y485758D01*
X1243375Y486050D01*
X1243667Y486258D01*
X1243958Y486300D01*
X1244250Y486217D01*
X1244458Y486008D01*
G01X1247183Y485133D02*
X1247350Y485258D01*
X1247475Y485467D01*
X1247558Y485758D01*
X1247475Y486008D01*
X1247308Y486175D01*
X1247017Y486300D01*
X1245892D01*
Y483800D01*
X1247267D01*
X1247558Y483967D01*
X1247725Y484217D01*
X1247808Y484508D01*
X1247725Y484800D01*
X1247475Y485050D01*
X1247183Y485133D01*
X1245892D01*
G01X1249033Y484175D02*
X1249283Y483967D01*
X1249575Y483842D01*
X1249950Y483800D01*
X1250325Y483883D01*
X1250617Y484050D01*
X1250825Y484342D01*
X1250867Y484675D01*
X1250783Y485008D01*
X1250575Y485217D01*
X1250283Y485383D01*
X1249992Y485425D01*
X1249700Y485383D01*
X1249325Y485217D01*
X1249450Y486300D01*
X1250575D01*
G01X1223900Y493400D02*
Y491150D01*
X1253800D01*
Y492200D01*
G01Y508200D02*
Y509250D01*
X1223900D01*
Y507000D01*
G01X1258850D02*
Y508200D01*
X1246850D01*
Y507000D01*
G01X1258850Y493400D02*
Y492200D01*
X1246850D01*
Y493400D01*
G01X1260362Y515957D02*
Y519057D01*
X1259902Y518437D01*
G01Y515957D02*
X1260822D01*
G01X1263922D02*
Y519057D01*
X1262504Y516835D01*
X1264420D01*
G01X1267022Y515957D02*
Y519057D01*
X1265604Y516835D01*
X1267520D01*
G01X1270986Y545750D02*
X1295376D01*
Y520160D01*
X1270986D01*
G01X1226336Y548181D02*
X1226211Y547931D01*
X1226128Y547639D01*
Y547306D01*
X1226253Y546931D01*
X1226461Y546639D01*
X1226711Y546431D01*
X1227128Y546264D01*
X1227503Y546222D01*
X1227878Y546306D01*
X1228128Y546431D01*
X1228378Y546681D01*
X1228545Y546972D01*
X1228628Y547264D01*
Y547556D01*
X1228545Y547847D01*
X1228420Y548097D01*
X1228253Y548306D01*
G01X1227586Y549572D02*
X1227295Y549864D01*
X1227128Y550114D01*
X1227045Y550447D01*
X1227128Y550739D01*
X1227295Y550947D01*
X1227545Y551114D01*
X1227836Y551156D01*
X1228086Y551114D01*
X1228336Y550947D01*
X1228545Y550697D01*
X1228628Y550406D01*
X1228545Y550072D01*
X1228295Y549781D01*
X1227920Y549614D01*
X1227503Y549572D01*
X1226961Y549656D01*
X1226670Y549781D01*
X1226378Y549989D01*
X1226170Y550281D01*
X1226128Y550572D01*
X1226211Y550864D01*
X1226420Y551072D01*
G01X1228628Y552422D02*
X1226128Y553464D01*
X1228628Y554506D01*
G01X1227753Y554131D02*
Y552797D01*
G01X1227586Y555772D02*
X1227295Y556064D01*
X1227128Y556314D01*
X1227045Y556647D01*
X1227128Y556939D01*
X1227295Y557147D01*
X1227545Y557314D01*
X1227836Y557356D01*
X1228086Y557314D01*
X1228336Y557147D01*
X1228545Y556897D01*
X1228628Y556606D01*
X1228545Y556272D01*
X1228295Y555981D01*
X1227920Y555814D01*
X1227503Y555772D01*
X1226961Y555856D01*
X1226670Y555981D01*
X1226378Y556189D01*
X1226170Y556481D01*
X1226128Y556772D01*
X1226211Y557064D01*
X1226420Y557272D01*
G01X1231431Y548255D02*
X1231306Y548005D01*
X1231223Y547713D01*
Y547380D01*
X1231348Y547005D01*
X1231556Y546713D01*
X1231806Y546505D01*
X1232223Y546338D01*
X1232598Y546296D01*
X1232973Y546380D01*
X1233223Y546505D01*
X1233473Y546755D01*
X1233640Y547046D01*
X1233723Y547338D01*
Y547630D01*
X1233640Y547921D01*
X1233515Y548171D01*
X1233348Y548380D01*
G01X1232681Y549646D02*
X1232390Y549938D01*
X1232223Y550188D01*
X1232140Y550521D01*
X1232223Y550813D01*
X1232390Y551021D01*
X1232640Y551188D01*
X1232931Y551230D01*
X1233181Y551188D01*
X1233431Y551021D01*
X1233640Y550771D01*
X1233723Y550480D01*
X1233640Y550146D01*
X1233390Y549855D01*
X1233015Y549688D01*
X1232598Y549646D01*
X1232056Y549730D01*
X1231765Y549855D01*
X1231473Y550063D01*
X1231265Y550355D01*
X1231223Y550646D01*
X1231306Y550938D01*
X1231515Y551146D01*
G01X1233723Y552496D02*
X1231223Y553538D01*
X1233723Y554580D01*
G01X1232848Y554205D02*
Y552871D01*
G01X1233723Y556555D02*
X1233181Y556638D01*
X1232723Y556763D01*
X1232306Y556930D01*
X1231848Y557138D01*
X1231223Y557471D01*
Y555805D01*
G01X1234795Y590905D02*
X1234545Y591030D01*
X1234253Y591113D01*
X1233920D01*
X1233545Y590988D01*
X1233253Y590780D01*
X1233045Y590530D01*
X1232878Y590113D01*
X1232836Y589738D01*
X1232920Y589363D01*
X1233045Y589113D01*
X1233295Y588863D01*
X1233586Y588696D01*
X1233878Y588613D01*
X1234170D01*
X1234461Y588696D01*
X1234711Y588821D01*
X1234920Y588988D01*
G01X1236186Y589655D02*
X1236478Y589946D01*
X1236728Y590113D01*
X1237061Y590196D01*
X1237353Y590113D01*
X1237561Y589946D01*
X1237728Y589696D01*
X1237770Y589405D01*
X1237728Y589155D01*
X1237561Y588905D01*
X1237311Y588696D01*
X1237020Y588613D01*
X1236686Y588696D01*
X1236395Y588946D01*
X1236228Y589321D01*
X1236186Y589738D01*
X1236270Y590280D01*
X1236395Y590571D01*
X1236603Y590863D01*
X1236895Y591071D01*
X1237186Y591113D01*
X1237478Y591030D01*
X1237686Y590821D01*
G01X1239036Y588613D02*
X1240078Y591113D01*
X1241120Y588613D01*
G01X1240745Y589488D02*
X1239411D01*
G01X1242261Y589113D02*
X1242511Y588821D01*
X1242845Y588655D01*
X1243220Y588613D01*
X1243553Y588655D01*
X1243886Y588863D01*
X1244095Y589113D01*
X1244136Y589363D01*
X1244053Y589655D01*
X1243761Y589863D01*
X1243470Y589946D01*
X1243095D01*
G01X1243470D02*
X1243720Y590071D01*
X1243928Y590280D01*
X1244011Y590530D01*
X1243928Y590780D01*
X1243720Y590988D01*
X1243345Y591113D01*
X1242970Y591071D01*
X1242595Y590905D01*
G01X1271852Y553677D02*
Y556777D01*
X1271392Y556157D01*
G01Y553677D02*
X1272312D01*
G01X1275412D02*
Y556777D01*
X1273994Y554555D01*
X1275910D01*
G01X1278512Y553677D02*
Y556777D01*
X1277094Y554555D01*
X1279010D01*
G01X1270724Y588560D02*
X1270954Y588870D01*
X1271222Y589025D01*
X1271529Y589077D01*
X1271912Y588974D01*
X1272180Y588715D01*
X1272257Y588405D01*
X1272219Y588095D01*
X1272065Y587837D01*
X1271299Y587320D01*
X1270954Y586959D01*
X1270724Y586442D01*
X1270647Y585977D01*
X1272257D01*
G01X1274552D02*
X1274820Y586029D01*
X1275127Y586184D01*
X1275319Y586442D01*
X1275395Y586804D01*
X1275319Y587165D01*
X1275089Y587475D01*
X1274744Y587630D01*
X1274360D01*
X1274130Y587734D01*
X1273939Y587992D01*
X1273862Y588354D01*
X1273977Y588715D01*
X1274245Y588974D01*
X1274552Y589077D01*
X1274859Y588974D01*
X1275127Y588715D01*
X1275242Y588354D01*
X1275165Y587992D01*
X1274974Y587734D01*
X1274744Y587630D01*
X1274360D01*
X1274015Y587475D01*
X1273785Y587165D01*
X1273709Y586804D01*
X1273785Y586442D01*
X1273977Y586184D01*
X1274284Y586029D01*
X1274552Y585977D01*
G01X1277652D02*
X1277920Y586029D01*
X1278227Y586184D01*
X1278419Y586442D01*
X1278495Y586804D01*
X1278419Y587165D01*
X1278189Y587475D01*
X1277844Y587630D01*
X1277460D01*
X1277230Y587734D01*
X1277039Y587992D01*
X1276962Y588354D01*
X1277077Y588715D01*
X1277345Y588974D01*
X1277652Y589077D01*
X1277959Y588974D01*
X1278227Y588715D01*
X1278342Y588354D01*
X1278265Y587992D01*
X1278074Y587734D01*
X1277844Y587630D01*
X1277460D01*
X1277115Y587475D01*
X1276885Y587165D01*
X1276809Y586804D01*
X1276885Y586442D01*
X1277077Y586184D01*
X1277384Y586029D01*
X1277652Y585977D01*
G01X1270986Y583550D02*
X1295376D01*
Y557960D01*
X1270986D01*
G01X1271724Y550560D02*
X1271954Y550870D01*
X1272222Y551025D01*
X1272529Y551077D01*
X1272912Y550974D01*
X1273180Y550715D01*
X1273257Y550405D01*
X1273219Y550095D01*
X1273065Y549837D01*
X1272299Y549320D01*
X1271954Y548959D01*
X1271724Y548442D01*
X1271647Y547977D01*
X1273257D01*
G01X1275552D02*
X1275820Y548029D01*
X1276127Y548184D01*
X1276319Y548442D01*
X1276395Y548804D01*
X1276319Y549165D01*
X1276089Y549475D01*
X1275744Y549630D01*
X1275360D01*
X1275130Y549734D01*
X1274939Y549992D01*
X1274862Y550354D01*
X1274977Y550715D01*
X1275245Y550974D01*
X1275552Y551077D01*
X1275859Y550974D01*
X1276127Y550715D01*
X1276242Y550354D01*
X1276165Y549992D01*
X1275974Y549734D01*
X1275744Y549630D01*
X1275360D01*
X1275015Y549475D01*
X1274785Y549165D01*
X1274709Y548804D01*
X1274785Y548442D01*
X1274977Y548184D01*
X1275284Y548029D01*
X1275552Y547977D01*
G01X1278652D02*
X1278920Y548029D01*
X1279227Y548184D01*
X1279419Y548442D01*
X1279495Y548804D01*
X1279419Y549165D01*
X1279189Y549475D01*
X1278844Y549630D01*
X1278460D01*
X1278230Y549734D01*
X1278039Y549992D01*
X1277962Y550354D01*
X1278077Y550715D01*
X1278345Y550974D01*
X1278652Y551077D01*
X1278959Y550974D01*
X1279227Y550715D01*
X1279342Y550354D01*
X1279265Y549992D01*
X1279074Y549734D01*
X1278844Y549630D01*
X1278460D01*
X1278115Y549475D01*
X1277885Y549165D01*
X1277809Y548804D01*
X1277885Y548442D01*
X1278077Y548184D01*
X1278384Y548029D01*
X1278652Y547977D01*
G01X1271782Y591587D02*
Y594687D01*
X1271322Y594067D01*
G01Y591587D02*
X1272242D01*
G01X1275342D02*
Y594687D01*
X1273924Y592465D01*
X1275840D01*
G01X1278442Y591587D02*
Y594687D01*
X1277024Y592465D01*
X1278940D01*
G01X1260804Y624940D02*
X1261034Y625250D01*
X1261302Y625405D01*
X1261609Y625457D01*
X1261992Y625354D01*
X1262260Y625095D01*
X1262337Y624785D01*
X1262299Y624475D01*
X1262145Y624217D01*
X1261379Y623700D01*
X1261034Y623339D01*
X1260804Y622822D01*
X1260727Y622357D01*
X1262337D01*
G01X1264632D02*
X1264900Y622409D01*
X1265207Y622564D01*
X1265399Y622822D01*
X1265475Y623184D01*
X1265399Y623545D01*
X1265169Y623855D01*
X1264824Y624010D01*
X1264440D01*
X1264210Y624114D01*
X1264019Y624372D01*
X1263942Y624734D01*
X1264057Y625095D01*
X1264325Y625354D01*
X1264632Y625457D01*
X1264939Y625354D01*
X1265207Y625095D01*
X1265322Y624734D01*
X1265245Y624372D01*
X1265054Y624114D01*
X1264824Y624010D01*
X1264440D01*
X1264095Y623855D01*
X1263865Y623545D01*
X1263789Y623184D01*
X1263865Y622822D01*
X1264057Y622564D01*
X1264364Y622409D01*
X1264632Y622357D01*
G01X1267732D02*
X1268000Y622409D01*
X1268307Y622564D01*
X1268499Y622822D01*
X1268575Y623184D01*
X1268499Y623545D01*
X1268269Y623855D01*
X1267924Y624010D01*
X1267540D01*
X1267310Y624114D01*
X1267119Y624372D01*
X1267042Y624734D01*
X1267157Y625095D01*
X1267425Y625354D01*
X1267732Y625457D01*
X1268039Y625354D01*
X1268307Y625095D01*
X1268422Y624734D01*
X1268345Y624372D01*
X1268154Y624114D01*
X1267924Y624010D01*
X1267540D01*
X1267195Y623855D01*
X1266965Y623545D01*
X1266889Y623184D01*
X1266965Y622822D01*
X1267157Y622564D01*
X1267464Y622409D01*
X1267732Y622357D01*
G01X1270986Y621350D02*
X1295376D01*
Y595760D01*
X1270986D01*
G01X1231750Y658650D02*
X1264450D01*
Y639950D01*
X1231750D01*
Y658650D01*
G01X1327267Y8458D02*
X1327017Y8583D01*
X1326725Y8666D01*
X1326392D01*
X1326017Y8541D01*
X1325725Y8333D01*
X1325517Y8083D01*
X1325350Y7666D01*
X1325308Y7291D01*
X1325392Y6916D01*
X1325517Y6666D01*
X1325767Y6416D01*
X1326058Y6249D01*
X1326350Y6166D01*
X1326642D01*
X1326933Y6249D01*
X1327183Y6374D01*
X1327392Y6541D01*
G01X1329450Y8666D02*
Y6166D01*
G01X1328492Y8666D02*
X1330408D01*
G01X1331633Y6541D02*
X1331883Y6333D01*
X1332175Y6208D01*
X1332550Y6166D01*
X1332925Y6249D01*
X1333217Y6416D01*
X1333425Y6708D01*
X1333467Y7041D01*
X1333383Y7374D01*
X1333175Y7583D01*
X1332883Y7749D01*
X1332592Y7791D01*
X1332300Y7749D01*
X1331925Y7583D01*
X1332050Y8666D01*
X1333175D01*
G01X1334733Y6666D02*
X1334983Y6374D01*
X1335317Y6208D01*
X1335692Y6166D01*
X1336025Y6208D01*
X1336358Y6416D01*
X1336567Y6666D01*
X1336608Y6916D01*
X1336525Y7208D01*
X1336233Y7416D01*
X1335942Y7499D01*
X1335567D01*
G01X1335942D02*
X1336192Y7624D01*
X1336400Y7833D01*
X1336483Y8083D01*
X1336400Y8333D01*
X1336192Y8541D01*
X1335817Y8666D01*
X1335442Y8624D01*
X1335067Y8458D01*
G01X1298657Y-11044D02*
X1298907Y-10836D01*
X1299074Y-10586D01*
X1299157Y-10294D01*
X1299074Y-9961D01*
X1298907Y-9711D01*
X1298657Y-9461D01*
X1298324Y-9378D01*
X1296657D01*
G01X1299157Y-6611D02*
X1296657D01*
X1298449Y-8153D01*
Y-6069D01*
G01X1297907Y-3761D02*
Y-2928D01*
X1298657D01*
X1298907Y-3178D01*
X1299074Y-3469D01*
X1299157Y-3886D01*
X1299074Y-4303D01*
X1298907Y-4594D01*
X1298657Y-4844D01*
X1298365Y-5011D01*
X1298032Y-5094D01*
X1297740D01*
X1297490Y-5011D01*
X1297199Y-4844D01*
X1296949Y-4594D01*
X1296782Y-4344D01*
X1296657Y-4011D01*
Y-3719D01*
X1296740Y-3386D01*
X1296907Y-3136D01*
G01X1298657Y-1828D02*
X1298949Y-1578D01*
X1299115Y-1244D01*
X1299157Y-869D01*
X1299115Y-536D01*
X1298907Y-203D01*
X1298657Y6D01*
X1298407Y47D01*
X1298115Y-36D01*
X1297907Y-328D01*
X1297824Y-619D01*
Y-994D01*
G01Y-619D02*
X1297699Y-369D01*
X1297490Y-161D01*
X1297240Y-78D01*
X1296990Y-161D01*
X1296782Y-369D01*
X1296657Y-744D01*
X1296699Y-1119D01*
X1296865Y-1494D01*
G01X1299133Y24117D02*
X1299383Y24325D01*
X1299550Y24575D01*
X1299633Y24867D01*
X1299550Y25200D01*
X1299383Y25450D01*
X1299133Y25700D01*
X1298800Y25783D01*
X1297133D01*
G01X1299633Y28550D02*
X1297133D01*
X1298925Y27008D01*
Y29092D01*
G01X1298383Y31400D02*
Y32233D01*
X1299133D01*
X1299383Y31983D01*
X1299550Y31692D01*
X1299633Y31275D01*
X1299550Y30858D01*
X1299383Y30567D01*
X1299133Y30317D01*
X1298841Y30150D01*
X1298508Y30067D01*
X1298216D01*
X1297966Y30150D01*
X1297675Y30317D01*
X1297425Y30567D01*
X1297258Y30817D01*
X1297133Y31150D01*
Y31442D01*
X1297216Y31775D01*
X1297383Y32025D01*
G01X1297550Y33458D02*
X1297300Y33708D01*
X1297175Y34000D01*
X1297133Y34333D01*
X1297216Y34750D01*
X1297425Y35042D01*
X1297675Y35125D01*
X1297925Y35083D01*
X1298133Y34917D01*
X1298550Y34083D01*
X1298841Y33708D01*
X1299258Y33458D01*
X1299633Y33375D01*
Y35125D01*
G01X1301834Y18217D02*
X1304334D01*
Y19883D01*
G01Y22067D02*
X1303792Y22150D01*
X1303334Y22275D01*
X1302917Y22442D01*
X1302459Y22650D01*
X1301834Y22983D01*
Y21317D01*
G01X1303084Y25500D02*
Y26333D01*
X1303834D01*
X1304084Y26083D01*
X1304251Y25792D01*
X1304334Y25375D01*
X1304251Y24958D01*
X1304084Y24667D01*
X1303834Y24417D01*
X1303542Y24250D01*
X1303209Y24167D01*
X1302917D01*
X1302667Y24250D01*
X1302376Y24417D01*
X1302126Y24667D01*
X1301959Y24917D01*
X1301834Y25250D01*
Y25542D01*
X1301917Y25875D01*
X1302084Y26125D01*
G01X1304334Y28350D02*
X1301834D01*
X1302334Y27850D01*
G01X1304334D02*
Y28850D01*
G01X1309066Y29174D02*
Y35222D01*
X1346466D01*
Y29174D01*
G01Y10026D02*
X1309066D01*
Y16074D01*
G01X1301833Y-13483D02*
X1304333D01*
Y-11817D01*
G01Y-9633D02*
X1303791Y-9550D01*
X1303333Y-9425D01*
X1302916Y-9258D01*
X1302458Y-9050D01*
X1301833Y-8717D01*
Y-10383D01*
G01X1303083Y-6200D02*
Y-5367D01*
X1303833D01*
X1304083Y-5617D01*
X1304250Y-5908D01*
X1304333Y-6325D01*
X1304250Y-6742D01*
X1304083Y-7033D01*
X1303833Y-7283D01*
X1303541Y-7450D01*
X1303208Y-7533D01*
X1302916D01*
X1302666Y-7450D01*
X1302375Y-7283D01*
X1302125Y-7033D01*
X1301958Y-6783D01*
X1301833Y-6450D01*
Y-6158D01*
X1301916Y-5825D01*
X1302083Y-5575D01*
G01X1302250Y-4142D02*
X1302000Y-3892D01*
X1301875Y-3600D01*
X1301833Y-3267D01*
X1301916Y-2850D01*
X1302125Y-2558D01*
X1302375Y-2475D01*
X1302625Y-2517D01*
X1302833Y-2683D01*
X1303250Y-3517D01*
X1303541Y-3892D01*
X1303958Y-4142D01*
X1304333Y-4225D01*
Y-2475D01*
G01X1309766Y-926D02*
Y5122D01*
X1347166D01*
Y-926D01*
G01Y-20074D02*
X1309766D01*
Y-14026D01*
G01X1338543Y51322D02*
Y54472D01*
X1335876Y58322D01*
G01X1341210D02*
X1338543Y54472D01*
G01X1324490Y76730D02*
Y86349D01*
X1319265D01*
Y92773D01*
X1313047D01*
Y97268D01*
X1339375D01*
Y98316D01*
X1344800D01*
G01X1325490Y75020D02*
X1328910D01*
Y53300D01*
G01X1328087Y50526D02*
Y38055D01*
X1346946D01*
G01X1301108Y36667D02*
X1300983Y36417D01*
X1300900Y36125D01*
Y35792D01*
X1301025Y35417D01*
X1301233Y35125D01*
X1301483Y34917D01*
X1301900Y34750D01*
X1302275Y34708D01*
X1302650Y34792D01*
X1302900Y34917D01*
X1303150Y35167D01*
X1303317Y35458D01*
X1303400Y35750D01*
Y36042D01*
X1303317Y36333D01*
X1303192Y36583D01*
X1303025Y36792D01*
G01X1302358Y38058D02*
X1302067Y38350D01*
X1301900Y38600D01*
X1301817Y38933D01*
X1301900Y39225D01*
X1302067Y39433D01*
X1302317Y39600D01*
X1302608Y39642D01*
X1302858Y39600D01*
X1303108Y39433D01*
X1303317Y39183D01*
X1303400Y38892D01*
X1303317Y38558D01*
X1303067Y38267D01*
X1302692Y38100D01*
X1302275Y38058D01*
X1301733Y38142D01*
X1301442Y38267D01*
X1301150Y38475D01*
X1300942Y38767D01*
X1300900Y39058D01*
X1300983Y39350D01*
X1301192Y39558D01*
G01X1302150Y42200D02*
Y43033D01*
X1302900D01*
X1303150Y42783D01*
X1303317Y42492D01*
X1303400Y42075D01*
X1303317Y41658D01*
X1303150Y41367D01*
X1302900Y41117D01*
X1302608Y40950D01*
X1302275Y40867D01*
X1301983D01*
X1301733Y40950D01*
X1301442Y41117D01*
X1301192Y41367D01*
X1301025Y41617D01*
X1300900Y41950D01*
Y42242D01*
X1300983Y42575D01*
X1301150Y42825D01*
G01X1302900Y44133D02*
X1303192Y44383D01*
X1303358Y44717D01*
X1303400Y45092D01*
X1303358Y45425D01*
X1303150Y45758D01*
X1302900Y45967D01*
X1302650Y46008D01*
X1302358Y45925D01*
X1302150Y45633D01*
X1302067Y45342D01*
Y44967D01*
G01Y45342D02*
X1301942Y45592D01*
X1301733Y45800D01*
X1301483Y45883D01*
X1301233Y45800D01*
X1301025Y45592D01*
X1300900Y45217D01*
X1300942Y44842D01*
X1301108Y44467D01*
G01X1300367Y85200D02*
Y87700D01*
X1301408D01*
X1301742Y87575D01*
X1301950Y87408D01*
X1302033Y87075D01*
X1301950Y86742D01*
X1301700Y86533D01*
X1301408Y86408D01*
X1300367D01*
G01X1301408D02*
X1302033Y85200D01*
G01X1304217D02*
X1304300Y85742D01*
X1304425Y86200D01*
X1304592Y86617D01*
X1304800Y87075D01*
X1305133Y87700D01*
X1303467D01*
G01X1306608Y85200D02*
Y87700D01*
X1308192D01*
G01X1307608Y86492D02*
X1306608D01*
G01X1309583Y85700D02*
X1309833Y85408D01*
X1310167Y85242D01*
X1310542Y85200D01*
X1310875Y85242D01*
X1311208Y85450D01*
X1311417Y85700D01*
X1311458Y85950D01*
X1311375Y86242D01*
X1311083Y86450D01*
X1310792Y86533D01*
X1310417D01*
G01X1310792D02*
X1311042Y86658D01*
X1311250Y86867D01*
X1311333Y87117D01*
X1311250Y87367D01*
X1311042Y87575D01*
X1310667Y87700D01*
X1310292Y87658D01*
X1309917Y87492D01*
G01X1312683Y85700D02*
X1312933Y85408D01*
X1313267Y85242D01*
X1313642Y85200D01*
X1313975Y85242D01*
X1314308Y85450D01*
X1314517Y85700D01*
X1314558Y85950D01*
X1314475Y86242D01*
X1314183Y86450D01*
X1313892Y86533D01*
X1313517D01*
G01X1313892D02*
X1314142Y86658D01*
X1314350Y86867D01*
X1314433Y87117D01*
X1314350Y87367D01*
X1314142Y87575D01*
X1313767Y87700D01*
X1313392Y87658D01*
X1313017Y87492D01*
G01X1307978Y94887D02*
X1305478D01*
Y95928D01*
X1305603Y96262D01*
X1305770Y96470D01*
X1306103Y96553D01*
X1306436Y96470D01*
X1306645Y96220D01*
X1306770Y95928D01*
Y94887D01*
G01Y95928D02*
X1307978Y96553D01*
G01Y98737D02*
X1307436Y98820D01*
X1306978Y98945D01*
X1306561Y99112D01*
X1306103Y99320D01*
X1305478Y99653D01*
Y97987D01*
G01X1307978Y101128D02*
X1305478D01*
Y102712D01*
G01X1306686Y102128D02*
Y101128D01*
G01X1307978Y105020D02*
X1307936Y105312D01*
X1307811Y105645D01*
X1307603Y105853D01*
X1307311Y105937D01*
X1307020Y105853D01*
X1306770Y105603D01*
X1306645Y105228D01*
Y104812D01*
X1306561Y104562D01*
X1306353Y104353D01*
X1306061Y104270D01*
X1305770Y104395D01*
X1305561Y104687D01*
X1305478Y105020D01*
X1305561Y105353D01*
X1305770Y105645D01*
X1306061Y105770D01*
X1306353Y105687D01*
X1306561Y105478D01*
X1306645Y105228D01*
Y104812D01*
X1306770Y104437D01*
X1307020Y104187D01*
X1307311Y104103D01*
X1307603Y104187D01*
X1307811Y104395D01*
X1307936Y104728D01*
X1307978Y105020D01*
G01X1304608Y64817D02*
X1304483Y64567D01*
X1304400Y64275D01*
Y63942D01*
X1304525Y63567D01*
X1304733Y63275D01*
X1304983Y63067D01*
X1305400Y62900D01*
X1305775Y62858D01*
X1306150Y62942D01*
X1306400Y63067D01*
X1306650Y63317D01*
X1306817Y63608D01*
X1306900Y63900D01*
Y64192D01*
X1306817Y64483D01*
X1306692Y64733D01*
X1306525Y64942D01*
G01X1306900Y66917D02*
X1306358Y67000D01*
X1305900Y67125D01*
X1305483Y67292D01*
X1305025Y67500D01*
X1304400Y67833D01*
Y66167D01*
G01X1305650Y70350D02*
Y71183D01*
X1306400D01*
X1306650Y70933D01*
X1306817Y70642D01*
X1306900Y70225D01*
X1306817Y69808D01*
X1306650Y69517D01*
X1306400Y69267D01*
X1306108Y69100D01*
X1305775Y69017D01*
X1305483D01*
X1305233Y69100D01*
X1304942Y69267D01*
X1304692Y69517D01*
X1304525Y69767D01*
X1304400Y70100D01*
Y70392D01*
X1304483Y70725D01*
X1304650Y70975D01*
G01X1304817Y72408D02*
X1304567Y72658D01*
X1304442Y72950D01*
X1304400Y73283D01*
X1304483Y73700D01*
X1304692Y73992D01*
X1304942Y74075D01*
X1305192Y74033D01*
X1305400Y73867D01*
X1305817Y73033D01*
X1306108Y72658D01*
X1306525Y72408D01*
X1306900Y72325D01*
Y74075D01*
G01Y76300D02*
X1306858Y76592D01*
X1306733Y76925D01*
X1306525Y77133D01*
X1306233Y77217D01*
X1305942Y77133D01*
X1305692Y76883D01*
X1305567Y76508D01*
Y76092D01*
X1305483Y75842D01*
X1305275Y75633D01*
X1304983Y75550D01*
X1304692Y75675D01*
X1304483Y75967D01*
X1304400Y76300D01*
X1304483Y76633D01*
X1304692Y76925D01*
X1304983Y77050D01*
X1305275Y76967D01*
X1305483Y76758D01*
X1305567Y76508D01*
Y76092D01*
X1305692Y75717D01*
X1305942Y75467D01*
X1306233Y75383D01*
X1306525Y75467D01*
X1306733Y75675D01*
X1306858Y76008D01*
X1306900Y76300D01*
G01X1323300Y38436D02*
X1327091D01*
Y51232D01*
X1323300D01*
G01X1310700Y38436D02*
X1307138D01*
Y51232D01*
X1310700D01*
G01X1308000Y73800D02*
X1310698D01*
G01X1326000D02*
X1323305D01*
G01X1326000D02*
Y51228D01*
G01X1308000Y73800D02*
Y51225D01*
G01X1299159Y61851D02*
X1299409Y62059D01*
X1299576Y62309D01*
X1299659Y62601D01*
X1299576Y62934D01*
X1299409Y63184D01*
X1299159Y63434D01*
X1298826Y63517D01*
X1297159D01*
G01X1299659Y66284D02*
X1297159D01*
X1298951Y64742D01*
Y66826D01*
G01X1298409Y69134D02*
Y69967D01*
X1299159D01*
X1299409Y69717D01*
X1299576Y69426D01*
X1299659Y69009D01*
X1299576Y68592D01*
X1299409Y68301D01*
X1299159Y68051D01*
X1298867Y67884D01*
X1298534Y67801D01*
X1298242D01*
X1297992Y67884D01*
X1297701Y68051D01*
X1297451Y68301D01*
X1297284Y68551D01*
X1297159Y68884D01*
Y69176D01*
X1297242Y69509D01*
X1297409Y69759D01*
G01X1299659Y71984D02*
X1297159D01*
X1297659Y71484D01*
G01X1299659D02*
Y72484D01*
G01X1317860Y134841D02*
Y132341D01*
X1319526D01*
G01X1321710D02*
X1321793Y132883D01*
X1321918Y133341D01*
X1322085Y133758D01*
X1322293Y134216D01*
X1322626Y134841D01*
X1320960D01*
G01X1324101Y132341D02*
Y134841D01*
X1325685D01*
G01X1325101Y133633D02*
X1324101D01*
G01X1327993Y132341D02*
Y134841D01*
X1327493Y134341D01*
G01Y132341D02*
X1328493D01*
G01X1338450Y106700D02*
Y103400D01*
X1311650D01*
Y106700D01*
G01Y126900D02*
Y130200D01*
X1338450D01*
Y126900D01*
G01X1292067Y98159D02*
X1291817Y98284D01*
X1291525Y98367D01*
X1291192D01*
X1290817Y98242D01*
X1290525Y98034D01*
X1290317Y97784D01*
X1290150Y97367D01*
X1290108Y96992D01*
X1290192Y96617D01*
X1290317Y96367D01*
X1290567Y96117D01*
X1290858Y95950D01*
X1291150Y95867D01*
X1291442D01*
X1291733Y95950D01*
X1291983Y96075D01*
X1292192Y96242D01*
G01X1294167Y95867D02*
X1294250Y96409D01*
X1294375Y96867D01*
X1294542Y97284D01*
X1294750Y97742D01*
X1295083Y98367D01*
X1293417D01*
G01X1296558Y95867D02*
Y98367D01*
X1298142D01*
G01X1297558Y97159D02*
X1296558D01*
G01X1300950Y95867D02*
Y98367D01*
X1299408Y96575D01*
X1301492D01*
G01X1338642Y134786D02*
X1338392Y134911D01*
X1338100Y134994D01*
X1337767D01*
X1337392Y134869D01*
X1337100Y134661D01*
X1336892Y134411D01*
X1336725Y133994D01*
X1336683Y133619D01*
X1336767Y133244D01*
X1336892Y132994D01*
X1337142Y132744D01*
X1337433Y132577D01*
X1337725Y132494D01*
X1338017D01*
X1338308Y132577D01*
X1338558Y132702D01*
X1338767Y132869D01*
G01X1340742Y132494D02*
X1340825Y133036D01*
X1340950Y133494D01*
X1341117Y133911D01*
X1341325Y134369D01*
X1341658Y134994D01*
X1339992D01*
G01X1343133Y132494D02*
Y134994D01*
X1344717D01*
G01X1344133Y133786D02*
X1343133D01*
G01X1346108Y132994D02*
X1346358Y132702D01*
X1346692Y132536D01*
X1347067Y132494D01*
X1347400Y132536D01*
X1347733Y132744D01*
X1347942Y132994D01*
X1347983Y133244D01*
X1347900Y133536D01*
X1347608Y133744D01*
X1347317Y133827D01*
X1346942D01*
G01X1347317D02*
X1347567Y133952D01*
X1347775Y134161D01*
X1347858Y134411D01*
X1347775Y134661D01*
X1347567Y134869D01*
X1347192Y134994D01*
X1346817Y134952D01*
X1346442Y134786D01*
G01X1282242Y105267D02*
X1282117Y105017D01*
X1282034Y104725D01*
Y104392D01*
X1282159Y104017D01*
X1282367Y103725D01*
X1282617Y103517D01*
X1283034Y103350D01*
X1283409Y103308D01*
X1283784Y103392D01*
X1284034Y103517D01*
X1284284Y103767D01*
X1284451Y104058D01*
X1284534Y104350D01*
Y104642D01*
X1284451Y104933D01*
X1284326Y105183D01*
X1284159Y105392D01*
G01X1283492Y106658D02*
X1283201Y106950D01*
X1283034Y107200D01*
X1282951Y107533D01*
X1283034Y107825D01*
X1283201Y108033D01*
X1283451Y108200D01*
X1283742Y108242D01*
X1283992Y108200D01*
X1284242Y108033D01*
X1284451Y107783D01*
X1284534Y107492D01*
X1284451Y107158D01*
X1284201Y106867D01*
X1283826Y106700D01*
X1283409Y106658D01*
X1282867Y106742D01*
X1282576Y106867D01*
X1282284Y107075D01*
X1282076Y107367D01*
X1282034Y107658D01*
X1282117Y107950D01*
X1282326Y108158D01*
G01X1284534Y109758D02*
X1282034D01*
Y111342D01*
G01X1283242Y110758D02*
Y109758D01*
G01X1284034Y112733D02*
X1284326Y112983D01*
X1284492Y113317D01*
X1284534Y113692D01*
X1284492Y114025D01*
X1284284Y114358D01*
X1284034Y114567D01*
X1283784Y114608D01*
X1283492Y114525D01*
X1283284Y114233D01*
X1283201Y113942D01*
Y113567D01*
G01Y113942D02*
X1283076Y114192D01*
X1282867Y114400D01*
X1282617Y114483D01*
X1282367Y114400D01*
X1282159Y114192D01*
X1282034Y113817D01*
X1282076Y113442D01*
X1282242Y113067D01*
G01X1281942Y120267D02*
X1281817Y120017D01*
X1281734Y119725D01*
Y119392D01*
X1281859Y119017D01*
X1282067Y118725D01*
X1282317Y118517D01*
X1282734Y118350D01*
X1283109Y118308D01*
X1283484Y118392D01*
X1283734Y118517D01*
X1283984Y118767D01*
X1284151Y119058D01*
X1284234Y119350D01*
Y119642D01*
X1284151Y119933D01*
X1284026Y120183D01*
X1283859Y120392D01*
G01X1283192Y121658D02*
X1282901Y121950D01*
X1282734Y122200D01*
X1282651Y122533D01*
X1282734Y122825D01*
X1282901Y123033D01*
X1283151Y123200D01*
X1283442Y123242D01*
X1283692Y123200D01*
X1283942Y123033D01*
X1284151Y122783D01*
X1284234Y122492D01*
X1284151Y122158D01*
X1283901Y121867D01*
X1283526Y121700D01*
X1283109Y121658D01*
X1282567Y121742D01*
X1282276Y121867D01*
X1281984Y122075D01*
X1281776Y122367D01*
X1281734Y122658D01*
X1281817Y122950D01*
X1282026Y123158D01*
G01X1284234Y124758D02*
X1281734D01*
Y126342D01*
G01X1282942Y125758D02*
Y124758D01*
G01X1282151Y127858D02*
X1281901Y128108D01*
X1281776Y128400D01*
X1281734Y128733D01*
X1281817Y129150D01*
X1282026Y129442D01*
X1282276Y129525D01*
X1282526Y129483D01*
X1282734Y129317D01*
X1283151Y128483D01*
X1283442Y128108D01*
X1283859Y127858D01*
X1284234Y127775D01*
Y129525D01*
G01X1305407Y129509D02*
X1305282Y129259D01*
X1305199Y128967D01*
Y128634D01*
X1305324Y128259D01*
X1305532Y127967D01*
X1305782Y127759D01*
X1306199Y127592D01*
X1306574Y127550D01*
X1306949Y127634D01*
X1307199Y127759D01*
X1307449Y128009D01*
X1307616Y128300D01*
X1307699Y128592D01*
Y128884D01*
X1307616Y129175D01*
X1307491Y129425D01*
X1307324Y129634D01*
G01X1306657Y130900D02*
X1306366Y131192D01*
X1306199Y131442D01*
X1306116Y131775D01*
X1306199Y132067D01*
X1306366Y132275D01*
X1306616Y132442D01*
X1306907Y132484D01*
X1307157Y132442D01*
X1307407Y132275D01*
X1307616Y132025D01*
X1307699Y131734D01*
X1307616Y131400D01*
X1307366Y131109D01*
X1306991Y130942D01*
X1306574Y130900D01*
X1306032Y130984D01*
X1305741Y131109D01*
X1305449Y131317D01*
X1305241Y131609D01*
X1305199Y131900D01*
X1305282Y132192D01*
X1305491Y132400D01*
G01X1307699Y134000D02*
X1305199D01*
Y135584D01*
G01X1306407Y135000D02*
Y134000D01*
G01X1307699Y138392D02*
X1305199D01*
X1306991Y136850D01*
Y138934D01*
G01X1288400Y99050D02*
X1287200D01*
Y111050D01*
X1288400D01*
G01X1302000Y99050D02*
X1303200D01*
Y111050D01*
X1302000D01*
G01X1303200Y104100D02*
X1304250D01*
Y134000D01*
X1302000D01*
G01X1288400D02*
X1286150D01*
Y104100D01*
X1287200D01*
G01X1295640Y139809D02*
Y142909D01*
X1297096D01*
G01X1296560Y141411D02*
X1295640D01*
G01X1299468Y139809D02*
Y142909D01*
X1299008Y142289D01*
G01Y139809D02*
X1299928D01*
G01X1282618Y170945D02*
Y148945D01*
X1285618D01*
Y143795D01*
X1408618D01*
Y176095D01*
X1290910D01*
G01X1296150Y211900D02*
Y215000D01*
X1295690Y214380D01*
G01Y211900D02*
X1296610D01*
G01X1299173Y211332D02*
X1299327Y212003D01*
G01X1301507Y212520D02*
X1301737Y212158D01*
X1302043Y211952D01*
X1302388Y211900D01*
X1302695Y211952D01*
X1303002Y212210D01*
X1303193Y212520D01*
X1303232Y212830D01*
X1303155Y213192D01*
X1302887Y213450D01*
X1302618Y213553D01*
X1302273D01*
G01X1302618D02*
X1302848Y213708D01*
X1303040Y213967D01*
X1303117Y214277D01*
X1303040Y214587D01*
X1302848Y214845D01*
X1302503Y215000D01*
X1302158Y214948D01*
X1301813Y214742D01*
G01X1310807Y215000D02*
Y212778D01*
X1310960Y212313D01*
X1311267Y212003D01*
X1311650Y211900D01*
X1312033Y212003D01*
X1312340Y212313D01*
X1312493Y212778D01*
Y215000D01*
G01X1313792D02*
X1314750Y211900D01*
X1315708Y215000D01*
G01X1317083Y211900D02*
Y215000D01*
X1318003D01*
X1318310Y214845D01*
X1318540Y214483D01*
X1318617Y214070D01*
X1318540Y213657D01*
X1318348Y213347D01*
X1318003Y213192D01*
X1317083D01*
G01X1324050Y215000D02*
Y211900D01*
G01X1323168Y215000D02*
X1324932D01*
G01X1326383Y211900D02*
Y215000D01*
X1327342D01*
X1327648Y214845D01*
X1327840Y214638D01*
X1327917Y214225D01*
X1327840Y213812D01*
X1327610Y213553D01*
X1327342Y213398D01*
X1326383D01*
G01X1327342D02*
X1327917Y211900D01*
G01X1329790Y215000D02*
X1330710D01*
G01X1330250D02*
Y211900D01*
G01X1329790D02*
X1330710D01*
G01X1332583D02*
Y215000D01*
X1333503D01*
X1333810Y214845D01*
X1334040Y214483D01*
X1334117Y214070D01*
X1334040Y213657D01*
X1333848Y213347D01*
X1333503Y213192D01*
X1332583D01*
G01X1339550Y211900D02*
Y215000D01*
X1339090Y214380D01*
G01Y211900D02*
X1340010D01*
G01X1342650D02*
Y215000D01*
X1342190Y214380D01*
G01Y211900D02*
X1343110D01*
G01X1345750Y211797D02*
X1345673Y211848D01*
Y211952D01*
X1345750Y212003D01*
X1345827Y211952D01*
Y211848D01*
X1345750Y211797D01*
G01X1348007Y212365D02*
X1348237Y212107D01*
X1348505Y211952D01*
X1348850Y211900D01*
X1349195Y212003D01*
X1349463Y212210D01*
X1349655Y212572D01*
X1349693Y212985D01*
X1349617Y213398D01*
X1349425Y213657D01*
X1349157Y213863D01*
X1348888Y213915D01*
X1348620Y213863D01*
X1348275Y213657D01*
X1348390Y215000D01*
X1349425D01*
G01X1350992D02*
X1351950Y211900D01*
X1352908Y215000D01*
G01X1294236Y187251D02*
Y190351D01*
X1293776Y189731D01*
G01Y187251D02*
X1294696D01*
G01X1297336Y190351D02*
X1297029Y190248D01*
X1296799Y189989D01*
X1296646Y189679D01*
X1296531Y189266D01*
X1296493Y188801D01*
X1296531Y188336D01*
X1296646Y187923D01*
X1296799Y187613D01*
X1297029Y187354D01*
X1297336Y187251D01*
X1297643Y187354D01*
X1297873Y187613D01*
X1298026Y187923D01*
X1298141Y188336D01*
X1298179Y188801D01*
X1298141Y189266D01*
X1298026Y189679D01*
X1297873Y189989D01*
X1297643Y190248D01*
X1297336Y190351D01*
G01X1300359Y186683D02*
X1300513Y187354D01*
G01X1303536Y187251D02*
Y190351D01*
X1303076Y189731D01*
G01Y187251D02*
X1303996D01*
G01X1305908Y189834D02*
X1306138Y190144D01*
X1306406Y190299D01*
X1306713Y190351D01*
X1307096Y190248D01*
X1307364Y189989D01*
X1307441Y189679D01*
X1307403Y189369D01*
X1307249Y189111D01*
X1306483Y188594D01*
X1306138Y188233D01*
X1305908Y187716D01*
X1305831Y187251D01*
X1307441D01*
G01X1313143Y188904D02*
X1313296Y189059D01*
X1313411Y189318D01*
X1313488Y189679D01*
X1313411Y189989D01*
X1313258Y190196D01*
X1312989Y190351D01*
X1311954D01*
Y187251D01*
X1313219D01*
X1313488Y187458D01*
X1313641Y187768D01*
X1313718Y188129D01*
X1313641Y188491D01*
X1313411Y188801D01*
X1313143Y188904D01*
X1311954D01*
G01X1314939Y187251D02*
Y190351D01*
X1315936Y187768D01*
X1316933Y190351D01*
Y187251D01*
G01X1319879Y190093D02*
X1319649Y190248D01*
X1319381Y190351D01*
X1319074D01*
X1318729Y190196D01*
X1318461Y189938D01*
X1318269Y189628D01*
X1318116Y189111D01*
X1318078Y188646D01*
X1318154Y188181D01*
X1318269Y187871D01*
X1318499Y187561D01*
X1318768Y187354D01*
X1319036Y187251D01*
X1319304D01*
X1319573Y187354D01*
X1319803Y187509D01*
X1319994Y187716D01*
G01X1324393Y187251D02*
Y190351D01*
X1325159D01*
X1325466Y190196D01*
X1325696Y189989D01*
X1325888Y189679D01*
X1326041Y189318D01*
X1326079Y188801D01*
X1326041Y188284D01*
X1325888Y187923D01*
X1325696Y187613D01*
X1325466Y187406D01*
X1325159Y187251D01*
X1324393D01*
G01X1327876Y190351D02*
X1328796D01*
G01X1328336D02*
Y187251D01*
G01X1327876D02*
X1328796D01*
G01X1330631Y187664D02*
X1330938Y187406D01*
X1331283Y187251D01*
X1331589D01*
X1331896Y187406D01*
X1332126Y187664D01*
X1332241Y188026D01*
X1332164Y188388D01*
X1331973Y188698D01*
X1331628Y188904D01*
X1331168Y189008D01*
X1330899Y189214D01*
X1330784Y189576D01*
X1330861Y189938D01*
X1331053Y190196D01*
X1331321Y190351D01*
X1331589D01*
X1331858Y190248D01*
X1332088Y189989D01*
G01X1333578Y187251D02*
X1334536Y190351D01*
X1335494Y187251D01*
G01X1335149Y188336D02*
X1333923D01*
G01X1337943Y188904D02*
X1338096Y189059D01*
X1338211Y189318D01*
X1338288Y189679D01*
X1338211Y189989D01*
X1338058Y190196D01*
X1337789Y190351D01*
X1336754D01*
Y187251D01*
X1338019D01*
X1338288Y187458D01*
X1338441Y187768D01*
X1338518Y188129D01*
X1338441Y188491D01*
X1338211Y188801D01*
X1337943Y188904D01*
X1336754D01*
G01X1339969Y190351D02*
Y187251D01*
X1341503D01*
G01X1344603D02*
X1343069D01*
Y190351D01*
X1344603D01*
G01X1343989Y188853D02*
X1343069D01*
G01X1300910Y193500D02*
Y196600D01*
X1299492Y194378D01*
X1301408D01*
G01X1303473Y192932D02*
X1303627Y193603D01*
G01X1305922Y194792D02*
X1306190Y195153D01*
X1306420Y195360D01*
X1306727Y195463D01*
X1306995Y195360D01*
X1307187Y195153D01*
X1307340Y194843D01*
X1307378Y194482D01*
X1307340Y194172D01*
X1307187Y193862D01*
X1306957Y193603D01*
X1306688Y193500D01*
X1306382Y193603D01*
X1306113Y193913D01*
X1305960Y194378D01*
X1305922Y194895D01*
X1305998Y195567D01*
X1306113Y195928D01*
X1306305Y196290D01*
X1306573Y196548D01*
X1306842Y196600D01*
X1307110Y196497D01*
X1307302Y196238D01*
G01X1313693Y196342D02*
X1313463Y196497D01*
X1313195Y196600D01*
X1312888D01*
X1312543Y196445D01*
X1312275Y196187D01*
X1312083Y195877D01*
X1311930Y195360D01*
X1311892Y194895D01*
X1311968Y194430D01*
X1312083Y194120D01*
X1312313Y193810D01*
X1312582Y193603D01*
X1312850Y193500D01*
X1313118D01*
X1313387Y193603D01*
X1313617Y193758D01*
X1313808Y193965D01*
G01X1315183Y196600D02*
Y193500D01*
X1316717D01*
G01X1319817D02*
X1318283D01*
Y196600D01*
X1319817D01*
G01X1319203Y195102D02*
X1318283D01*
G01X1321192Y193500D02*
X1322150Y196600D01*
X1323108Y193500D01*
G01X1322763Y194585D02*
X1321537D01*
G01X1324483Y193500D02*
Y196600D01*
X1325442D01*
X1325748Y196445D01*
X1325940Y196238D01*
X1326017Y195825D01*
X1325940Y195412D01*
X1325710Y195153D01*
X1325442Y194998D01*
X1324483D01*
G01X1325442D02*
X1326017Y193500D01*
G01X1330683D02*
Y196600D01*
X1331642D01*
X1331948Y196445D01*
X1332140Y196238D01*
X1332217Y195825D01*
X1332140Y195412D01*
X1331910Y195153D01*
X1331642Y194998D01*
X1330683D01*
G01X1331642D02*
X1332217Y193500D01*
G01X1334550Y196600D02*
Y193500D01*
G01X1333668Y196600D02*
X1335432D01*
G01X1338493Y196342D02*
X1338263Y196497D01*
X1337995Y196600D01*
X1337688D01*
X1337343Y196445D01*
X1337075Y196187D01*
X1336883Y195877D01*
X1336730Y195360D01*
X1336692Y194895D01*
X1336768Y194430D01*
X1336883Y194120D01*
X1337113Y193810D01*
X1337382Y193603D01*
X1337650Y193500D01*
X1337918D01*
X1338187Y193603D01*
X1338417Y193758D01*
X1338608Y193965D01*
G01X1343083Y193500D02*
Y196600D01*
X1344042D01*
X1344348Y196445D01*
X1344540Y196238D01*
X1344617Y195825D01*
X1344540Y195412D01*
X1344310Y195153D01*
X1344042Y194998D01*
X1343083D01*
G01X1344042D02*
X1344617Y193500D01*
G01X1347717D02*
X1346183D01*
Y196600D01*
X1347717D01*
G01X1347103Y195102D02*
X1346183D01*
G01X1350280Y195050D02*
X1351047D01*
Y194120D01*
X1350817Y193810D01*
X1350548Y193603D01*
X1350165Y193500D01*
X1349782Y193603D01*
X1349513Y193810D01*
X1349283Y194120D01*
X1349130Y194482D01*
X1349053Y194895D01*
Y195257D01*
X1349130Y195567D01*
X1349283Y195928D01*
X1349513Y196238D01*
X1349743Y196445D01*
X1350050Y196600D01*
X1350318D01*
X1350625Y196497D01*
X1350855Y196290D01*
G01X1352690Y196600D02*
X1353610D01*
G01X1353150D02*
Y193500D01*
G01X1352690D02*
X1353610D01*
G01X1355445Y193913D02*
X1355752Y193655D01*
X1356097Y193500D01*
X1356403D01*
X1356710Y193655D01*
X1356940Y193913D01*
X1357055Y194275D01*
X1356978Y194637D01*
X1356787Y194947D01*
X1356442Y195153D01*
X1355982Y195257D01*
X1355713Y195463D01*
X1355598Y195825D01*
X1355675Y196187D01*
X1355867Y196445D01*
X1356135Y196600D01*
X1356403D01*
X1356672Y196497D01*
X1356902Y196238D01*
G01X1359350Y196600D02*
Y193500D01*
G01X1358468Y196600D02*
X1360232D01*
G01X1363217Y193500D02*
X1361683D01*
Y196600D01*
X1363217D01*
G01X1362603Y195102D02*
X1361683D01*
G01X1364783Y193500D02*
Y196600D01*
X1365742D01*
X1366048Y196445D01*
X1366240Y196238D01*
X1366317Y195825D01*
X1366240Y195412D01*
X1366010Y195153D01*
X1365742Y194998D01*
X1364783D01*
G01X1365742D02*
X1366317Y193500D01*
G01X1367845Y193913D02*
X1368152Y193655D01*
X1368497Y193500D01*
X1368803D01*
X1369110Y193655D01*
X1369340Y193913D01*
X1369455Y194275D01*
X1369378Y194637D01*
X1369187Y194947D01*
X1368842Y195153D01*
X1368382Y195257D01*
X1368113Y195463D01*
X1367998Y195825D01*
X1368075Y196187D01*
X1368267Y196445D01*
X1368535Y196600D01*
X1368803D01*
X1369072Y196497D01*
X1369302Y196238D01*
G01X1298250Y217900D02*
X1298518Y217952D01*
X1298825Y218107D01*
X1299017Y218365D01*
X1299093Y218727D01*
X1299017Y219088D01*
X1298787Y219398D01*
X1298442Y219553D01*
X1298058D01*
X1297828Y219657D01*
X1297637Y219915D01*
X1297560Y220277D01*
X1297675Y220638D01*
X1297943Y220897D01*
X1298250Y221000D01*
X1298557Y220897D01*
X1298825Y220638D01*
X1298940Y220277D01*
X1298863Y219915D01*
X1298672Y219657D01*
X1298442Y219553D01*
X1298058D01*
X1297713Y219398D01*
X1297483Y219088D01*
X1297407Y218727D01*
X1297483Y218365D01*
X1297675Y218107D01*
X1297982Y217952D01*
X1298250Y217900D01*
G01X1301273Y217332D02*
X1301427Y218003D01*
G01X1304450Y217900D02*
Y221000D01*
X1303990Y220380D01*
G01Y217900D02*
X1304910D01*
G01X1307550Y221000D02*
X1307243Y220897D01*
X1307013Y220638D01*
X1306860Y220328D01*
X1306745Y219915D01*
X1306707Y219450D01*
X1306745Y218985D01*
X1306860Y218572D01*
X1307013Y218262D01*
X1307243Y218003D01*
X1307550Y217900D01*
X1307857Y218003D01*
X1308087Y218262D01*
X1308240Y218572D01*
X1308355Y218985D01*
X1308393Y219450D01*
X1308355Y219915D01*
X1308240Y220328D01*
X1308087Y220638D01*
X1307857Y220897D01*
X1307550Y221000D01*
G01X1298298Y200362D02*
X1298567Y200103D01*
X1298873Y200000D01*
X1299180Y200103D01*
X1299448Y200413D01*
X1299640Y200878D01*
X1299717Y201343D01*
Y201912D01*
X1299640Y202377D01*
X1299448Y202790D01*
X1299218Y202997D01*
X1298950Y203100D01*
X1298643Y202997D01*
X1298413Y202790D01*
X1298260Y202480D01*
X1298183Y202067D01*
X1298260Y201705D01*
X1298452Y201343D01*
X1298682Y201137D01*
X1298950Y201085D01*
X1299257Y201188D01*
X1299487Y201447D01*
X1299717Y201912D01*
G01X1301973Y199432D02*
X1302127Y200103D01*
G01X1305150Y200000D02*
Y203100D01*
X1304690Y202480D01*
G01Y200000D02*
X1305610D01*
G01X1308250D02*
Y203100D01*
X1307790Y202480D01*
G01Y200000D02*
X1308710D01*
G01X1313645Y200413D02*
X1313952Y200155D01*
X1314297Y200000D01*
X1314603D01*
X1314910Y200155D01*
X1315140Y200413D01*
X1315255Y200775D01*
X1315178Y201137D01*
X1314987Y201447D01*
X1314642Y201653D01*
X1314182Y201757D01*
X1313913Y201963D01*
X1313798Y202325D01*
X1313875Y202687D01*
X1314067Y202945D01*
X1314335Y203100D01*
X1314603D01*
X1314872Y202997D01*
X1315102Y202738D01*
G01X1316553Y200000D02*
Y203100D01*
X1317550Y200517D01*
X1318547Y203100D01*
Y200000D01*
G01X1320957Y201653D02*
X1321110Y201808D01*
X1321225Y202067D01*
X1321302Y202428D01*
X1321225Y202738D01*
X1321072Y202945D01*
X1320803Y203100D01*
X1319768D01*
Y200000D01*
X1321033D01*
X1321302Y200207D01*
X1321455Y200517D01*
X1321532Y200878D01*
X1321455Y201240D01*
X1321225Y201550D01*
X1320957Y201653D01*
X1319768D01*
G01X1322907Y203100D02*
Y200878D01*
X1323060Y200413D01*
X1323367Y200103D01*
X1323750Y200000D01*
X1324133Y200103D01*
X1324440Y200413D01*
X1324593Y200878D01*
Y203100D01*
G01X1326045Y200413D02*
X1326352Y200155D01*
X1326697Y200000D01*
X1327003D01*
X1327310Y200155D01*
X1327540Y200413D01*
X1327655Y200775D01*
X1327578Y201137D01*
X1327387Y201447D01*
X1327042Y201653D01*
X1326582Y201757D01*
X1326313Y201963D01*
X1326198Y202325D01*
X1326275Y202687D01*
X1326467Y202945D01*
X1326735Y203100D01*
X1327003D01*
X1327272Y202997D01*
X1327502Y202738D01*
G01X1332207Y203100D02*
Y200878D01*
X1332360Y200413D01*
X1332667Y200103D01*
X1333050Y200000D01*
X1333433Y200103D01*
X1333740Y200413D01*
X1333893Y200878D01*
Y203100D01*
G01X1335192Y200000D02*
X1336150Y203100D01*
X1337108Y200000D01*
G01X1336763Y201085D02*
X1335537D01*
G01X1338483Y200000D02*
Y203100D01*
X1339442D01*
X1339748Y202945D01*
X1339940Y202738D01*
X1340017Y202325D01*
X1339940Y201912D01*
X1339710Y201653D01*
X1339442Y201498D01*
X1338483D01*
G01X1339442D02*
X1340017Y200000D01*
G01X1342350Y203100D02*
Y200000D01*
G01X1341468Y203100D02*
X1343232D01*
G01X1349317Y200000D02*
X1347783D01*
Y203100D01*
X1349317D01*
G01X1348703Y201602D02*
X1347783D01*
G01X1350653Y200000D02*
Y203100D01*
X1351650Y200517D01*
X1352647Y203100D01*
Y200000D01*
G01X1353983D02*
Y203100D01*
X1354903D01*
X1355210Y202945D01*
X1355440Y202583D01*
X1355517Y202170D01*
X1355440Y201757D01*
X1355248Y201447D01*
X1354903Y201292D01*
X1353983D01*
G01X1357850Y203100D02*
Y200000D01*
G01X1356968Y203100D02*
X1358732D01*
G01X1360950Y200000D02*
Y201395D01*
X1360183Y203100D01*
G01X1361717D02*
X1360950Y201395D01*
G01X1298307Y206820D02*
X1298537Y206458D01*
X1298843Y206252D01*
X1299188Y206200D01*
X1299495Y206252D01*
X1299802Y206510D01*
X1299993Y206820D01*
X1300032Y207130D01*
X1299955Y207492D01*
X1299687Y207750D01*
X1299418Y207853D01*
X1299073D01*
G01X1299418D02*
X1299648Y208008D01*
X1299840Y208267D01*
X1299917Y208577D01*
X1299840Y208887D01*
X1299648Y209145D01*
X1299303Y209300D01*
X1298958Y209248D01*
X1298613Y209042D01*
G01X1302173Y205632D02*
X1302327Y206303D01*
G01X1304507Y206665D02*
X1304737Y206407D01*
X1305005Y206252D01*
X1305350Y206200D01*
X1305695Y206303D01*
X1305963Y206510D01*
X1306155Y206872D01*
X1306193Y207285D01*
X1306117Y207698D01*
X1305925Y207957D01*
X1305657Y208163D01*
X1305388Y208215D01*
X1305120Y208163D01*
X1304775Y207957D01*
X1304890Y209300D01*
X1305925D01*
G01X1310707D02*
Y207078D01*
X1310860Y206613D01*
X1311167Y206303D01*
X1311550Y206200D01*
X1311933Y206303D01*
X1312240Y206613D01*
X1312393Y207078D01*
Y209300D01*
G01X1313692D02*
X1314650Y206200D01*
X1315608Y209300D01*
G01X1316983Y206200D02*
Y209300D01*
X1317903D01*
X1318210Y209145D01*
X1318440Y208783D01*
X1318517Y208370D01*
X1318440Y207957D01*
X1318248Y207647D01*
X1317903Y207492D01*
X1316983D01*
G01X1323950Y209300D02*
Y206200D01*
G01X1323068Y209300D02*
X1324832D01*
G01X1326283Y206200D02*
Y209300D01*
X1327242D01*
X1327548Y209145D01*
X1327740Y208938D01*
X1327817Y208525D01*
X1327740Y208112D01*
X1327510Y207853D01*
X1327242Y207698D01*
X1326283D01*
G01X1327242D02*
X1327817Y206200D01*
G01X1329690Y209300D02*
X1330610D01*
G01X1330150D02*
Y206200D01*
G01X1329690D02*
X1330610D01*
G01X1332483D02*
Y209300D01*
X1333403D01*
X1333710Y209145D01*
X1333940Y208783D01*
X1334017Y208370D01*
X1333940Y207957D01*
X1333748Y207647D01*
X1333403Y207492D01*
X1332483D01*
G01X1339450Y206200D02*
Y209300D01*
X1338990Y208680D01*
G01Y206200D02*
X1339910D01*
G01X1342550D02*
Y209300D01*
X1342090Y208680D01*
G01Y206200D02*
X1343010D01*
G01X1344692Y209300D02*
X1345650Y206200D01*
X1346608Y209300D01*
G01X1370500Y210451D02*
X1285878D01*
Y216451D01*
G01X1295419Y198451D02*
X1285878D01*
Y204451D01*
G01X1316091D02*
X1285878D01*
Y207130D01*
G01Y208759D02*
Y210451D01*
G01X1373986Y185451D02*
X1285878D01*
Y191951D01*
G01X1285880Y185470D02*
X1285878D01*
G01X1373986Y191951D02*
X1285878D01*
Y198451D01*
G01X1373986Y216451D02*
X1285878D01*
Y227451D01*
X1373986D01*
G01Y198451D02*
X1305300D01*
G01X1309486Y204451D02*
Y185451D01*
G01Y210451D02*
Y204451D01*
G01Y227451D02*
Y210451D01*
G01X1373986Y204451D02*
X1317504D01*
G01X1302900Y198451D02*
X1298085D01*
G01X1288629Y222508D02*
X1288706Y223180D01*
X1288821Y223748D01*
X1288974Y224265D01*
X1289166Y224833D01*
X1289473Y225608D01*
X1287939D01*
G01X1291729Y221940D02*
X1291883Y222611D01*
G01X1294254Y222870D02*
X1294523Y222611D01*
X1294829Y222508D01*
X1295136Y222611D01*
X1295404Y222921D01*
X1295596Y223386D01*
X1295673Y223851D01*
Y224420D01*
X1295596Y224885D01*
X1295404Y225298D01*
X1295174Y225505D01*
X1294906Y225608D01*
X1294599Y225505D01*
X1294369Y225298D01*
X1294216Y224988D01*
X1294139Y224575D01*
X1294216Y224213D01*
X1294408Y223851D01*
X1294638Y223645D01*
X1294906Y223593D01*
X1295213Y223696D01*
X1295443Y223955D01*
X1295673Y224420D01*
G01X1297929Y221940D02*
X1298083Y222611D01*
G01X1300378Y225091D02*
X1300608Y225401D01*
X1300876Y225556D01*
X1301183Y225608D01*
X1301566Y225505D01*
X1301834Y225246D01*
X1301911Y224936D01*
X1301873Y224626D01*
X1301719Y224368D01*
X1300953Y223851D01*
X1300608Y223490D01*
X1300378Y222973D01*
X1300301Y222508D01*
X1301911D01*
G01X1304129Y221940D02*
X1304283Y222611D01*
G01X1307766Y222508D02*
Y225608D01*
X1306348Y223386D01*
X1308264D01*
G01X1312624Y222508D02*
Y225608D01*
X1314388Y222508D01*
Y225608D01*
G01X1316606Y222508D02*
X1316299Y222560D01*
X1316031Y222766D01*
X1315801Y223076D01*
X1315648Y223438D01*
X1315571Y223851D01*
Y224265D01*
X1315648Y224678D01*
X1315801Y225040D01*
X1316031Y225350D01*
X1316299Y225556D01*
X1316606Y225608D01*
X1316913Y225556D01*
X1317181Y225350D01*
X1317411Y225040D01*
X1317564Y224678D01*
X1317641Y224265D01*
Y223851D01*
X1317564Y223438D01*
X1317411Y223076D01*
X1317181Y222766D01*
X1316913Y222560D01*
X1316606Y222508D01*
G01X1318939D02*
Y225608D01*
X1319898D01*
X1320204Y225453D01*
X1320396Y225246D01*
X1320473Y224833D01*
X1320396Y224420D01*
X1320166Y224161D01*
X1319898Y224006D01*
X1318939D01*
G01X1319898D02*
X1320473Y222508D01*
G01X1321809D02*
Y225608D01*
X1322806Y223025D01*
X1323803Y225608D01*
Y222508D01*
G01X1324948D02*
X1325906Y225608D01*
X1326864Y222508D01*
G01X1326519Y223593D02*
X1325293D01*
G01X1328239Y225608D02*
Y222508D01*
X1329773D01*
G01X1289103Y229017D02*
X1289295Y228707D01*
X1289525Y228500D01*
X1289793Y228397D01*
X1290100Y228500D01*
X1290330Y228707D01*
X1290560Y229017D01*
X1290637Y229430D01*
Y231497D01*
G01X1292318Y228759D02*
X1292587Y228500D01*
X1292893Y228397D01*
X1293200Y228500D01*
X1293468Y228810D01*
X1293660Y229275D01*
X1293737Y229740D01*
Y230309D01*
X1293660Y230774D01*
X1293468Y231187D01*
X1293238Y231394D01*
X1292970Y231497D01*
X1292663Y231394D01*
X1292433Y231187D01*
X1292280Y230877D01*
X1292203Y230464D01*
X1292280Y230102D01*
X1292472Y229740D01*
X1292702Y229534D01*
X1292970Y229482D01*
X1293277Y229585D01*
X1293507Y229844D01*
X1293737Y230309D01*
G01X1296300Y229947D02*
X1297067D01*
Y229017D01*
X1296837Y228707D01*
X1296568Y228500D01*
X1296185Y228397D01*
X1295802Y228500D01*
X1295533Y228707D01*
X1295303Y229017D01*
X1295150Y229379D01*
X1295073Y229792D01*
Y230154D01*
X1295150Y230464D01*
X1295303Y230825D01*
X1295533Y231135D01*
X1295763Y231342D01*
X1296070Y231497D01*
X1296338D01*
X1296645Y231394D01*
X1296875Y231187D01*
G01X1299170Y228397D02*
Y231497D01*
X1298710Y230877D01*
G01Y228397D02*
X1299630D01*
G01X1284094Y268097D02*
X1281594D01*
Y269138D01*
X1281719Y269472D01*
X1281886Y269680D01*
X1282219Y269763D01*
X1282552Y269680D01*
X1282761Y269430D01*
X1282886Y269138D01*
Y268097D01*
G01Y269138D02*
X1284094Y269763D01*
G01Y272030D02*
X1281594D01*
X1282094Y271530D01*
G01X1284094D02*
Y272530D01*
G01X1282011Y274338D02*
X1281761Y274588D01*
X1281636Y274880D01*
X1281594Y275213D01*
X1281677Y275630D01*
X1281886Y275922D01*
X1282136Y276005D01*
X1282386Y275963D01*
X1282594Y275797D01*
X1283011Y274963D01*
X1283302Y274588D01*
X1283719Y274338D01*
X1284094Y274255D01*
Y276005D01*
G01X1281594Y276980D02*
X1284094Y277563D01*
X1281594Y278230D01*
X1284094Y278897D01*
X1281594Y279480D01*
G01X1283719Y280413D02*
X1283927Y280663D01*
X1284052Y280955D01*
X1284094Y281330D01*
X1284011Y281705D01*
X1283844Y281997D01*
X1283552Y282205D01*
X1283219Y282247D01*
X1282886Y282163D01*
X1282677Y281955D01*
X1282511Y281663D01*
X1282469Y281372D01*
X1282511Y281080D01*
X1282677Y280705D01*
X1281594Y280830D01*
Y281955D01*
G01X1299450Y342200D02*
Y345300D01*
X1298990Y344680D01*
G01Y342200D02*
X1299910D01*
G01X1302550Y345300D02*
X1302243Y345197D01*
X1302013Y344938D01*
X1301860Y344628D01*
X1301745Y344215D01*
X1301707Y343750D01*
X1301745Y343285D01*
X1301860Y342872D01*
X1302013Y342562D01*
X1302243Y342303D01*
X1302550Y342200D01*
X1302857Y342303D01*
X1303087Y342562D01*
X1303240Y342872D01*
X1303355Y343285D01*
X1303393Y343750D01*
X1303355Y344215D01*
X1303240Y344628D01*
X1303087Y344938D01*
X1302857Y345197D01*
X1302550Y345300D01*
G01X1305573Y341632D02*
X1305727Y342303D01*
G01X1308750Y342200D02*
Y345300D01*
X1308290Y344680D01*
G01Y342200D02*
X1309210D01*
G01X1311122Y344783D02*
X1311352Y345093D01*
X1311620Y345248D01*
X1311927Y345300D01*
X1312310Y345197D01*
X1312578Y344938D01*
X1312655Y344628D01*
X1312617Y344318D01*
X1312463Y344060D01*
X1311697Y343543D01*
X1311352Y343182D01*
X1311122Y342665D01*
X1311045Y342200D01*
X1312655D01*
G01X1317283D02*
Y345300D01*
X1318242D01*
X1318548Y345145D01*
X1318740Y344938D01*
X1318817Y344525D01*
X1318740Y344112D01*
X1318510Y343853D01*
X1318242Y343698D01*
X1317283D01*
G01X1318242D02*
X1318817Y342200D01*
G01X1321917D02*
X1320383D01*
Y345300D01*
X1321917D01*
G01X1321303Y343802D02*
X1320383D01*
G01X1325093Y345042D02*
X1324863Y345197D01*
X1324595Y345300D01*
X1324288D01*
X1323943Y345145D01*
X1323675Y344887D01*
X1323483Y344577D01*
X1323330Y344060D01*
X1323292Y343595D01*
X1323368Y343130D01*
X1323483Y342820D01*
X1323713Y342510D01*
X1323982Y342303D01*
X1324250Y342200D01*
X1324518D01*
X1324787Y342303D01*
X1325017Y342458D01*
X1325208Y342665D01*
G01X1327350Y342200D02*
X1327043Y342252D01*
X1326775Y342458D01*
X1326545Y342768D01*
X1326392Y343130D01*
X1326315Y343543D01*
Y343957D01*
X1326392Y344370D01*
X1326545Y344732D01*
X1326775Y345042D01*
X1327043Y345248D01*
X1327350Y345300D01*
X1327657Y345248D01*
X1327925Y345042D01*
X1328155Y344732D01*
X1328308Y344370D01*
X1328385Y343957D01*
Y343543D01*
X1328308Y343130D01*
X1328155Y342768D01*
X1327925Y342458D01*
X1327657Y342252D01*
X1327350Y342200D01*
G01X1329492Y345300D02*
X1330450Y342200D01*
X1331408Y345300D01*
G01X1334317Y342200D02*
X1332783D01*
Y345300D01*
X1334317D01*
G01X1333703Y343802D02*
X1332783D01*
G01X1335883Y342200D02*
Y345300D01*
X1336842D01*
X1337148Y345145D01*
X1337340Y344938D01*
X1337417Y344525D01*
X1337340Y344112D01*
X1337110Y343853D01*
X1336842Y343698D01*
X1335883D01*
G01X1336842D02*
X1337417Y342200D01*
G01X1343157Y343853D02*
X1343310Y344008D01*
X1343425Y344267D01*
X1343502Y344628D01*
X1343425Y344938D01*
X1343272Y345145D01*
X1343003Y345300D01*
X1341968D01*
Y342200D01*
X1343233D01*
X1343502Y342407D01*
X1343655Y342717D01*
X1343732Y343078D01*
X1343655Y343440D01*
X1343425Y343750D01*
X1343157Y343853D01*
X1341968D01*
G01X1345490Y345300D02*
X1346410D01*
G01X1345950D02*
Y342200D01*
G01X1345490D02*
X1346410D01*
G01X1349050D02*
X1348743Y342252D01*
X1348475Y342458D01*
X1348245Y342768D01*
X1348092Y343130D01*
X1348015Y343543D01*
Y343957D01*
X1348092Y344370D01*
X1348245Y344732D01*
X1348475Y345042D01*
X1348743Y345248D01*
X1349050Y345300D01*
X1349357Y345248D01*
X1349625Y345042D01*
X1349855Y344732D01*
X1350008Y344370D01*
X1350085Y343957D01*
Y343543D01*
X1350008Y343130D01*
X1349855Y342768D01*
X1349625Y342458D01*
X1349357Y342252D01*
X1349050Y342200D01*
G01X1351345Y342613D02*
X1351652Y342355D01*
X1351997Y342200D01*
X1352303D01*
X1352610Y342355D01*
X1352840Y342613D01*
X1352955Y342975D01*
X1352878Y343337D01*
X1352687Y343647D01*
X1352342Y343853D01*
X1351882Y343957D01*
X1351613Y344163D01*
X1351498Y344525D01*
X1351575Y344887D01*
X1351767Y345145D01*
X1352035Y345300D01*
X1352303D01*
X1352572Y345197D01*
X1352802Y344938D01*
G01X1287200Y340400D02*
X1379200D01*
G01X1288200Y374600D02*
X1287200D01*
Y340400D01*
G01X1335200Y364900D02*
Y370200D01*
X1314700D01*
Y340400D01*
G01X1281290Y287788D02*
X1281165Y287538D01*
X1281082Y287246D01*
Y286913D01*
X1281207Y286538D01*
X1281415Y286246D01*
X1281665Y286038D01*
X1282082Y285871D01*
X1282457Y285829D01*
X1282832Y285913D01*
X1283082Y286038D01*
X1283332Y286288D01*
X1283499Y286579D01*
X1283582Y286871D01*
Y287163D01*
X1283499Y287454D01*
X1283374Y287704D01*
X1283207Y287913D01*
G01X1283582Y289888D02*
X1283040Y289971D01*
X1282582Y290096D01*
X1282165Y290263D01*
X1281707Y290471D01*
X1281082Y290804D01*
Y289138D01*
G01X1283582Y292279D02*
X1281082D01*
Y293863D01*
G01X1282290Y293279D02*
Y292279D01*
G01X1283582Y296171D02*
X1281082D01*
X1281582Y295671D01*
G01X1283582D02*
Y296671D01*
G01Y299271D02*
X1283540Y299563D01*
X1283415Y299896D01*
X1283207Y300104D01*
X1282915Y300188D01*
X1282624Y300104D01*
X1282374Y299854D01*
X1282249Y299479D01*
Y299063D01*
X1282165Y298813D01*
X1281957Y298604D01*
X1281665Y298521D01*
X1281374Y298646D01*
X1281165Y298938D01*
X1281082Y299271D01*
X1281165Y299604D01*
X1281374Y299896D01*
X1281665Y300021D01*
X1281957Y299938D01*
X1282165Y299729D01*
X1282249Y299479D01*
Y299063D01*
X1282374Y298688D01*
X1282624Y298438D01*
X1282915Y298354D01*
X1283207Y298438D01*
X1283415Y298646D01*
X1283540Y298979D01*
X1283582Y299271D01*
G01X1281120Y305931D02*
X1280995Y305681D01*
X1280912Y305389D01*
Y305056D01*
X1281037Y304681D01*
X1281245Y304389D01*
X1281495Y304181D01*
X1281912Y304014D01*
X1282287Y303972D01*
X1282662Y304056D01*
X1282912Y304181D01*
X1283162Y304431D01*
X1283329Y304722D01*
X1283412Y305014D01*
Y305306D01*
X1283329Y305597D01*
X1283204Y305847D01*
X1283037Y306056D01*
G01X1283412Y308031D02*
X1282870Y308114D01*
X1282412Y308239D01*
X1281995Y308406D01*
X1281537Y308614D01*
X1280912Y308947D01*
Y307281D01*
G01X1283412Y310422D02*
X1280912D01*
Y312006D01*
G01X1282120Y311422D02*
Y310422D01*
G01X1283412Y314314D02*
X1280912D01*
X1281412Y313814D01*
G01X1283412D02*
Y314814D01*
G01X1282370Y316622D02*
X1282079Y316914D01*
X1281912Y317164D01*
X1281829Y317497D01*
X1281912Y317789D01*
X1282079Y317997D01*
X1282329Y318164D01*
X1282620Y318206D01*
X1282870Y318164D01*
X1283120Y317997D01*
X1283329Y317747D01*
X1283412Y317456D01*
X1283329Y317122D01*
X1283079Y316831D01*
X1282704Y316664D01*
X1282287Y316622D01*
X1281745Y316706D01*
X1281454Y316831D01*
X1281162Y317039D01*
X1280954Y317331D01*
X1280912Y317622D01*
X1280995Y317914D01*
X1281204Y318122D01*
G01X1288028Y402162D02*
X1288297Y401903D01*
X1288603Y401800D01*
X1288910Y401903D01*
X1289178Y402213D01*
X1289370Y402678D01*
X1289447Y403143D01*
Y403712D01*
X1289370Y404177D01*
X1289178Y404590D01*
X1288948Y404797D01*
X1288680Y404900D01*
X1288373Y404797D01*
X1288143Y404590D01*
X1287990Y404280D01*
X1287913Y403867D01*
X1287990Y403505D01*
X1288182Y403143D01*
X1288412Y402937D01*
X1288680Y402885D01*
X1288987Y402988D01*
X1289217Y403247D01*
X1289447Y403712D01*
G01X1281603Y401800D02*
X1281680Y402472D01*
X1281795Y403040D01*
X1281948Y403557D01*
X1282140Y404125D01*
X1282447Y404900D01*
X1280913D01*
G01X1294680Y401800D02*
Y404900D01*
X1294220Y404280D01*
G01Y401800D02*
X1295140D01*
G01X1297780D02*
Y404900D01*
X1297320Y404280D01*
G01Y401800D02*
X1298240D01*
G01X1294483Y376120D02*
X1294675Y375810D01*
X1294905Y375603D01*
X1295173Y375500D01*
X1295480Y375603D01*
X1295710Y375810D01*
X1295940Y376120D01*
X1296017Y376533D01*
Y378600D01*
G01X1298273Y375500D02*
X1298350Y376172D01*
X1298465Y376740D01*
X1298618Y377257D01*
X1298810Y377825D01*
X1299117Y378600D01*
X1297583D01*
G01X1301680Y377050D02*
X1302447D01*
Y376120D01*
X1302217Y375810D01*
X1301948Y375603D01*
X1301565Y375500D01*
X1301182Y375603D01*
X1300913Y375810D01*
X1300683Y376120D01*
X1300530Y376482D01*
X1300453Y376895D01*
Y377257D01*
X1300530Y377567D01*
X1300683Y377928D01*
X1300913Y378238D01*
X1301143Y378445D01*
X1301450Y378600D01*
X1301718D01*
X1302025Y378497D01*
X1302255Y378290D01*
G01X1303707Y376120D02*
X1303937Y375758D01*
X1304243Y375552D01*
X1304588Y375500D01*
X1304895Y375552D01*
X1305202Y375810D01*
X1305393Y376120D01*
X1305432Y376430D01*
X1305355Y376792D01*
X1305087Y377050D01*
X1304818Y377153D01*
X1304473D01*
G01X1304818D02*
X1305048Y377308D01*
X1305240Y377567D01*
X1305317Y377877D01*
X1305240Y378187D01*
X1305048Y378445D01*
X1304703Y378600D01*
X1304358Y378548D01*
X1304013Y378342D01*
G01X1316968Y366300D02*
Y369400D01*
X1318732Y366300D01*
Y369400D01*
G01X1320950Y366300D02*
X1320643Y366352D01*
X1320375Y366558D01*
X1320145Y366868D01*
X1319992Y367230D01*
X1319915Y367643D01*
Y368057D01*
X1319992Y368470D01*
X1320145Y368832D01*
X1320375Y369142D01*
X1320643Y369348D01*
X1320950Y369400D01*
X1321257Y369348D01*
X1321525Y369142D01*
X1321755Y368832D01*
X1321908Y368470D01*
X1321985Y368057D01*
Y367643D01*
X1321908Y367230D01*
X1321755Y366868D01*
X1321525Y366558D01*
X1321257Y366352D01*
X1320950Y366300D01*
G01X1323283D02*
Y369400D01*
X1324242D01*
X1324548Y369245D01*
X1324740Y369038D01*
X1324817Y368625D01*
X1324740Y368212D01*
X1324510Y367953D01*
X1324242Y367798D01*
X1323283D01*
G01X1324242D02*
X1324817Y366300D01*
G01X1326153D02*
Y369400D01*
X1327150Y366817D01*
X1328147Y369400D01*
Y366300D01*
G01X1329292D02*
X1330250Y369400D01*
X1331208Y366300D01*
G01X1330863Y367385D02*
X1329637D01*
G01X1332583Y369400D02*
Y366300D01*
X1334117D01*
G01X1304707Y361120D02*
X1304937Y360758D01*
X1305243Y360552D01*
X1305588Y360500D01*
X1305895Y360552D01*
X1306202Y360810D01*
X1306393Y361120D01*
X1306432Y361430D01*
X1306355Y361792D01*
X1306087Y362050D01*
X1305818Y362153D01*
X1305473D01*
G01X1305818D02*
X1306048Y362308D01*
X1306240Y362567D01*
X1306317Y362877D01*
X1306240Y363187D01*
X1306048Y363445D01*
X1305703Y363600D01*
X1305358Y363548D01*
X1305013Y363342D01*
G01X1308573Y359932D02*
X1308727Y360603D01*
G01X1310907Y360965D02*
X1311137Y360707D01*
X1311405Y360552D01*
X1311750Y360500D01*
X1312095Y360603D01*
X1312363Y360810D01*
X1312555Y361172D01*
X1312593Y361585D01*
X1312517Y361998D01*
X1312325Y362257D01*
X1312057Y362463D01*
X1311788Y362515D01*
X1311520Y362463D01*
X1311175Y362257D01*
X1311290Y363600D01*
X1312325D01*
G01X1316953Y360500D02*
Y363600D01*
X1317950Y361017D01*
X1318947Y363600D01*
Y360500D01*
G01X1321817D02*
X1320283D01*
Y363600D01*
X1321817D01*
G01X1321203Y362102D02*
X1320283D01*
G01X1326522Y360500D02*
Y363600D01*
X1327978D01*
G01X1327442Y362102D02*
X1326522D01*
G01X1330350Y360500D02*
X1330043Y360552D01*
X1329775Y360758D01*
X1329545Y361068D01*
X1329392Y361430D01*
X1329315Y361843D01*
Y362257D01*
X1329392Y362670D01*
X1329545Y363032D01*
X1329775Y363342D01*
X1330043Y363548D01*
X1330350Y363600D01*
X1330657Y363548D01*
X1330925Y363342D01*
X1331155Y363032D01*
X1331308Y362670D01*
X1331385Y362257D01*
Y361843D01*
X1331308Y361430D01*
X1331155Y361068D01*
X1330925Y360758D01*
X1330657Y360552D01*
X1330350Y360500D01*
G01X1332683D02*
Y363600D01*
X1333642D01*
X1333948Y363445D01*
X1334140Y363238D01*
X1334217Y362825D01*
X1334140Y362412D01*
X1333910Y362153D01*
X1333642Y361998D01*
X1332683D01*
G01X1333642D02*
X1334217Y360500D01*
G01X1337393Y363342D02*
X1337163Y363497D01*
X1336895Y363600D01*
X1336588D01*
X1336243Y363445D01*
X1335975Y363187D01*
X1335783Y362877D01*
X1335630Y362360D01*
X1335592Y361895D01*
X1335668Y361430D01*
X1335783Y361120D01*
X1336013Y360810D01*
X1336282Y360603D01*
X1336550Y360500D01*
X1336818D01*
X1337087Y360603D01*
X1337317Y360758D01*
X1337508Y360965D01*
G01X1340417Y360500D02*
X1338883D01*
Y363600D01*
X1340417D01*
G01X1339803Y362102D02*
X1338883D01*
G01X1345007Y363600D02*
Y361378D01*
X1345160Y360913D01*
X1345467Y360603D01*
X1345850Y360500D01*
X1346233Y360603D01*
X1346540Y360913D01*
X1346693Y361378D01*
Y363600D01*
G01X1348183Y360500D02*
Y363600D01*
X1349103D01*
X1349410Y363445D01*
X1349640Y363083D01*
X1349717Y362670D01*
X1349640Y362257D01*
X1349448Y361947D01*
X1349103Y361792D01*
X1348183D01*
G01X1351207Y360500D02*
Y363600D01*
X1351973D01*
X1352280Y363445D01*
X1352510Y363238D01*
X1352702Y362928D01*
X1352855Y362567D01*
X1352893Y362050D01*
X1352855Y361533D01*
X1352702Y361172D01*
X1352510Y360862D01*
X1352280Y360655D01*
X1351973Y360500D01*
X1351207D01*
G01X1301798Y354762D02*
X1302067Y354503D01*
X1302373Y354400D01*
X1302680Y354503D01*
X1302948Y354813D01*
X1303140Y355278D01*
X1303217Y355743D01*
Y356312D01*
X1303140Y356777D01*
X1302948Y357190D01*
X1302718Y357397D01*
X1302450Y357500D01*
X1302143Y357397D01*
X1301913Y357190D01*
X1301760Y356880D01*
X1301683Y356467D01*
X1301760Y356105D01*
X1301952Y355743D01*
X1302182Y355537D01*
X1302450Y355485D01*
X1302757Y355588D01*
X1302987Y355847D01*
X1303217Y356312D01*
G01X1305473Y353832D02*
X1305627Y354503D01*
G01X1308650Y354400D02*
Y357500D01*
X1308190Y356880D01*
G01Y354400D02*
X1309110D01*
G01X1311750D02*
Y357500D01*
X1311290Y356880D01*
G01Y354400D02*
X1312210D01*
G01X1317183D02*
Y357500D01*
X1318103D01*
X1318410Y357345D01*
X1318640Y356983D01*
X1318717Y356570D01*
X1318640Y356157D01*
X1318448Y355847D01*
X1318103Y355692D01*
X1317183D01*
G01X1320092Y354400D02*
X1321050Y357500D01*
X1322008Y354400D01*
G01X1321663Y355485D02*
X1320437D01*
G01X1323345Y354813D02*
X1323652Y354555D01*
X1323997Y354400D01*
X1324303D01*
X1324610Y354555D01*
X1324840Y354813D01*
X1324955Y355175D01*
X1324878Y355537D01*
X1324687Y355847D01*
X1324342Y356053D01*
X1323882Y356157D01*
X1323613Y356363D01*
X1323498Y356725D01*
X1323575Y357087D01*
X1323767Y357345D01*
X1324035Y357500D01*
X1324303D01*
X1324572Y357397D01*
X1324802Y357138D01*
G01X1326445Y354813D02*
X1326752Y354555D01*
X1327097Y354400D01*
X1327403D01*
X1327710Y354555D01*
X1327940Y354813D01*
X1328055Y355175D01*
X1327978Y355537D01*
X1327787Y355847D01*
X1327442Y356053D01*
X1326982Y356157D01*
X1326713Y356363D01*
X1326598Y356725D01*
X1326675Y357087D01*
X1326867Y357345D01*
X1327135Y357500D01*
X1327403D01*
X1327672Y357397D01*
X1327902Y357138D01*
G01X1329200Y357500D02*
X1329737Y354400D01*
X1330350Y357500D01*
X1330963Y354400D01*
X1331500Y357500D01*
G01X1332607Y354400D02*
Y357500D01*
X1333373D01*
X1333680Y357345D01*
X1333910Y357138D01*
X1334102Y356828D01*
X1334255Y356467D01*
X1334293Y355950D01*
X1334255Y355433D01*
X1334102Y355072D01*
X1333910Y354762D01*
X1333680Y354555D01*
X1333373Y354400D01*
X1332607D01*
G01X1340493Y357242D02*
X1340263Y357397D01*
X1339995Y357500D01*
X1339688D01*
X1339343Y357345D01*
X1339075Y357087D01*
X1338883Y356777D01*
X1338730Y356260D01*
X1338692Y355795D01*
X1338768Y355330D01*
X1338883Y355020D01*
X1339113Y354710D01*
X1339382Y354503D01*
X1339650Y354400D01*
X1339918D01*
X1340187Y354503D01*
X1340417Y354658D01*
X1340608Y354865D01*
G01X1341983Y357500D02*
Y354400D01*
X1343517D01*
G01X1345083D02*
Y357500D01*
X1346042D01*
X1346348Y357345D01*
X1346540Y357138D01*
X1346617Y356725D01*
X1346540Y356312D01*
X1346310Y356053D01*
X1346042Y355898D01*
X1345083D01*
G01X1346042D02*
X1346617Y354400D01*
G01X1305910Y348300D02*
Y351400D01*
X1304492Y349178D01*
X1306408D01*
G01X1308473Y347732D02*
X1308627Y348403D01*
G01X1310922Y349592D02*
X1311190Y349953D01*
X1311420Y350160D01*
X1311727Y350263D01*
X1311995Y350160D01*
X1312187Y349953D01*
X1312340Y349643D01*
X1312378Y349282D01*
X1312340Y348972D01*
X1312187Y348662D01*
X1311957Y348403D01*
X1311688Y348300D01*
X1311382Y348403D01*
X1311113Y348713D01*
X1310960Y349178D01*
X1310922Y349695D01*
X1310998Y350367D01*
X1311113Y350728D01*
X1311305Y351090D01*
X1311573Y351348D01*
X1311842Y351400D01*
X1312110Y351297D01*
X1312302Y351038D01*
G01X1318157Y349953D02*
X1318310Y350108D01*
X1318425Y350367D01*
X1318502Y350728D01*
X1318425Y351038D01*
X1318272Y351245D01*
X1318003Y351400D01*
X1316968D01*
Y348300D01*
X1318233D01*
X1318502Y348507D01*
X1318655Y348817D01*
X1318732Y349178D01*
X1318655Y349540D01*
X1318425Y349850D01*
X1318157Y349953D01*
X1316968D01*
G01X1320490Y351400D02*
X1321410D01*
G01X1320950D02*
Y348300D01*
G01X1320490D02*
X1321410D01*
G01X1324050D02*
X1323743Y348352D01*
X1323475Y348558D01*
X1323245Y348868D01*
X1323092Y349230D01*
X1323015Y349643D01*
Y350057D01*
X1323092Y350470D01*
X1323245Y350832D01*
X1323475Y351142D01*
X1323743Y351348D01*
X1324050Y351400D01*
X1324357Y351348D01*
X1324625Y351142D01*
X1324855Y350832D01*
X1325008Y350470D01*
X1325085Y350057D01*
Y349643D01*
X1325008Y349230D01*
X1324855Y348868D01*
X1324625Y348558D01*
X1324357Y348352D01*
X1324050Y348300D01*
G01X1326345Y348713D02*
X1326652Y348455D01*
X1326997Y348300D01*
X1327303D01*
X1327610Y348455D01*
X1327840Y348713D01*
X1327955Y349075D01*
X1327878Y349437D01*
X1327687Y349747D01*
X1327342Y349953D01*
X1326882Y350057D01*
X1326613Y350263D01*
X1326498Y350625D01*
X1326575Y350987D01*
X1326767Y351245D01*
X1327035Y351400D01*
X1327303D01*
X1327572Y351297D01*
X1327802Y351038D01*
G01X1332507Y351400D02*
Y349178D01*
X1332660Y348713D01*
X1332967Y348403D01*
X1333350Y348300D01*
X1333733Y348403D01*
X1334040Y348713D01*
X1334193Y349178D01*
Y351400D01*
G01X1335645Y348713D02*
X1335952Y348455D01*
X1336297Y348300D01*
X1336603D01*
X1336910Y348455D01*
X1337140Y348713D01*
X1337255Y349075D01*
X1337178Y349437D01*
X1336987Y349747D01*
X1336642Y349953D01*
X1336182Y350057D01*
X1335913Y350263D01*
X1335798Y350625D01*
X1335875Y350987D01*
X1336067Y351245D01*
X1336335Y351400D01*
X1336603D01*
X1336872Y351297D01*
X1337102Y351038D01*
G01X1339857Y349953D02*
X1340010Y350108D01*
X1340125Y350367D01*
X1340202Y350728D01*
X1340125Y351038D01*
X1339972Y351245D01*
X1339703Y351400D01*
X1338668D01*
Y348300D01*
X1339933D01*
X1340202Y348507D01*
X1340355Y348817D01*
X1340432Y349178D01*
X1340355Y349540D01*
X1340125Y349850D01*
X1339857Y349953D01*
X1338668D01*
G01X1345022Y348300D02*
Y351400D01*
X1346478D01*
G01X1345942Y349902D02*
X1345022D01*
G01X1348083Y351400D02*
Y348300D01*
X1349617D01*
G01X1351145Y348713D02*
X1351452Y348455D01*
X1351797Y348300D01*
X1352103D01*
X1352410Y348455D01*
X1352640Y348713D01*
X1352755Y349075D01*
X1352678Y349437D01*
X1352487Y349747D01*
X1352142Y349953D01*
X1351682Y350057D01*
X1351413Y350263D01*
X1351298Y350625D01*
X1351375Y350987D01*
X1351567Y351245D01*
X1351835Y351400D01*
X1352103D01*
X1352372Y351297D01*
X1352602Y351038D01*
G01X1354245Y348300D02*
Y351400D01*
G01X1355855D02*
Y348300D01*
G01Y349850D02*
X1354245D01*
G01X1360483Y348300D02*
Y351400D01*
X1361442D01*
X1361748Y351245D01*
X1361940Y351038D01*
X1362017Y350625D01*
X1361940Y350212D01*
X1361710Y349953D01*
X1361442Y349798D01*
X1360483D01*
G01X1361442D02*
X1362017Y348300D01*
G01X1365193Y351142D02*
X1364963Y351297D01*
X1364695Y351400D01*
X1364388D01*
X1364043Y351245D01*
X1363775Y350987D01*
X1363583Y350677D01*
X1363430Y350160D01*
X1363392Y349695D01*
X1363468Y349230D01*
X1363583Y348920D01*
X1363813Y348610D01*
X1364082Y348403D01*
X1364350Y348300D01*
X1364618D01*
X1364887Y348403D01*
X1365117Y348558D01*
X1365308Y348765D01*
G01X1366492Y351400D02*
X1367450Y348300D01*
X1368408Y351400D01*
G01X1369783Y348300D02*
Y351400D01*
X1370742D01*
X1371048Y351245D01*
X1371240Y351038D01*
X1371317Y350625D01*
X1371240Y350212D01*
X1371010Y349953D01*
X1370742Y349798D01*
X1369783D01*
G01X1370742D02*
X1371317Y348300D01*
G01X1373650D02*
Y349695D01*
X1372883Y351400D01*
G01X1374417D02*
X1373650Y349695D01*
G01X1289839Y370220D02*
Y373320D01*
X1289379Y372700D01*
G01Y370220D02*
X1290299D01*
G01X1292862Y369652D02*
X1293016Y370323D01*
G01X1295196Y370840D02*
X1295426Y370478D01*
X1295732Y370272D01*
X1296077Y370220D01*
X1296384Y370272D01*
X1296691Y370530D01*
X1296882Y370840D01*
X1296921Y371150D01*
X1296844Y371512D01*
X1296576Y371770D01*
X1296307Y371873D01*
X1295962D01*
G01X1296307D02*
X1296537Y372028D01*
X1296729Y372287D01*
X1296806Y372597D01*
X1296729Y372907D01*
X1296537Y373165D01*
X1296192Y373320D01*
X1295847Y373268D01*
X1295502Y373062D01*
G01X1299062Y369652D02*
X1299216Y370323D01*
G01X1302162Y370220D02*
X1302239Y370892D01*
X1302354Y371460D01*
X1302507Y371977D01*
X1302699Y372545D01*
X1303006Y373320D01*
X1301472D01*
G01X1305262Y369652D02*
X1305416Y370323D01*
G01X1307787Y370582D02*
X1308056Y370323D01*
X1308362Y370220D01*
X1308669Y370323D01*
X1308937Y370633D01*
X1309129Y371098D01*
X1309206Y371563D01*
Y372132D01*
X1309129Y372597D01*
X1308937Y373010D01*
X1308707Y373217D01*
X1308439Y373320D01*
X1308132Y373217D01*
X1307902Y373010D01*
X1307749Y372700D01*
X1307672Y372287D01*
X1307749Y371925D01*
X1307941Y371563D01*
X1308171Y371357D01*
X1308439Y371305D01*
X1308746Y371408D01*
X1308976Y371667D01*
X1309206Y372132D01*
G01X1289111Y368903D02*
X1289341Y369213D01*
X1289609Y369368D01*
X1289916Y369420D01*
X1290299Y369317D01*
X1290567Y369058D01*
X1290644Y368748D01*
X1290606Y368438D01*
X1290452Y368180D01*
X1289686Y367663D01*
X1289341Y367302D01*
X1289111Y366785D01*
X1289034Y366320D01*
X1290644D01*
G01X1292862Y365752D02*
X1293016Y366423D01*
G01X1296499Y366320D02*
Y369420D01*
X1295081Y367198D01*
X1296997D01*
G01X1299062Y365752D02*
X1299216Y366423D01*
G01X1302239Y366320D02*
X1302507Y366372D01*
X1302814Y366527D01*
X1303006Y366785D01*
X1303082Y367147D01*
X1303006Y367508D01*
X1302776Y367818D01*
X1302431Y367973D01*
X1302047D01*
X1301817Y368077D01*
X1301626Y368335D01*
X1301549Y368697D01*
X1301664Y369058D01*
X1301932Y369317D01*
X1302239Y369420D01*
X1302546Y369317D01*
X1302814Y369058D01*
X1302929Y368697D01*
X1302852Y368335D01*
X1302661Y368077D01*
X1302431Y367973D01*
X1302047D01*
X1301702Y367818D01*
X1301472Y367508D01*
X1301396Y367147D01*
X1301472Y366785D01*
X1301664Y366527D01*
X1301971Y366372D01*
X1302239Y366320D01*
G01X1305262Y365752D02*
X1305416Y366423D01*
G01X1308439Y366320D02*
Y369420D01*
X1307979Y368800D01*
G01Y366320D02*
X1308899D01*
G01X1311539Y369420D02*
X1311232Y369317D01*
X1311002Y369058D01*
X1310849Y368748D01*
X1310734Y368335D01*
X1310696Y367870D01*
X1310734Y367405D01*
X1310849Y366992D01*
X1311002Y366682D01*
X1311232Y366423D01*
X1311539Y366320D01*
X1311846Y366423D01*
X1312076Y366682D01*
X1312229Y366992D01*
X1312344Y367405D01*
X1312382Y367870D01*
X1312344Y368335D01*
X1312229Y368748D01*
X1312076Y369058D01*
X1311846Y369317D01*
X1311539Y369420D01*
G01X1379200Y346900D02*
X1287200D01*
G01Y352900D02*
X1379200D01*
G01X1287200Y358900D02*
X1354145D01*
G01X1287200Y364900D02*
X1354145D01*
G01X1314700Y370200D02*
Y374600D01*
X1291400D01*
G01X1334767Y373492D02*
X1334517Y373617D01*
X1334225Y373700D01*
X1333892D01*
X1333517Y373575D01*
X1333225Y373367D01*
X1333017Y373117D01*
X1332850Y372700D01*
X1332808Y372325D01*
X1332892Y371950D01*
X1333017Y371700D01*
X1333267Y371450D01*
X1333558Y371283D01*
X1333850Y371200D01*
X1334142D01*
X1334433Y371283D01*
X1334683Y371408D01*
X1334892Y371575D01*
G01X1336950Y373700D02*
Y371200D01*
G01X1335992Y373700D02*
X1337908D01*
G01X1339967Y371200D02*
X1340050Y371742D01*
X1340175Y372200D01*
X1340342Y372617D01*
X1340550Y373075D01*
X1340883Y373700D01*
X1339217D01*
G01X1342358Y373283D02*
X1342608Y373533D01*
X1342900Y373658D01*
X1343233Y373700D01*
X1343650Y373617D01*
X1343942Y373408D01*
X1344025Y373158D01*
X1343983Y372908D01*
X1343817Y372700D01*
X1342983Y372283D01*
X1342608Y371992D01*
X1342358Y371575D01*
X1342275Y371200D01*
X1344025D01*
G01X1317102Y373728D02*
Y371228D01*
X1318768D01*
G01X1320952D02*
X1321035Y371770D01*
X1321160Y372228D01*
X1321327Y372645D01*
X1321535Y373103D01*
X1321868Y373728D01*
X1320202D01*
G01X1325052Y373520D02*
X1324802Y373645D01*
X1324510Y373728D01*
X1324177D01*
X1323802Y373603D01*
X1323510Y373395D01*
X1323302Y373145D01*
X1323135Y372728D01*
X1323093Y372353D01*
X1323177Y371978D01*
X1323302Y371728D01*
X1323552Y371478D01*
X1323843Y371311D01*
X1324135Y371228D01*
X1324427D01*
X1324718Y371311D01*
X1324968Y371436D01*
X1325177Y371603D01*
G01X1326443Y373311D02*
X1326693Y373561D01*
X1326985Y373686D01*
X1327318Y373728D01*
X1327735Y373645D01*
X1328027Y373436D01*
X1328110Y373186D01*
X1328068Y372936D01*
X1327902Y372728D01*
X1327068Y372311D01*
X1326693Y372020D01*
X1326443Y371603D01*
X1326360Y371228D01*
X1328110D01*
G01X1310550Y394050D02*
Y400098D01*
X1347950D01*
Y394050D01*
G01Y374902D02*
X1310550D01*
Y380950D01*
G01X1286380Y409100D02*
Y412200D01*
X1285920Y411580D01*
G01Y409100D02*
X1286840D01*
G01X1289480Y412200D02*
X1289173Y412097D01*
X1288943Y411838D01*
X1288790Y411528D01*
X1288675Y411115D01*
X1288637Y410650D01*
X1288675Y410185D01*
X1288790Y409772D01*
X1288943Y409462D01*
X1289173Y409203D01*
X1289480Y409100D01*
X1289787Y409203D01*
X1290017Y409462D01*
X1290170Y409772D01*
X1290285Y410185D01*
X1290323Y410650D01*
X1290285Y411115D01*
X1290170Y411528D01*
X1290017Y411838D01*
X1289787Y412097D01*
X1289480Y412200D01*
G01X1294380Y409100D02*
Y412200D01*
X1293920Y411580D01*
G01Y409100D02*
X1294840D01*
G01X1296752Y411683D02*
X1296982Y411993D01*
X1297250Y412148D01*
X1297557Y412200D01*
X1297940Y412097D01*
X1298208Y411838D01*
X1298285Y411528D01*
X1298247Y411218D01*
X1298093Y410960D01*
X1297327Y410443D01*
X1296982Y410082D01*
X1296752Y409565D01*
X1296675Y409100D01*
X1298285D01*
G01X1317817Y414330D02*
Y416830D01*
X1318858D01*
X1319192Y416705D01*
X1319400Y416538D01*
X1319483Y416205D01*
X1319400Y415872D01*
X1319150Y415663D01*
X1318858Y415538D01*
X1317817D01*
G01X1318858D02*
X1319483Y414330D01*
G01X1321667D02*
X1321750Y414872D01*
X1321875Y415330D01*
X1322042Y415747D01*
X1322250Y416205D01*
X1322583Y416830D01*
X1320917D01*
G01X1325767Y416622D02*
X1325517Y416747D01*
X1325225Y416830D01*
X1324892D01*
X1324517Y416705D01*
X1324225Y416497D01*
X1324017Y416247D01*
X1323850Y415830D01*
X1323808Y415455D01*
X1323892Y415080D01*
X1324017Y414830D01*
X1324267Y414580D01*
X1324558Y414413D01*
X1324850Y414330D01*
X1325142D01*
X1325433Y414413D01*
X1325683Y414538D01*
X1325892Y414705D01*
G01X1327033Y414830D02*
X1327283Y414538D01*
X1327617Y414372D01*
X1327992Y414330D01*
X1328325Y414372D01*
X1328658Y414580D01*
X1328867Y414830D01*
X1328908Y415080D01*
X1328825Y415372D01*
X1328533Y415580D01*
X1328242Y415663D01*
X1327867D01*
G01X1328242D02*
X1328492Y415788D01*
X1328700Y415997D01*
X1328783Y416247D01*
X1328700Y416497D01*
X1328492Y416705D01*
X1328117Y416830D01*
X1327742Y416788D01*
X1327367Y416622D01*
G01X1331419Y422650D02*
Y425150D01*
X1332460D01*
X1332794Y425025D01*
X1333002Y424858D01*
X1333085Y424525D01*
X1333002Y424192D01*
X1332752Y423983D01*
X1332460Y423858D01*
X1331419D01*
G01X1332460D02*
X1333085Y422650D01*
G01X1335269D02*
X1335352Y423192D01*
X1335477Y423650D01*
X1335644Y424067D01*
X1335852Y424525D01*
X1336185Y425150D01*
X1334519D01*
G01X1339369Y424942D02*
X1339119Y425067D01*
X1338827Y425150D01*
X1338494D01*
X1338119Y425025D01*
X1337827Y424817D01*
X1337619Y424567D01*
X1337452Y424150D01*
X1337410Y423775D01*
X1337494Y423400D01*
X1337619Y423150D01*
X1337869Y422900D01*
X1338160Y422733D01*
X1338452Y422650D01*
X1338744D01*
X1339035Y422733D01*
X1339285Y422858D01*
X1339494Y423025D01*
G01X1340760Y424733D02*
X1341010Y424983D01*
X1341302Y425108D01*
X1341635Y425150D01*
X1342052Y425067D01*
X1342344Y424858D01*
X1342427Y424608D01*
X1342385Y424358D01*
X1342219Y424150D01*
X1341385Y423733D01*
X1341010Y423442D01*
X1340760Y423025D01*
X1340677Y422650D01*
X1342427D01*
G01X1345152D02*
Y425150D01*
X1343610Y423358D01*
X1345694D01*
G01X1319567Y412922D02*
X1319317Y413047D01*
X1319025Y413130D01*
X1318692D01*
X1318317Y413005D01*
X1318025Y412797D01*
X1317817Y412547D01*
X1317650Y412130D01*
X1317608Y411755D01*
X1317692Y411380D01*
X1317817Y411130D01*
X1318067Y410880D01*
X1318358Y410713D01*
X1318650Y410630D01*
X1318942D01*
X1319233Y410713D01*
X1319483Y410838D01*
X1319692Y411005D01*
G01X1321667Y410630D02*
X1321750Y411172D01*
X1321875Y411630D01*
X1322042Y412047D01*
X1322250Y412505D01*
X1322583Y413130D01*
X1320917D01*
G01X1325767Y412922D02*
X1325517Y413047D01*
X1325225Y413130D01*
X1324892D01*
X1324517Y413005D01*
X1324225Y412797D01*
X1324017Y412547D01*
X1323850Y412130D01*
X1323808Y411755D01*
X1323892Y411380D01*
X1324017Y411130D01*
X1324267Y410880D01*
X1324558Y410713D01*
X1324850Y410630D01*
X1325142D01*
X1325433Y410713D01*
X1325683Y410838D01*
X1325892Y411005D01*
G01X1327158Y411672D02*
X1327450Y411963D01*
X1327700Y412130D01*
X1328033Y412213D01*
X1328325Y412130D01*
X1328533Y411963D01*
X1328700Y411713D01*
X1328742Y411422D01*
X1328700Y411172D01*
X1328533Y410922D01*
X1328283Y410713D01*
X1327992Y410630D01*
X1327658Y410713D01*
X1327367Y410963D01*
X1327200Y411338D01*
X1327158Y411755D01*
X1327242Y412297D01*
X1327367Y412588D01*
X1327575Y412880D01*
X1327867Y413088D01*
X1328158Y413130D01*
X1328450Y413047D01*
X1328658Y412838D01*
G01X1319567Y409222D02*
X1319317Y409347D01*
X1319025Y409430D01*
X1318692D01*
X1318317Y409305D01*
X1318025Y409097D01*
X1317817Y408847D01*
X1317650Y408430D01*
X1317608Y408055D01*
X1317692Y407680D01*
X1317817Y407430D01*
X1318067Y407180D01*
X1318358Y407013D01*
X1318650Y406930D01*
X1318942D01*
X1319233Y407013D01*
X1319483Y407138D01*
X1319692Y407305D01*
G01X1321667Y406930D02*
X1321750Y407472D01*
X1321875Y407930D01*
X1322042Y408347D01*
X1322250Y408805D01*
X1322583Y409430D01*
X1320917D01*
G01X1325767Y409222D02*
X1325517Y409347D01*
X1325225Y409430D01*
X1324892D01*
X1324517Y409305D01*
X1324225Y409097D01*
X1324017Y408847D01*
X1323850Y408430D01*
X1323808Y408055D01*
X1323892Y407680D01*
X1324017Y407430D01*
X1324267Y407180D01*
X1324558Y407013D01*
X1324850Y406930D01*
X1325142D01*
X1325433Y407013D01*
X1325683Y407138D01*
X1325892Y407305D01*
G01X1327950Y406930D02*
Y409430D01*
X1327450Y408930D01*
G01Y406930D02*
X1328450D01*
G01X1331050Y409430D02*
X1330717Y409347D01*
X1330467Y409138D01*
X1330300Y408888D01*
X1330175Y408555D01*
X1330133Y408180D01*
X1330175Y407805D01*
X1330300Y407472D01*
X1330467Y407222D01*
X1330717Y407013D01*
X1331050Y406930D01*
X1331383Y407013D01*
X1331633Y407222D01*
X1331800Y407472D01*
X1331925Y407805D01*
X1331967Y408180D01*
X1331925Y408555D01*
X1331800Y408888D01*
X1331633Y409138D01*
X1331383Y409347D01*
X1331050Y409430D01*
G01X1284117Y462459D02*
X1283867Y462584D01*
X1283575Y462667D01*
X1283242D01*
X1282867Y462542D01*
X1282575Y462334D01*
X1282367Y462084D01*
X1282200Y461667D01*
X1282158Y461292D01*
X1282242Y460917D01*
X1282367Y460667D01*
X1282617Y460417D01*
X1282908Y460250D01*
X1283200Y460167D01*
X1283492D01*
X1283783Y460250D01*
X1284033Y460375D01*
X1284242Y460542D01*
G01X1285508Y461209D02*
X1285800Y461500D01*
X1286050Y461667D01*
X1286383Y461750D01*
X1286675Y461667D01*
X1286883Y461500D01*
X1287050Y461250D01*
X1287092Y460959D01*
X1287050Y460709D01*
X1286883Y460459D01*
X1286633Y460250D01*
X1286342Y460167D01*
X1286008Y460250D01*
X1285717Y460500D01*
X1285550Y460875D01*
X1285508Y461292D01*
X1285592Y461834D01*
X1285717Y462125D01*
X1285925Y462417D01*
X1286217Y462625D01*
X1286508Y462667D01*
X1286800Y462584D01*
X1287008Y462375D01*
G01X1289733Y461500D02*
X1289900Y461625D01*
X1290025Y461834D01*
X1290108Y462125D01*
X1290025Y462375D01*
X1289858Y462542D01*
X1289567Y462667D01*
X1288442D01*
Y460167D01*
X1289817D01*
X1290108Y460334D01*
X1290275Y460584D01*
X1290358Y460875D01*
X1290275Y461167D01*
X1290025Y461417D01*
X1289733Y461500D01*
X1288442D01*
G01X1291708Y462250D02*
X1291958Y462500D01*
X1292250Y462625D01*
X1292583Y462667D01*
X1293000Y462584D01*
X1293292Y462375D01*
X1293375Y462125D01*
X1293333Y461875D01*
X1293167Y461667D01*
X1292333Y461250D01*
X1291958Y460959D01*
X1291708Y460542D01*
X1291625Y460167D01*
X1293375D01*
G01X1295600Y462667D02*
X1295267Y462584D01*
X1295017Y462375D01*
X1294850Y462125D01*
X1294725Y461792D01*
X1294683Y461417D01*
X1294725Y461042D01*
X1294850Y460709D01*
X1295017Y460459D01*
X1295267Y460250D01*
X1295600Y460167D01*
X1295933Y460250D01*
X1296183Y460459D01*
X1296350Y460709D01*
X1296475Y461042D01*
X1296517Y461417D01*
X1296475Y461792D01*
X1296350Y462125D01*
X1296183Y462375D01*
X1295933Y462584D01*
X1295600Y462667D01*
G01X1343567Y466559D02*
X1343317Y466684D01*
X1343025Y466767D01*
X1342692D01*
X1342317Y466642D01*
X1342025Y466434D01*
X1341817Y466184D01*
X1341650Y465767D01*
X1341608Y465392D01*
X1341692Y465017D01*
X1341817Y464767D01*
X1342067Y464517D01*
X1342358Y464350D01*
X1342650Y464267D01*
X1342942D01*
X1343233Y464350D01*
X1343483Y464475D01*
X1343692Y464642D01*
G01X1345750Y464267D02*
X1346042Y464309D01*
X1346375Y464434D01*
X1346583Y464642D01*
X1346667Y464934D01*
X1346583Y465225D01*
X1346333Y465475D01*
X1345958Y465600D01*
X1345542D01*
X1345292Y465684D01*
X1345083Y465892D01*
X1345000Y466184D01*
X1345125Y466475D01*
X1345417Y466684D01*
X1345750Y466767D01*
X1346083Y466684D01*
X1346375Y466475D01*
X1346500Y466184D01*
X1346417Y465892D01*
X1346208Y465684D01*
X1345958Y465600D01*
X1345542D01*
X1345167Y465475D01*
X1344917Y465225D01*
X1344833Y464934D01*
X1344917Y464642D01*
X1345125Y464434D01*
X1345458Y464309D01*
X1345750Y464267D01*
G01X1349350D02*
Y466767D01*
X1347808Y464975D01*
X1349892D01*
G01X1351033Y464642D02*
X1351283Y464434D01*
X1351575Y464309D01*
X1351950Y464267D01*
X1352325Y464350D01*
X1352617Y464517D01*
X1352825Y464809D01*
X1352867Y465142D01*
X1352783Y465475D01*
X1352575Y465684D01*
X1352283Y465850D01*
X1351992Y465892D01*
X1351700Y465850D01*
X1351325Y465684D01*
X1351450Y466767D01*
X1352575D01*
G01X1282618Y453425D02*
Y431425D01*
X1285618D01*
Y426275D01*
X1408618D01*
Y458575D01*
X1290910D01*
G01X1332300Y519400D02*
Y516100D01*
X1305500D01*
Y519400D01*
G01X1283208Y496767D02*
X1283083Y496517D01*
X1283000Y496225D01*
Y495892D01*
X1283125Y495517D01*
X1283333Y495225D01*
X1283583Y495017D01*
X1284000Y494850D01*
X1284375Y494808D01*
X1284750Y494892D01*
X1285000Y495017D01*
X1285250Y495267D01*
X1285417Y495558D01*
X1285500Y495850D01*
Y496142D01*
X1285417Y496433D01*
X1285292Y496683D01*
X1285125Y496892D01*
G01X1285500Y498867D02*
X1284958Y498950D01*
X1284500Y499075D01*
X1284083Y499242D01*
X1283625Y499450D01*
X1283000Y499783D01*
Y498117D01*
G01X1284167Y502383D02*
X1284042Y502550D01*
X1283833Y502675D01*
X1283542Y502758D01*
X1283292Y502675D01*
X1283125Y502508D01*
X1283000Y502217D01*
Y501092D01*
X1285500D01*
Y502467D01*
X1285333Y502758D01*
X1285083Y502925D01*
X1284792Y503008D01*
X1284500Y502925D01*
X1284250Y502675D01*
X1284167Y502383D01*
Y501092D01*
G01X1285500Y505067D02*
X1284958Y505150D01*
X1284500Y505275D01*
X1284083Y505442D01*
X1283625Y505650D01*
X1283000Y505983D01*
Y504317D01*
G01X1322417Y495667D02*
Y498167D01*
X1323458D01*
X1323792Y498042D01*
X1324000Y497875D01*
X1324083Y497542D01*
X1324000Y497209D01*
X1323750Y497000D01*
X1323458Y496875D01*
X1322417D01*
G01X1323458D02*
X1324083Y495667D01*
G01X1326267D02*
X1326350Y496209D01*
X1326475Y496667D01*
X1326642Y497084D01*
X1326850Y497542D01*
X1327183Y498167D01*
X1325517D01*
G01X1329783Y497000D02*
X1329950Y497125D01*
X1330075Y497334D01*
X1330158Y497625D01*
X1330075Y497875D01*
X1329908Y498042D01*
X1329617Y498167D01*
X1328492D01*
Y495667D01*
X1329867D01*
X1330158Y495834D01*
X1330325Y496084D01*
X1330408Y496375D01*
X1330325Y496667D01*
X1330075Y496917D01*
X1329783Y497000D01*
X1328492D01*
G01X1331842Y495959D02*
X1332133Y495750D01*
X1332467Y495667D01*
X1332800Y495750D01*
X1333092Y496000D01*
X1333300Y496375D01*
X1333383Y496750D01*
Y497209D01*
X1333300Y497584D01*
X1333092Y497917D01*
X1332842Y498084D01*
X1332550Y498167D01*
X1332217Y498084D01*
X1331967Y497917D01*
X1331800Y497667D01*
X1331717Y497334D01*
X1331800Y497042D01*
X1332008Y496750D01*
X1332258Y496584D01*
X1332550Y496542D01*
X1332883Y496625D01*
X1333133Y496834D01*
X1333383Y497209D01*
G01X1325400Y480017D02*
X1322900D01*
Y481058D01*
X1323025Y481392D01*
X1323192Y481600D01*
X1323525Y481683D01*
X1323858Y481600D01*
X1324067Y481350D01*
X1324192Y481058D01*
Y480017D01*
G01Y481058D02*
X1325400Y481683D01*
G01Y483867D02*
X1324858Y483950D01*
X1324400Y484075D01*
X1323983Y484242D01*
X1323525Y484450D01*
X1322900Y484783D01*
Y483117D01*
G01X1324067Y487383D02*
X1323942Y487550D01*
X1323733Y487675D01*
X1323442Y487758D01*
X1323192Y487675D01*
X1323025Y487508D01*
X1322900Y487217D01*
Y486092D01*
X1325400D01*
Y487467D01*
X1325233Y487758D01*
X1324983Y487925D01*
X1324692Y488008D01*
X1324400Y487925D01*
X1324150Y487675D01*
X1324067Y487383D01*
Y486092D01*
G01X1325400Y490150D02*
X1322900D01*
X1323400Y489650D01*
G01X1325400D02*
Y490650D01*
G01X1324900Y492333D02*
X1325192Y492583D01*
X1325358Y492917D01*
X1325400Y493292D01*
X1325358Y493625D01*
X1325150Y493958D01*
X1324900Y494167D01*
X1324650Y494208D01*
X1324358Y494125D01*
X1324150Y493833D01*
X1324067Y493542D01*
Y493167D01*
G01Y493542D02*
X1323942Y493792D01*
X1323733Y494000D01*
X1323483Y494083D01*
X1323233Y494000D01*
X1323025Y493792D01*
X1322900Y493417D01*
X1322942Y493042D01*
X1323108Y492667D01*
G01X1329100Y480017D02*
X1326600D01*
Y481058D01*
X1326725Y481392D01*
X1326892Y481600D01*
X1327225Y481683D01*
X1327558Y481600D01*
X1327767Y481350D01*
X1327892Y481058D01*
Y480017D01*
G01Y481058D02*
X1329100Y481683D01*
G01Y483867D02*
X1328558Y483950D01*
X1328100Y484075D01*
X1327683Y484242D01*
X1327225Y484450D01*
X1326600Y484783D01*
Y483117D01*
G01X1327767Y487383D02*
X1327642Y487550D01*
X1327433Y487675D01*
X1327142Y487758D01*
X1326892Y487675D01*
X1326725Y487508D01*
X1326600Y487217D01*
Y486092D01*
X1329100D01*
Y487467D01*
X1328933Y487758D01*
X1328683Y487925D01*
X1328392Y488008D01*
X1328100Y487925D01*
X1327850Y487675D01*
X1327767Y487383D01*
Y486092D01*
G01X1329100Y490150D02*
X1326600D01*
X1327100Y489650D01*
G01X1329100D02*
Y490650D01*
G01X1328058Y492458D02*
X1327767Y492750D01*
X1327600Y493000D01*
X1327517Y493333D01*
X1327600Y493625D01*
X1327767Y493833D01*
X1328017Y494000D01*
X1328308Y494042D01*
X1328558Y494000D01*
X1328808Y493833D01*
X1329017Y493583D01*
X1329100Y493292D01*
X1329017Y492958D01*
X1328767Y492667D01*
X1328392Y492500D01*
X1327975Y492458D01*
X1327433Y492542D01*
X1327142Y492667D01*
X1326850Y492875D01*
X1326642Y493167D01*
X1326600Y493458D01*
X1326683Y493750D01*
X1326892Y493958D01*
G01X1293600Y490717D02*
X1291100D01*
Y491758D01*
X1291225Y492092D01*
X1291392Y492300D01*
X1291725Y492383D01*
X1292058Y492300D01*
X1292267Y492050D01*
X1292392Y491758D01*
Y490717D01*
G01Y491758D02*
X1293600Y492383D01*
G01Y494567D02*
X1293058Y494650D01*
X1292600Y494775D01*
X1292183Y494942D01*
X1291725Y495150D01*
X1291100Y495483D01*
Y493817D01*
G01X1292267Y498083D02*
X1292142Y498250D01*
X1291933Y498375D01*
X1291642Y498458D01*
X1291392Y498375D01*
X1291225Y498208D01*
X1291100Y497917D01*
Y496792D01*
X1293600D01*
Y498167D01*
X1293433Y498458D01*
X1293183Y498625D01*
X1292892Y498708D01*
X1292600Y498625D01*
X1292350Y498375D01*
X1292267Y498083D01*
Y496792D01*
G01X1293600Y500850D02*
X1291100D01*
X1291600Y500350D01*
G01X1293600D02*
Y501350D01*
G01Y503950D02*
X1291100D01*
X1291600Y503450D01*
G01X1293600D02*
Y504450D01*
G01X1297100Y490917D02*
X1294600D01*
Y491958D01*
X1294725Y492292D01*
X1294892Y492500D01*
X1295225Y492583D01*
X1295558Y492500D01*
X1295767Y492250D01*
X1295892Y491958D01*
Y490917D01*
G01Y491958D02*
X1297100Y492583D01*
G01Y494767D02*
X1296558Y494850D01*
X1296100Y494975D01*
X1295683Y495142D01*
X1295225Y495350D01*
X1294600Y495683D01*
Y494017D01*
G01X1295767Y498283D02*
X1295642Y498450D01*
X1295433Y498575D01*
X1295142Y498658D01*
X1294892Y498575D01*
X1294725Y498408D01*
X1294600Y498117D01*
Y496992D01*
X1297100D01*
Y498367D01*
X1296933Y498658D01*
X1296683Y498825D01*
X1296392Y498908D01*
X1296100Y498825D01*
X1295850Y498575D01*
X1295767Y498283D01*
Y496992D01*
G01X1297100Y501050D02*
X1294600D01*
X1295100Y500550D01*
G01X1297100D02*
Y501550D01*
G01X1296725Y503233D02*
X1296933Y503483D01*
X1297058Y503775D01*
X1297100Y504150D01*
X1297017Y504525D01*
X1296850Y504817D01*
X1296558Y505025D01*
X1296225Y505067D01*
X1295892Y504983D01*
X1295683Y504775D01*
X1295517Y504483D01*
X1295475Y504192D01*
X1295517Y503900D01*
X1295683Y503525D01*
X1294600Y503650D01*
Y504775D01*
G01X1305057Y495060D02*
Y497560D01*
X1306098D01*
X1306432Y497435D01*
X1306640Y497268D01*
X1306723Y496935D01*
X1306640Y496602D01*
X1306390Y496393D01*
X1306098Y496268D01*
X1305057D01*
G01X1306098D02*
X1306723Y495060D01*
G01X1308907D02*
X1308990Y495602D01*
X1309115Y496060D01*
X1309282Y496477D01*
X1309490Y496935D01*
X1309823Y497560D01*
X1308157D01*
G01X1312423Y496393D02*
X1312590Y496518D01*
X1312715Y496727D01*
X1312798Y497018D01*
X1312715Y497268D01*
X1312548Y497435D01*
X1312257Y497560D01*
X1311132D01*
Y495060D01*
X1312507D01*
X1312798Y495227D01*
X1312965Y495477D01*
X1313048Y495768D01*
X1312965Y496060D01*
X1312715Y496310D01*
X1312423Y496393D01*
X1311132D01*
G01X1315190Y495060D02*
Y497560D01*
X1314690Y497060D01*
G01Y495060D02*
X1315690D01*
G01X1318290D02*
X1318582Y495102D01*
X1318915Y495227D01*
X1319123Y495435D01*
X1319207Y495727D01*
X1319123Y496018D01*
X1318873Y496268D01*
X1318498Y496393D01*
X1318082D01*
X1317832Y496477D01*
X1317623Y496685D01*
X1317540Y496977D01*
X1317665Y497268D01*
X1317957Y497477D01*
X1318290Y497560D01*
X1318623Y497477D01*
X1318915Y497268D01*
X1319040Y496977D01*
X1318957Y496685D01*
X1318748Y496477D01*
X1318498Y496393D01*
X1318082D01*
X1317707Y496268D01*
X1317457Y496018D01*
X1317373Y495727D01*
X1317457Y495435D01*
X1317665Y495227D01*
X1317998Y495102D01*
X1318290Y495060D01*
G01X1339834Y523467D02*
X1337334D01*
Y524508D01*
X1337459Y524842D01*
X1337626Y525050D01*
X1337959Y525133D01*
X1338292Y525050D01*
X1338501Y524800D01*
X1338626Y524508D01*
Y523467D01*
G01Y524508D02*
X1339834Y525133D01*
G01Y527317D02*
X1339292Y527400D01*
X1338834Y527525D01*
X1338417Y527692D01*
X1337959Y527900D01*
X1337334Y528233D01*
Y526567D01*
G01X1338501Y530833D02*
X1338376Y531000D01*
X1338167Y531125D01*
X1337876Y531208D01*
X1337626Y531125D01*
X1337459Y530958D01*
X1337334Y530667D01*
Y529542D01*
X1339834D01*
Y530917D01*
X1339667Y531208D01*
X1339417Y531375D01*
X1339126Y531458D01*
X1338834Y531375D01*
X1338584Y531125D01*
X1338501Y530833D01*
Y529542D01*
G01X1339834Y533600D02*
X1337334D01*
X1337834Y533100D01*
G01X1339834D02*
Y534100D01*
G01X1339542Y535992D02*
X1339751Y536283D01*
X1339834Y536617D01*
X1339751Y536950D01*
X1339501Y537242D01*
X1339126Y537450D01*
X1338751Y537533D01*
X1338292D01*
X1337917Y537450D01*
X1337584Y537242D01*
X1337417Y536992D01*
X1337334Y536700D01*
X1337417Y536367D01*
X1337584Y536117D01*
X1337834Y535950D01*
X1338167Y535867D01*
X1338459Y535950D01*
X1338751Y536158D01*
X1338917Y536408D01*
X1338959Y536700D01*
X1338876Y537033D01*
X1338667Y537283D01*
X1338292Y537533D01*
G01X1290100Y490717D02*
X1287600D01*
Y491758D01*
X1287725Y492092D01*
X1287892Y492300D01*
X1288225Y492383D01*
X1288558Y492300D01*
X1288767Y492050D01*
X1288892Y491758D01*
Y490717D01*
G01Y491758D02*
X1290100Y492383D01*
G01Y494567D02*
X1289558Y494650D01*
X1289100Y494775D01*
X1288683Y494942D01*
X1288225Y495150D01*
X1287600Y495483D01*
Y493817D01*
G01X1288767Y498083D02*
X1288642Y498250D01*
X1288433Y498375D01*
X1288142Y498458D01*
X1287892Y498375D01*
X1287725Y498208D01*
X1287600Y497917D01*
Y496792D01*
X1290100D01*
Y498167D01*
X1289933Y498458D01*
X1289683Y498625D01*
X1289392Y498708D01*
X1289100Y498625D01*
X1288850Y498375D01*
X1288767Y498083D01*
Y496792D01*
G01X1290100Y500850D02*
X1287600D01*
X1288100Y500350D01*
G01X1290100D02*
Y501350D01*
G01X1287600Y503950D02*
X1287683Y503617D01*
X1287892Y503367D01*
X1288142Y503200D01*
X1288475Y503075D01*
X1288850Y503033D01*
X1289225Y503075D01*
X1289558Y503200D01*
X1289808Y503367D01*
X1290017Y503617D01*
X1290100Y503950D01*
X1290017Y504283D01*
X1289808Y504533D01*
X1289558Y504700D01*
X1289225Y504825D01*
X1288850Y504867D01*
X1288475Y504825D01*
X1288142Y504700D01*
X1287892Y504533D01*
X1287683Y504283D01*
X1287600Y503950D01*
G01X1291217Y508442D02*
X1290967Y508567D01*
X1290675Y508650D01*
X1290342D01*
X1289967Y508525D01*
X1289675Y508317D01*
X1289467Y508067D01*
X1289300Y507650D01*
X1289258Y507275D01*
X1289342Y506900D01*
X1289467Y506650D01*
X1289717Y506400D01*
X1290008Y506233D01*
X1290300Y506150D01*
X1290592D01*
X1290883Y506233D01*
X1291133Y506358D01*
X1291342Y506525D01*
G01X1293317Y506150D02*
X1293400Y506692D01*
X1293525Y507150D01*
X1293692Y507567D01*
X1293900Y508025D01*
X1294233Y508650D01*
X1292567D01*
G01X1296833Y507483D02*
X1297000Y507608D01*
X1297125Y507817D01*
X1297208Y508108D01*
X1297125Y508358D01*
X1296958Y508525D01*
X1296667Y508650D01*
X1295542D01*
Y506150D01*
X1296917D01*
X1297208Y506317D01*
X1297375Y506567D01*
X1297458Y506858D01*
X1297375Y507150D01*
X1297125Y507400D01*
X1296833Y507483D01*
X1295542D01*
G01X1298683Y506650D02*
X1298933Y506358D01*
X1299267Y506192D01*
X1299642Y506150D01*
X1299975Y506192D01*
X1300308Y506400D01*
X1300517Y506650D01*
X1300558Y506900D01*
X1300475Y507192D01*
X1300183Y507400D01*
X1299892Y507483D01*
X1299517D01*
G01X1299892D02*
X1300142Y507608D01*
X1300350Y507817D01*
X1300433Y508067D01*
X1300350Y508317D01*
X1300142Y508525D01*
X1299767Y508650D01*
X1299392Y508608D01*
X1299017Y508442D01*
G01X1302700Y508650D02*
X1302367Y508567D01*
X1302117Y508358D01*
X1301950Y508108D01*
X1301825Y507775D01*
X1301783Y507400D01*
X1301825Y507025D01*
X1301950Y506692D01*
X1302117Y506442D01*
X1302367Y506233D01*
X1302700Y506150D01*
X1303033Y506233D01*
X1303283Y506442D01*
X1303450Y506692D01*
X1303575Y507025D01*
X1303617Y507400D01*
X1303575Y507775D01*
X1303450Y508108D01*
X1303283Y508358D01*
X1303033Y508567D01*
X1302700Y508650D01*
G01X1319608Y481767D02*
X1319483Y481517D01*
X1319400Y481225D01*
Y480892D01*
X1319525Y480517D01*
X1319733Y480225D01*
X1319983Y480017D01*
X1320400Y479850D01*
X1320775Y479808D01*
X1321150Y479892D01*
X1321400Y480017D01*
X1321650Y480267D01*
X1321817Y480558D01*
X1321900Y480850D01*
Y481142D01*
X1321817Y481433D01*
X1321692Y481683D01*
X1321525Y481892D01*
G01X1321900Y483867D02*
X1321358Y483950D01*
X1320900Y484075D01*
X1320483Y484242D01*
X1320025Y484450D01*
X1319400Y484783D01*
Y483117D01*
G01X1320567Y487383D02*
X1320442Y487550D01*
X1320233Y487675D01*
X1319942Y487758D01*
X1319692Y487675D01*
X1319525Y487508D01*
X1319400Y487217D01*
Y486092D01*
X1321900D01*
Y487467D01*
X1321733Y487758D01*
X1321483Y487925D01*
X1321192Y488008D01*
X1320900Y487925D01*
X1320650Y487675D01*
X1320567Y487383D01*
Y486092D01*
G01X1321900Y490150D02*
X1319400D01*
X1319900Y489650D01*
G01X1321900D02*
Y490650D01*
G01Y493250D02*
X1319400D01*
X1319900Y492750D01*
G01X1321900D02*
Y493750D01*
G01X1316042Y481667D02*
X1315917Y481417D01*
X1315834Y481125D01*
Y480792D01*
X1315959Y480417D01*
X1316167Y480125D01*
X1316417Y479917D01*
X1316834Y479750D01*
X1317209Y479708D01*
X1317584Y479792D01*
X1317834Y479917D01*
X1318084Y480167D01*
X1318251Y480458D01*
X1318334Y480750D01*
Y481042D01*
X1318251Y481333D01*
X1318126Y481583D01*
X1317959Y481792D01*
G01X1318334Y483767D02*
X1317792Y483850D01*
X1317334Y483975D01*
X1316917Y484142D01*
X1316459Y484350D01*
X1315834Y484683D01*
Y483017D01*
G01X1317001Y487283D02*
X1316876Y487450D01*
X1316667Y487575D01*
X1316376Y487658D01*
X1316126Y487575D01*
X1315959Y487408D01*
X1315834Y487117D01*
Y485992D01*
X1318334D01*
Y487367D01*
X1318167Y487658D01*
X1317917Y487825D01*
X1317626Y487908D01*
X1317334Y487825D01*
X1317084Y487575D01*
X1317001Y487283D01*
Y485992D01*
G01X1318042Y489342D02*
X1318251Y489633D01*
X1318334Y489967D01*
X1318251Y490300D01*
X1318001Y490592D01*
X1317626Y490800D01*
X1317251Y490883D01*
X1316792D01*
X1316417Y490800D01*
X1316084Y490592D01*
X1315917Y490342D01*
X1315834Y490050D01*
X1315917Y489717D01*
X1316084Y489467D01*
X1316334Y489300D01*
X1316667Y489217D01*
X1316959Y489300D01*
X1317251Y489508D01*
X1317417Y489758D01*
X1317459Y490050D01*
X1317376Y490383D01*
X1317167Y490633D01*
X1316792Y490883D01*
G01X1336917Y492592D02*
X1336667Y492717D01*
X1336375Y492800D01*
X1336042D01*
X1335667Y492675D01*
X1335375Y492467D01*
X1335167Y492217D01*
X1335000Y491800D01*
X1334958Y491425D01*
X1335042Y491050D01*
X1335167Y490800D01*
X1335417Y490550D01*
X1335708Y490383D01*
X1336000Y490300D01*
X1336292D01*
X1336583Y490383D01*
X1336833Y490508D01*
X1337042Y490675D01*
G01X1339017Y490300D02*
X1339100Y490842D01*
X1339225Y491300D01*
X1339392Y491717D01*
X1339600Y492175D01*
X1339933Y492800D01*
X1338267D01*
G01X1342533Y491633D02*
X1342700Y491758D01*
X1342825Y491967D01*
X1342908Y492258D01*
X1342825Y492508D01*
X1342658Y492675D01*
X1342367Y492800D01*
X1341242D01*
Y490300D01*
X1342617D01*
X1342908Y490467D01*
X1343075Y490717D01*
X1343158Y491008D01*
X1343075Y491300D01*
X1342825Y491550D01*
X1342533Y491633D01*
X1341242D01*
G01X1345300Y490300D02*
Y492800D01*
X1344800Y492300D01*
G01Y490300D02*
X1345800D01*
G01X1348900D02*
Y492800D01*
X1347358Y491008D01*
X1349442D01*
G01X1292717Y469758D02*
X1292467Y469883D01*
X1292175Y469966D01*
X1291842D01*
X1291467Y469841D01*
X1291175Y469633D01*
X1290967Y469383D01*
X1290800Y468966D01*
X1290758Y468591D01*
X1290842Y468216D01*
X1290967Y467966D01*
X1291217Y467716D01*
X1291508Y467549D01*
X1291800Y467466D01*
X1292092D01*
X1292383Y467549D01*
X1292633Y467674D01*
X1292842Y467841D01*
G01X1294108Y468508D02*
X1294400Y468799D01*
X1294650Y468966D01*
X1294983Y469049D01*
X1295275Y468966D01*
X1295483Y468799D01*
X1295650Y468549D01*
X1295692Y468258D01*
X1295650Y468008D01*
X1295483Y467758D01*
X1295233Y467549D01*
X1294942Y467466D01*
X1294608Y467549D01*
X1294317Y467799D01*
X1294150Y468174D01*
X1294108Y468591D01*
X1294192Y469133D01*
X1294317Y469424D01*
X1294525Y469716D01*
X1294817Y469924D01*
X1295108Y469966D01*
X1295400Y469883D01*
X1295608Y469674D01*
G01X1298333Y468799D02*
X1298500Y468924D01*
X1298625Y469133D01*
X1298708Y469424D01*
X1298625Y469674D01*
X1298458Y469841D01*
X1298167Y469966D01*
X1297042D01*
Y467466D01*
X1298417D01*
X1298708Y467633D01*
X1298875Y467883D01*
X1298958Y468174D01*
X1298875Y468466D01*
X1298625Y468716D01*
X1298333Y468799D01*
X1297042D01*
G01X1301100Y467466D02*
Y469966D01*
X1300600Y469466D01*
G01Y467466D02*
X1301600D01*
G01X1303492Y467758D02*
X1303783Y467549D01*
X1304117Y467466D01*
X1304450Y467549D01*
X1304742Y467799D01*
X1304950Y468174D01*
X1305033Y468549D01*
Y469008D01*
X1304950Y469383D01*
X1304742Y469716D01*
X1304492Y469883D01*
X1304200Y469966D01*
X1303867Y469883D01*
X1303617Y469716D01*
X1303450Y469466D01*
X1303367Y469133D01*
X1303450Y468841D01*
X1303658Y468549D01*
X1303908Y468383D01*
X1304200Y468341D01*
X1304533Y468424D01*
X1304783Y468633D01*
X1305033Y469008D01*
G01X1343067Y473259D02*
X1342817Y473384D01*
X1342525Y473467D01*
X1342192D01*
X1341817Y473342D01*
X1341525Y473134D01*
X1341317Y472884D01*
X1341150Y472467D01*
X1341108Y472092D01*
X1341192Y471717D01*
X1341317Y471467D01*
X1341567Y471217D01*
X1341858Y471050D01*
X1342150Y470967D01*
X1342442D01*
X1342733Y471050D01*
X1342983Y471175D01*
X1343192Y471342D01*
G01X1345250Y470967D02*
X1345542Y471009D01*
X1345875Y471134D01*
X1346083Y471342D01*
X1346167Y471634D01*
X1346083Y471925D01*
X1345833Y472175D01*
X1345458Y472300D01*
X1345042D01*
X1344792Y472384D01*
X1344583Y472592D01*
X1344500Y472884D01*
X1344625Y473175D01*
X1344917Y473384D01*
X1345250Y473467D01*
X1345583Y473384D01*
X1345875Y473175D01*
X1346000Y472884D01*
X1345917Y472592D01*
X1345708Y472384D01*
X1345458Y472300D01*
X1345042D01*
X1344667Y472175D01*
X1344417Y471925D01*
X1344333Y471634D01*
X1344417Y471342D01*
X1344625Y471134D01*
X1344958Y471009D01*
X1345250Y470967D01*
G01X1348850D02*
Y473467D01*
X1347308Y471675D01*
X1349392D01*
G01X1351950Y470967D02*
Y473467D01*
X1350408Y471675D01*
X1352492D01*
G01X1299067Y484142D02*
X1298817Y484267D01*
X1298525Y484350D01*
X1298192D01*
X1297817Y484225D01*
X1297525Y484017D01*
X1297317Y483767D01*
X1297150Y483350D01*
X1297108Y482975D01*
X1297192Y482600D01*
X1297317Y482350D01*
X1297567Y482100D01*
X1297858Y481933D01*
X1298150Y481850D01*
X1298442D01*
X1298733Y481933D01*
X1298983Y482058D01*
X1299192Y482225D01*
G01X1300458Y482892D02*
X1300750Y483183D01*
X1301000Y483350D01*
X1301333Y483433D01*
X1301625Y483350D01*
X1301833Y483183D01*
X1302000Y482933D01*
X1302042Y482642D01*
X1302000Y482392D01*
X1301833Y482142D01*
X1301583Y481933D01*
X1301292Y481850D01*
X1300958Y481933D01*
X1300667Y482183D01*
X1300500Y482558D01*
X1300458Y482975D01*
X1300542Y483517D01*
X1300667Y483808D01*
X1300875Y484100D01*
X1301167Y484308D01*
X1301458Y484350D01*
X1301750Y484267D01*
X1301958Y484058D01*
G01X1304683Y483183D02*
X1304850Y483308D01*
X1304975Y483517D01*
X1305058Y483808D01*
X1304975Y484058D01*
X1304808Y484225D01*
X1304517Y484350D01*
X1303392D01*
Y481850D01*
X1304767D01*
X1305058Y482017D01*
X1305225Y482267D01*
X1305308Y482558D01*
X1305225Y482850D01*
X1304975Y483100D01*
X1304683Y483183D01*
X1303392D01*
G01X1307450Y481850D02*
X1307742Y481892D01*
X1308075Y482017D01*
X1308283Y482225D01*
X1308367Y482517D01*
X1308283Y482808D01*
X1308033Y483058D01*
X1307658Y483183D01*
X1307242D01*
X1306992Y483267D01*
X1306783Y483475D01*
X1306700Y483767D01*
X1306825Y484058D01*
X1307117Y484267D01*
X1307450Y484350D01*
X1307783Y484267D01*
X1308075Y484058D01*
X1308200Y483767D01*
X1308117Y483475D01*
X1307908Y483267D01*
X1307658Y483183D01*
X1307242D01*
X1306867Y483058D01*
X1306617Y482808D01*
X1306533Y482517D01*
X1306617Y482225D01*
X1306825Y482017D01*
X1307158Y481892D01*
X1307450Y481850D01*
G01X1298367Y479442D02*
X1298117Y479567D01*
X1297825Y479650D01*
X1297492D01*
X1297117Y479525D01*
X1296825Y479317D01*
X1296617Y479067D01*
X1296450Y478650D01*
X1296408Y478275D01*
X1296492Y477900D01*
X1296617Y477650D01*
X1296867Y477400D01*
X1297158Y477233D01*
X1297450Y477150D01*
X1297742D01*
X1298033Y477233D01*
X1298283Y477358D01*
X1298492Y477525D01*
G01X1299758Y478192D02*
X1300050Y478483D01*
X1300300Y478650D01*
X1300633Y478733D01*
X1300925Y478650D01*
X1301133Y478483D01*
X1301300Y478233D01*
X1301342Y477942D01*
X1301300Y477692D01*
X1301133Y477442D01*
X1300883Y477233D01*
X1300592Y477150D01*
X1300258Y477233D01*
X1299967Y477483D01*
X1299800Y477858D01*
X1299758Y478275D01*
X1299842Y478817D01*
X1299967Y479108D01*
X1300175Y479400D01*
X1300467Y479608D01*
X1300758Y479650D01*
X1301050Y479567D01*
X1301258Y479358D01*
G01X1303983Y478483D02*
X1304150Y478608D01*
X1304275Y478817D01*
X1304358Y479108D01*
X1304275Y479358D01*
X1304108Y479525D01*
X1303817Y479650D01*
X1302692D01*
Y477150D01*
X1304067D01*
X1304358Y477317D01*
X1304525Y477567D01*
X1304608Y477858D01*
X1304525Y478150D01*
X1304275Y478400D01*
X1303983Y478483D01*
X1302692D01*
G01X1306042Y477442D02*
X1306333Y477233D01*
X1306667Y477150D01*
X1307000Y477233D01*
X1307292Y477483D01*
X1307500Y477858D01*
X1307583Y478233D01*
Y478692D01*
X1307500Y479067D01*
X1307292Y479400D01*
X1307042Y479567D01*
X1306750Y479650D01*
X1306417Y479567D01*
X1306167Y479400D01*
X1306000Y479150D01*
X1305917Y478817D01*
X1306000Y478525D01*
X1306208Y478233D01*
X1306458Y478067D01*
X1306750Y478025D01*
X1307083Y478108D01*
X1307333Y478317D01*
X1307583Y478692D01*
G01X1298167Y475389D02*
X1297917Y475514D01*
X1297625Y475597D01*
X1297292D01*
X1296917Y475472D01*
X1296625Y475264D01*
X1296417Y475014D01*
X1296250Y474597D01*
X1296208Y474222D01*
X1296292Y473847D01*
X1296417Y473597D01*
X1296667Y473347D01*
X1296958Y473180D01*
X1297250Y473097D01*
X1297542D01*
X1297833Y473180D01*
X1298083Y473305D01*
X1298292Y473472D01*
G01X1299558Y474139D02*
X1299850Y474430D01*
X1300100Y474597D01*
X1300433Y474680D01*
X1300725Y474597D01*
X1300933Y474430D01*
X1301100Y474180D01*
X1301142Y473889D01*
X1301100Y473639D01*
X1300933Y473389D01*
X1300683Y473180D01*
X1300392Y473097D01*
X1300058Y473180D01*
X1299767Y473430D01*
X1299600Y473805D01*
X1299558Y474222D01*
X1299642Y474764D01*
X1299767Y475055D01*
X1299975Y475347D01*
X1300267Y475555D01*
X1300558Y475597D01*
X1300850Y475514D01*
X1301058Y475305D01*
G01X1303783Y474430D02*
X1303950Y474555D01*
X1304075Y474764D01*
X1304158Y475055D01*
X1304075Y475305D01*
X1303908Y475472D01*
X1303617Y475597D01*
X1302492D01*
Y473097D01*
X1303867D01*
X1304158Y473264D01*
X1304325Y473514D01*
X1304408Y473805D01*
X1304325Y474097D01*
X1304075Y474347D01*
X1303783Y474430D01*
X1302492D01*
G01X1306550Y473097D02*
Y475597D01*
X1306050Y475097D01*
G01Y473097D02*
X1307050D01*
G01X1309650Y475597D02*
X1309317Y475514D01*
X1309067Y475305D01*
X1308900Y475055D01*
X1308775Y474722D01*
X1308733Y474347D01*
X1308775Y473972D01*
X1308900Y473639D01*
X1309067Y473389D01*
X1309317Y473180D01*
X1309650Y473097D01*
X1309983Y473180D01*
X1310233Y473389D01*
X1310400Y473639D01*
X1310525Y473972D01*
X1310567Y474347D01*
X1310525Y474722D01*
X1310400Y475055D01*
X1310233Y475305D01*
X1309983Y475514D01*
X1309650Y475597D01*
G01X1299167Y488042D02*
X1298917Y488167D01*
X1298625Y488250D01*
X1298292D01*
X1297917Y488125D01*
X1297625Y487917D01*
X1297417Y487667D01*
X1297250Y487250D01*
X1297208Y486875D01*
X1297292Y486500D01*
X1297417Y486250D01*
X1297667Y486000D01*
X1297958Y485833D01*
X1298250Y485750D01*
X1298542D01*
X1298833Y485833D01*
X1299083Y485958D01*
X1299292Y486125D01*
G01X1300558Y486792D02*
X1300850Y487083D01*
X1301100Y487250D01*
X1301433Y487333D01*
X1301725Y487250D01*
X1301933Y487083D01*
X1302100Y486833D01*
X1302142Y486542D01*
X1302100Y486292D01*
X1301933Y486042D01*
X1301683Y485833D01*
X1301392Y485750D01*
X1301058Y485833D01*
X1300767Y486083D01*
X1300600Y486458D01*
X1300558Y486875D01*
X1300642Y487417D01*
X1300767Y487708D01*
X1300975Y488000D01*
X1301267Y488208D01*
X1301558Y488250D01*
X1301850Y488167D01*
X1302058Y487958D01*
G01X1304783Y487083D02*
X1304950Y487208D01*
X1305075Y487417D01*
X1305158Y487708D01*
X1305075Y487958D01*
X1304908Y488125D01*
X1304617Y488250D01*
X1303492D01*
Y485750D01*
X1304867D01*
X1305158Y485917D01*
X1305325Y486167D01*
X1305408Y486458D01*
X1305325Y486750D01*
X1305075Y487000D01*
X1304783Y487083D01*
X1303492D01*
G01X1306758Y486792D02*
X1307050Y487083D01*
X1307300Y487250D01*
X1307633Y487333D01*
X1307925Y487250D01*
X1308133Y487083D01*
X1308300Y486833D01*
X1308342Y486542D01*
X1308300Y486292D01*
X1308133Y486042D01*
X1307883Y485833D01*
X1307592Y485750D01*
X1307258Y485833D01*
X1306967Y486083D01*
X1306800Y486458D01*
X1306758Y486875D01*
X1306842Y487417D01*
X1306967Y487708D01*
X1307175Y488000D01*
X1307467Y488208D01*
X1307758Y488250D01*
X1308050Y488167D01*
X1308258Y487958D01*
G01X1334367Y488658D02*
X1334117Y488783D01*
X1333825Y488866D01*
X1333492D01*
X1333117Y488741D01*
X1332825Y488533D01*
X1332617Y488283D01*
X1332450Y487866D01*
X1332408Y487491D01*
X1332492Y487116D01*
X1332617Y486866D01*
X1332867Y486616D01*
X1333158Y486449D01*
X1333450Y486366D01*
X1333742D01*
X1334033Y486449D01*
X1334283Y486574D01*
X1334492Y486741D01*
G01X1336550Y486366D02*
X1336842Y486408D01*
X1337175Y486533D01*
X1337383Y486741D01*
X1337467Y487033D01*
X1337383Y487324D01*
X1337133Y487574D01*
X1336758Y487699D01*
X1336342D01*
X1336092Y487783D01*
X1335883Y487991D01*
X1335800Y488283D01*
X1335925Y488574D01*
X1336217Y488783D01*
X1336550Y488866D01*
X1336883Y488783D01*
X1337175Y488574D01*
X1337300Y488283D01*
X1337217Y487991D01*
X1337008Y487783D01*
X1336758Y487699D01*
X1336342D01*
X1335967Y487574D01*
X1335717Y487324D01*
X1335633Y487033D01*
X1335717Y486741D01*
X1335925Y486533D01*
X1336258Y486408D01*
X1336550Y486366D01*
G01X1338733Y486866D02*
X1338983Y486574D01*
X1339317Y486408D01*
X1339692Y486366D01*
X1340025Y486408D01*
X1340358Y486616D01*
X1340567Y486866D01*
X1340608Y487116D01*
X1340525Y487408D01*
X1340233Y487616D01*
X1339942Y487699D01*
X1339567D01*
G01X1339942D02*
X1340192Y487824D01*
X1340400Y488033D01*
X1340483Y488283D01*
X1340400Y488533D01*
X1340192Y488741D01*
X1339817Y488866D01*
X1339442Y488824D01*
X1339067Y488658D01*
G01X1343250Y486366D02*
Y488866D01*
X1341708Y487074D01*
X1343792D01*
G01X1335067Y480958D02*
X1334817Y481083D01*
X1334525Y481166D01*
X1334192D01*
X1333817Y481041D01*
X1333525Y480833D01*
X1333317Y480583D01*
X1333150Y480166D01*
X1333108Y479791D01*
X1333192Y479416D01*
X1333317Y479166D01*
X1333567Y478916D01*
X1333858Y478749D01*
X1334150Y478666D01*
X1334442D01*
X1334733Y478749D01*
X1334983Y478874D01*
X1335192Y479041D01*
G01X1337250Y478666D02*
X1337542Y478708D01*
X1337875Y478833D01*
X1338083Y479041D01*
X1338167Y479333D01*
X1338083Y479624D01*
X1337833Y479874D01*
X1337458Y479999D01*
X1337042D01*
X1336792Y480083D01*
X1336583Y480291D01*
X1336500Y480583D01*
X1336625Y480874D01*
X1336917Y481083D01*
X1337250Y481166D01*
X1337583Y481083D01*
X1337875Y480874D01*
X1338000Y480583D01*
X1337917Y480291D01*
X1337708Y480083D01*
X1337458Y479999D01*
X1337042D01*
X1336667Y479874D01*
X1336417Y479624D01*
X1336333Y479333D01*
X1336417Y479041D01*
X1336625Y478833D01*
X1336958Y478708D01*
X1337250Y478666D01*
G01X1339433Y479166D02*
X1339683Y478874D01*
X1340017Y478708D01*
X1340392Y478666D01*
X1340725Y478708D01*
X1341058Y478916D01*
X1341267Y479166D01*
X1341308Y479416D01*
X1341225Y479708D01*
X1340933Y479916D01*
X1340642Y479999D01*
X1340267D01*
G01X1340642D02*
X1340892Y480124D01*
X1341100Y480333D01*
X1341183Y480583D01*
X1341100Y480833D01*
X1340892Y481041D01*
X1340517Y481166D01*
X1340142Y481124D01*
X1339767Y480958D01*
G01X1342533Y479041D02*
X1342783Y478833D01*
X1343075Y478708D01*
X1343450Y478666D01*
X1343825Y478749D01*
X1344117Y478916D01*
X1344325Y479208D01*
X1344367Y479541D01*
X1344283Y479874D01*
X1344075Y480083D01*
X1343783Y480249D01*
X1343492Y480291D01*
X1343200Y480249D01*
X1342825Y480083D01*
X1342950Y481166D01*
X1344075D01*
G01X1285767Y475759D02*
X1285517Y475884D01*
X1285225Y475967D01*
X1284892D01*
X1284517Y475842D01*
X1284225Y475634D01*
X1284017Y475384D01*
X1283850Y474967D01*
X1283808Y474592D01*
X1283892Y474217D01*
X1284017Y473967D01*
X1284267Y473717D01*
X1284558Y473550D01*
X1284850Y473467D01*
X1285142D01*
X1285433Y473550D01*
X1285683Y473675D01*
X1285892Y473842D01*
G01X1287950Y473467D02*
X1288242Y473509D01*
X1288575Y473634D01*
X1288783Y473842D01*
X1288867Y474134D01*
X1288783Y474425D01*
X1288533Y474675D01*
X1288158Y474800D01*
X1287742D01*
X1287492Y474884D01*
X1287283Y475092D01*
X1287200Y475384D01*
X1287325Y475675D01*
X1287617Y475884D01*
X1287950Y475967D01*
X1288283Y475884D01*
X1288575Y475675D01*
X1288700Y475384D01*
X1288617Y475092D01*
X1288408Y474884D01*
X1288158Y474800D01*
X1287742D01*
X1287367Y474675D01*
X1287117Y474425D01*
X1287033Y474134D01*
X1287117Y473842D01*
X1287325Y473634D01*
X1287658Y473509D01*
X1287950Y473467D01*
G01X1290258Y475550D02*
X1290508Y475800D01*
X1290800Y475925D01*
X1291133Y475967D01*
X1291550Y475884D01*
X1291842Y475675D01*
X1291925Y475425D01*
X1291883Y475175D01*
X1291717Y474967D01*
X1290883Y474550D01*
X1290508Y474259D01*
X1290258Y473842D01*
X1290175Y473467D01*
X1291925D01*
G01X1293442Y473759D02*
X1293733Y473550D01*
X1294067Y473467D01*
X1294400Y473550D01*
X1294692Y473800D01*
X1294900Y474175D01*
X1294983Y474550D01*
Y475009D01*
X1294900Y475384D01*
X1294692Y475717D01*
X1294442Y475884D01*
X1294150Y475967D01*
X1293817Y475884D01*
X1293567Y475717D01*
X1293400Y475467D01*
X1293317Y475134D01*
X1293400Y474842D01*
X1293608Y474550D01*
X1293858Y474384D01*
X1294150Y474342D01*
X1294483Y474425D01*
X1294733Y474634D01*
X1294983Y475009D01*
G01X1286167Y479659D02*
X1285917Y479784D01*
X1285625Y479867D01*
X1285292D01*
X1284917Y479742D01*
X1284625Y479534D01*
X1284417Y479284D01*
X1284250Y478867D01*
X1284208Y478492D01*
X1284292Y478117D01*
X1284417Y477867D01*
X1284667Y477617D01*
X1284958Y477450D01*
X1285250Y477367D01*
X1285542D01*
X1285833Y477450D01*
X1286083Y477575D01*
X1286292Y477742D01*
G01X1288350Y477367D02*
X1288642Y477409D01*
X1288975Y477534D01*
X1289183Y477742D01*
X1289267Y478034D01*
X1289183Y478325D01*
X1288933Y478575D01*
X1288558Y478700D01*
X1288142D01*
X1287892Y478784D01*
X1287683Y478992D01*
X1287600Y479284D01*
X1287725Y479575D01*
X1288017Y479784D01*
X1288350Y479867D01*
X1288683Y479784D01*
X1288975Y479575D01*
X1289100Y479284D01*
X1289017Y478992D01*
X1288808Y478784D01*
X1288558Y478700D01*
X1288142D01*
X1287767Y478575D01*
X1287517Y478325D01*
X1287433Y478034D01*
X1287517Y477742D01*
X1287725Y477534D01*
X1288058Y477409D01*
X1288350Y477367D01*
G01X1290658Y479450D02*
X1290908Y479700D01*
X1291200Y479825D01*
X1291533Y479867D01*
X1291950Y479784D01*
X1292242Y479575D01*
X1292325Y479325D01*
X1292283Y479075D01*
X1292117Y478867D01*
X1291283Y478450D01*
X1290908Y478159D01*
X1290658Y477742D01*
X1290575Y477367D01*
X1292325D01*
G01X1294550D02*
X1294842Y477409D01*
X1295175Y477534D01*
X1295383Y477742D01*
X1295467Y478034D01*
X1295383Y478325D01*
X1295133Y478575D01*
X1294758Y478700D01*
X1294342D01*
X1294092Y478784D01*
X1293883Y478992D01*
X1293800Y479284D01*
X1293925Y479575D01*
X1294217Y479784D01*
X1294550Y479867D01*
X1294883Y479784D01*
X1295175Y479575D01*
X1295300Y479284D01*
X1295217Y478992D01*
X1295008Y478784D01*
X1294758Y478700D01*
X1294342D01*
X1293967Y478575D01*
X1293717Y478325D01*
X1293633Y478034D01*
X1293717Y477742D01*
X1293925Y477534D01*
X1294258Y477409D01*
X1294550Y477367D01*
G01X1286567Y484492D02*
X1286317Y484617D01*
X1286025Y484700D01*
X1285692D01*
X1285317Y484575D01*
X1285025Y484367D01*
X1284817Y484117D01*
X1284650Y483700D01*
X1284608Y483325D01*
X1284692Y482950D01*
X1284817Y482700D01*
X1285067Y482450D01*
X1285358Y482283D01*
X1285650Y482200D01*
X1285942D01*
X1286233Y482283D01*
X1286483Y482408D01*
X1286692Y482575D01*
G01X1288750Y482200D02*
X1289042Y482242D01*
X1289375Y482367D01*
X1289583Y482575D01*
X1289667Y482867D01*
X1289583Y483158D01*
X1289333Y483408D01*
X1288958Y483533D01*
X1288542D01*
X1288292Y483617D01*
X1288083Y483825D01*
X1288000Y484117D01*
X1288125Y484408D01*
X1288417Y484617D01*
X1288750Y484700D01*
X1289083Y484617D01*
X1289375Y484408D01*
X1289500Y484117D01*
X1289417Y483825D01*
X1289208Y483617D01*
X1288958Y483533D01*
X1288542D01*
X1288167Y483408D01*
X1287917Y483158D01*
X1287833Y482867D01*
X1287917Y482575D01*
X1288125Y482367D01*
X1288458Y482242D01*
X1288750Y482200D01*
G01X1291058Y484283D02*
X1291308Y484533D01*
X1291600Y484658D01*
X1291933Y484700D01*
X1292350Y484617D01*
X1292642Y484408D01*
X1292725Y484158D01*
X1292683Y483908D01*
X1292517Y483700D01*
X1291683Y483283D01*
X1291308Y482992D01*
X1291058Y482575D01*
X1290975Y482200D01*
X1292725D01*
G01X1294867D02*
X1294950Y482742D01*
X1295075Y483200D01*
X1295242Y483617D01*
X1295450Y484075D01*
X1295783Y484700D01*
X1294117D01*
G01X1340017Y484959D02*
X1339767Y485084D01*
X1339475Y485167D01*
X1339142D01*
X1338767Y485042D01*
X1338475Y484834D01*
X1338267Y484584D01*
X1338100Y484167D01*
X1338058Y483792D01*
X1338142Y483417D01*
X1338267Y483167D01*
X1338517Y482917D01*
X1338808Y482750D01*
X1339100Y482667D01*
X1339392D01*
X1339683Y482750D01*
X1339933Y482875D01*
X1340142Y483042D01*
G01X1341408Y483709D02*
X1341700Y484000D01*
X1341950Y484167D01*
X1342283Y484250D01*
X1342575Y484167D01*
X1342783Y484000D01*
X1342950Y483750D01*
X1342992Y483459D01*
X1342950Y483209D01*
X1342783Y482959D01*
X1342533Y482750D01*
X1342242Y482667D01*
X1341908Y482750D01*
X1341617Y483000D01*
X1341450Y483375D01*
X1341408Y483792D01*
X1341492Y484334D01*
X1341617Y484625D01*
X1341825Y484917D01*
X1342117Y485125D01*
X1342408Y485167D01*
X1342700Y485084D01*
X1342908Y484875D01*
G01X1345633Y484000D02*
X1345800Y484125D01*
X1345925Y484334D01*
X1346008Y484625D01*
X1345925Y484875D01*
X1345758Y485042D01*
X1345467Y485167D01*
X1344342D01*
Y482667D01*
X1345717D01*
X1346008Y482834D01*
X1346175Y483084D01*
X1346258Y483375D01*
X1346175Y483667D01*
X1345925Y483917D01*
X1345633Y484000D01*
X1344342D01*
G01X1348400Y482667D02*
Y485167D01*
X1347900Y484667D01*
G01Y482667D02*
X1348900D01*
G01X1350583Y483042D02*
X1350833Y482834D01*
X1351125Y482709D01*
X1351500Y482667D01*
X1351875Y482750D01*
X1352167Y482917D01*
X1352375Y483209D01*
X1352417Y483542D01*
X1352333Y483875D01*
X1352125Y484084D01*
X1351833Y484250D01*
X1351542Y484292D01*
X1351250Y484250D01*
X1350875Y484084D01*
X1351000Y485167D01*
X1352125D01*
G01X1286567Y488592D02*
X1286317Y488717D01*
X1286025Y488800D01*
X1285692D01*
X1285317Y488675D01*
X1285025Y488467D01*
X1284817Y488217D01*
X1284650Y487800D01*
X1284608Y487425D01*
X1284692Y487050D01*
X1284817Y486800D01*
X1285067Y486550D01*
X1285358Y486383D01*
X1285650Y486300D01*
X1285942D01*
X1286233Y486383D01*
X1286483Y486508D01*
X1286692Y486675D01*
G01X1288750Y486300D02*
X1289042Y486342D01*
X1289375Y486467D01*
X1289583Y486675D01*
X1289667Y486967D01*
X1289583Y487258D01*
X1289333Y487508D01*
X1288958Y487633D01*
X1288542D01*
X1288292Y487717D01*
X1288083Y487925D01*
X1288000Y488217D01*
X1288125Y488508D01*
X1288417Y488717D01*
X1288750Y488800D01*
X1289083Y488717D01*
X1289375Y488508D01*
X1289500Y488217D01*
X1289417Y487925D01*
X1289208Y487717D01*
X1288958Y487633D01*
X1288542D01*
X1288167Y487508D01*
X1287917Y487258D01*
X1287833Y486967D01*
X1287917Y486675D01*
X1288125Y486467D01*
X1288458Y486342D01*
X1288750Y486300D01*
G01X1291058Y488383D02*
X1291308Y488633D01*
X1291600Y488758D01*
X1291933Y488800D01*
X1292350Y488717D01*
X1292642Y488508D01*
X1292725Y488258D01*
X1292683Y488008D01*
X1292517Y487800D01*
X1291683Y487383D01*
X1291308Y487092D01*
X1291058Y486675D01*
X1290975Y486300D01*
X1292725D01*
G01X1294158Y487342D02*
X1294450Y487633D01*
X1294700Y487800D01*
X1295033Y487883D01*
X1295325Y487800D01*
X1295533Y487633D01*
X1295700Y487383D01*
X1295742Y487092D01*
X1295700Y486842D01*
X1295533Y486592D01*
X1295283Y486383D01*
X1294992Y486300D01*
X1294658Y486383D01*
X1294367Y486633D01*
X1294200Y487008D01*
X1294158Y487425D01*
X1294242Y487967D01*
X1294367Y488258D01*
X1294575Y488550D01*
X1294867Y488758D01*
X1295158Y488800D01*
X1295450Y488717D01*
X1295658Y488508D01*
G01X1337417Y477358D02*
X1337167Y477483D01*
X1336875Y477566D01*
X1336542D01*
X1336167Y477441D01*
X1335875Y477233D01*
X1335667Y476983D01*
X1335500Y476566D01*
X1335458Y476191D01*
X1335542Y475816D01*
X1335667Y475566D01*
X1335917Y475316D01*
X1336208Y475149D01*
X1336500Y475066D01*
X1336792D01*
X1337083Y475149D01*
X1337333Y475274D01*
X1337542Y475441D01*
G01X1338808Y476108D02*
X1339100Y476399D01*
X1339350Y476566D01*
X1339683Y476649D01*
X1339975Y476566D01*
X1340183Y476399D01*
X1340350Y476149D01*
X1340392Y475858D01*
X1340350Y475608D01*
X1340183Y475358D01*
X1339933Y475149D01*
X1339642Y475066D01*
X1339308Y475149D01*
X1339017Y475399D01*
X1338850Y475774D01*
X1338808Y476191D01*
X1338892Y476733D01*
X1339017Y477024D01*
X1339225Y477316D01*
X1339517Y477524D01*
X1339808Y477566D01*
X1340100Y477483D01*
X1340308Y477274D01*
G01X1343033Y476399D02*
X1343200Y476524D01*
X1343325Y476733D01*
X1343408Y477024D01*
X1343325Y477274D01*
X1343158Y477441D01*
X1342867Y477566D01*
X1341742D01*
Y475066D01*
X1343117D01*
X1343408Y475233D01*
X1343575Y475483D01*
X1343658Y475774D01*
X1343575Y476066D01*
X1343325Y476316D01*
X1343033Y476399D01*
X1341742D01*
G01X1345800Y475066D02*
Y477566D01*
X1345300Y477066D01*
G01Y475066D02*
X1346300D01*
G01X1348108Y476108D02*
X1348400Y476399D01*
X1348650Y476566D01*
X1348983Y476649D01*
X1349275Y476566D01*
X1349483Y476399D01*
X1349650Y476149D01*
X1349692Y475858D01*
X1349650Y475608D01*
X1349483Y475358D01*
X1349233Y475149D01*
X1348942Y475066D01*
X1348608Y475149D01*
X1348317Y475399D01*
X1348150Y475774D01*
X1348108Y476191D01*
X1348192Y476733D01*
X1348317Y477024D01*
X1348525Y477316D01*
X1348817Y477524D01*
X1349108Y477566D01*
X1349400Y477483D01*
X1349608Y477274D01*
G01X1298708Y492467D02*
X1298583Y492217D01*
X1298500Y491925D01*
Y491592D01*
X1298625Y491217D01*
X1298833Y490925D01*
X1299083Y490717D01*
X1299500Y490550D01*
X1299875Y490508D01*
X1300250Y490592D01*
X1300500Y490717D01*
X1300750Y490967D01*
X1300917Y491258D01*
X1301000Y491550D01*
Y491842D01*
X1300917Y492133D01*
X1300792Y492383D01*
X1300625Y492592D01*
G01X1301000Y494567D02*
X1300458Y494650D01*
X1300000Y494775D01*
X1299583Y494942D01*
X1299125Y495150D01*
X1298500Y495483D01*
Y493817D01*
G01X1299667Y498083D02*
X1299542Y498250D01*
X1299333Y498375D01*
X1299042Y498458D01*
X1298792Y498375D01*
X1298625Y498208D01*
X1298500Y497917D01*
Y496792D01*
X1301000D01*
Y498167D01*
X1300833Y498458D01*
X1300583Y498625D01*
X1300292Y498708D01*
X1300000Y498625D01*
X1299750Y498375D01*
X1299667Y498083D01*
Y496792D01*
G01X1301000Y500850D02*
X1298500D01*
X1299000Y500350D01*
G01X1301000D02*
Y501350D01*
G01X1300500Y503033D02*
X1300792Y503283D01*
X1300958Y503617D01*
X1301000Y503992D01*
X1300958Y504325D01*
X1300750Y504658D01*
X1300500Y504867D01*
X1300250Y504908D01*
X1299958Y504825D01*
X1299750Y504533D01*
X1299667Y504242D01*
Y503867D01*
G01Y504242D02*
X1299542Y504492D01*
X1299333Y504700D01*
X1299083Y504783D01*
X1298833Y504700D01*
X1298625Y504492D01*
X1298500Y504117D01*
X1298542Y503742D01*
X1298708Y503367D01*
G01X1340850Y509400D02*
Y536700D01*
X1368150D01*
Y509400D01*
X1340850D01*
G01X1297721Y538478D02*
X1300221D01*
Y540144D01*
G01Y542328D02*
X1299679Y542411D01*
X1299221Y542536D01*
X1298804Y542703D01*
X1298346Y542911D01*
X1297721Y543244D01*
Y541578D01*
G01X1298888Y545844D02*
X1298763Y546011D01*
X1298554Y546136D01*
X1298263Y546219D01*
X1298013Y546136D01*
X1297846Y545969D01*
X1297721Y545678D01*
Y544553D01*
X1300221D01*
Y545928D01*
X1300054Y546219D01*
X1299804Y546386D01*
X1299513Y546469D01*
X1299221Y546386D01*
X1298971Y546136D01*
X1298888Y545844D01*
Y544553D01*
G01X1300221Y548611D02*
X1297721D01*
X1298221Y548111D01*
G01X1300221D02*
Y549111D01*
G01X1305500Y539600D02*
Y542900D01*
X1332300D01*
Y539600D01*
G01X1296942Y578967D02*
X1296817Y578717D01*
X1296734Y578425D01*
Y578092D01*
X1296859Y577717D01*
X1297067Y577425D01*
X1297317Y577217D01*
X1297734Y577050D01*
X1298109Y577008D01*
X1298484Y577092D01*
X1298734Y577217D01*
X1298984Y577467D01*
X1299151Y577758D01*
X1299234Y578050D01*
Y578342D01*
X1299151Y578633D01*
X1299026Y578883D01*
X1298859Y579092D01*
G01X1298192Y580358D02*
X1297901Y580650D01*
X1297734Y580900D01*
X1297651Y581233D01*
X1297734Y581525D01*
X1297901Y581733D01*
X1298151Y581900D01*
X1298442Y581942D01*
X1298692Y581900D01*
X1298942Y581733D01*
X1299151Y581483D01*
X1299234Y581192D01*
X1299151Y580858D01*
X1298901Y580567D01*
X1298526Y580400D01*
X1298109Y580358D01*
X1297567Y580442D01*
X1297276Y580567D01*
X1296984Y580775D01*
X1296776Y581067D01*
X1296734Y581358D01*
X1296817Y581650D01*
X1297026Y581858D01*
G01X1299234Y583208D02*
X1296734Y584250D01*
X1299234Y585292D01*
G01X1298359Y584917D02*
Y583583D01*
G01X1299234Y587850D02*
X1296734D01*
X1298526Y586308D01*
Y588392D01*
G01X1335217Y544459D02*
X1334967Y544584D01*
X1334675Y544667D01*
X1334342D01*
X1333967Y544542D01*
X1333675Y544334D01*
X1333467Y544084D01*
X1333300Y543667D01*
X1333258Y543292D01*
X1333342Y542917D01*
X1333467Y542667D01*
X1333717Y542417D01*
X1334008Y542250D01*
X1334300Y542167D01*
X1334592D01*
X1334883Y542250D01*
X1335133Y542375D01*
X1335342Y542542D01*
G01X1337317Y542167D02*
X1337400Y542709D01*
X1337525Y543167D01*
X1337692Y543584D01*
X1337900Y544042D01*
X1338233Y544667D01*
X1336567D01*
G01X1339458Y542167D02*
X1340500Y544667D01*
X1341542Y542167D01*
G01X1341167Y543042D02*
X1339833D01*
G01X1342683Y542667D02*
X1342933Y542375D01*
X1343267Y542209D01*
X1343642Y542167D01*
X1343975Y542209D01*
X1344308Y542417D01*
X1344517Y542667D01*
X1344558Y542917D01*
X1344475Y543209D01*
X1344183Y543417D01*
X1343892Y543500D01*
X1343517D01*
G01X1343892D02*
X1344142Y543625D01*
X1344350Y543834D01*
X1344433Y544084D01*
X1344350Y544334D01*
X1344142Y544542D01*
X1343767Y544667D01*
X1343392Y544625D01*
X1343017Y544459D01*
G01X1347200Y542167D02*
Y544667D01*
X1345658Y542875D01*
X1347742D01*
G01X1296340Y553125D02*
X1296215Y552875D01*
X1296132Y552583D01*
Y552250D01*
X1296257Y551875D01*
X1296465Y551583D01*
X1296715Y551375D01*
X1297132Y551208D01*
X1297507Y551166D01*
X1297882Y551250D01*
X1298132Y551375D01*
X1298382Y551625D01*
X1298549Y551916D01*
X1298632Y552208D01*
Y552500D01*
X1298549Y552791D01*
X1298424Y553041D01*
X1298257Y553250D01*
G01X1297590Y554516D02*
X1297299Y554808D01*
X1297132Y555058D01*
X1297049Y555391D01*
X1297132Y555683D01*
X1297299Y555891D01*
X1297549Y556058D01*
X1297840Y556100D01*
X1298090Y556058D01*
X1298340Y555891D01*
X1298549Y555641D01*
X1298632Y555350D01*
X1298549Y555016D01*
X1298299Y554725D01*
X1297924Y554558D01*
X1297507Y554516D01*
X1296965Y554600D01*
X1296674Y554725D01*
X1296382Y554933D01*
X1296174Y555225D01*
X1296132Y555516D01*
X1296215Y555808D01*
X1296424Y556016D01*
G01X1298632Y557366D02*
X1296132Y558408D01*
X1298632Y559450D01*
G01X1297757Y559075D02*
Y557741D01*
G01X1298257Y560591D02*
X1298465Y560841D01*
X1298590Y561133D01*
X1298632Y561508D01*
X1298549Y561883D01*
X1298382Y562175D01*
X1298090Y562383D01*
X1297757Y562425D01*
X1297424Y562341D01*
X1297215Y562133D01*
X1297049Y561841D01*
X1297007Y561550D01*
X1297049Y561258D01*
X1297215Y560883D01*
X1296132Y561008D01*
Y562133D01*
G01X1338100Y563900D02*
X1315525D01*
G01X1338100Y545900D02*
X1315528D01*
G01X1338100D02*
Y548595D01*
G01Y563900D02*
Y561202D01*
G01X1302736Y561200D02*
Y564762D01*
X1315532D01*
Y561200D01*
G01X1302736Y548600D02*
Y544809D01*
X1315532D01*
Y548600D01*
G01X1307434Y586817D02*
X1309934D01*
Y588483D01*
G01Y590667D02*
X1309392Y590750D01*
X1308934Y590875D01*
X1308517Y591042D01*
X1308059Y591250D01*
X1307434Y591583D01*
Y589917D01*
G01X1309934Y592808D02*
X1307434Y593850D01*
X1309934Y594892D01*
G01X1309059Y594517D02*
Y593183D01*
G01X1309434Y596033D02*
X1309726Y596283D01*
X1309892Y596617D01*
X1309934Y596992D01*
X1309892Y597325D01*
X1309684Y597658D01*
X1309434Y597867D01*
X1309184Y597908D01*
X1308892Y597825D01*
X1308684Y597533D01*
X1308601Y597242D01*
Y596867D01*
G01Y597242D02*
X1308476Y597492D01*
X1308267Y597700D01*
X1308017Y597783D01*
X1307767Y597700D01*
X1307559Y597492D01*
X1307434Y597117D01*
X1307476Y596742D01*
X1307642Y596367D01*
G01X1310950Y587106D02*
Y593154D01*
X1348350D01*
Y587106D01*
G01Y567958D02*
X1310950D01*
Y574006D01*
G01X1296642Y601867D02*
X1296517Y601617D01*
X1296434Y601325D01*
Y600992D01*
X1296559Y600617D01*
X1296767Y600325D01*
X1297017Y600117D01*
X1297434Y599950D01*
X1297809Y599908D01*
X1298184Y599992D01*
X1298434Y600117D01*
X1298684Y600367D01*
X1298851Y600658D01*
X1298934Y600950D01*
Y601242D01*
X1298851Y601533D01*
X1298726Y601783D01*
X1298559Y601992D01*
G01X1297892Y603258D02*
X1297601Y603550D01*
X1297434Y603800D01*
X1297351Y604133D01*
X1297434Y604425D01*
X1297601Y604633D01*
X1297851Y604800D01*
X1298142Y604842D01*
X1298392Y604800D01*
X1298642Y604633D01*
X1298851Y604383D01*
X1298934Y604092D01*
X1298851Y603758D01*
X1298601Y603467D01*
X1298226Y603300D01*
X1297809Y603258D01*
X1297267Y603342D01*
X1296976Y603467D01*
X1296684Y603675D01*
X1296476Y603967D01*
X1296434Y604258D01*
X1296517Y604550D01*
X1296726Y604758D01*
G01X1298934Y606108D02*
X1296434Y607150D01*
X1298934Y608192D01*
G01X1298059Y607817D02*
Y606483D01*
G01X1298934Y610250D02*
X1296434D01*
X1296934Y609750D01*
G01X1298934D02*
Y610750D01*
G01X1304834Y612117D02*
X1307334D01*
Y613783D01*
G01Y615967D02*
X1306792Y616050D01*
X1306334Y616175D01*
X1305917Y616342D01*
X1305459Y616550D01*
X1304834Y616883D01*
Y615217D01*
G01X1307334Y618108D02*
X1304834Y619150D01*
X1307334Y620192D01*
G01X1306459Y619817D02*
Y618483D01*
G01X1307334Y622250D02*
X1304834D01*
X1305334Y621750D01*
G01X1307334D02*
Y622750D01*
G01X1310850Y616006D02*
Y622054D01*
X1348250D01*
Y616006D01*
G01Y596858D02*
X1310850D01*
Y602906D01*
G01X1396258Y-38257D02*
X1378258D01*
Y-56257D01*
X1396258D01*
Y-38257D01*
G01X1416258D02*
X1398258D01*
Y-56257D01*
X1416258D01*
Y-38257D01*
G01X1386694Y-13367D02*
X1391760D01*
X1386694Y-20367D01*
X1391760D01*
G01X1349000Y-14000D02*
Y-22000D01*
X1393000D01*
Y-21000D01*
G01X1385948Y12267D02*
Y8244D01*
X1393012D01*
Y5372D01*
G01X1385948Y18976D02*
Y36724D01*
X1384023D01*
G01X1393012Y1688D02*
Y-22207D01*
G01X1348500Y0D02*
Y13500D01*
X1349700D01*
Y30100D01*
X1348000D01*
Y37800D01*
G01X1394937Y7359D02*
Y4859D01*
G01X1393979Y7359D02*
X1395895D01*
G01X1397162Y4859D02*
Y7359D01*
G01X1398912D02*
Y4859D01*
G01Y6109D02*
X1397162D01*
G01X1401054Y4859D02*
X1401137Y5401D01*
X1401262Y5859D01*
X1401429Y6276D01*
X1401637Y6734D01*
X1401970Y7359D01*
X1400304D01*
G01X1404487Y6109D02*
X1405320D01*
Y5359D01*
X1405070Y5109D01*
X1404779Y4942D01*
X1404362Y4859D01*
X1403945Y4942D01*
X1403654Y5109D01*
X1403404Y5359D01*
X1403237Y5651D01*
X1403154Y5984D01*
Y6276D01*
X1403237Y6526D01*
X1403404Y6817D01*
X1403654Y7067D01*
X1403904Y7234D01*
X1404237Y7359D01*
X1404529D01*
X1404862Y7276D01*
X1405112Y7109D01*
G01X1407337Y4859D02*
Y7359D01*
X1406837Y6859D01*
G01Y4859D02*
X1407837D01*
G01X1519441Y38776D02*
Y9176D01*
X1497741D01*
Y11976D01*
X1408441D01*
Y9176D01*
X1386741D01*
Y38776D01*
X1408441D01*
Y35976D01*
X1497741D01*
Y38776D01*
X1519441D01*
G01X1350150Y4993D02*
X1377450D01*
Y-18557D01*
X1350150D01*
Y4993D01*
G01X1350461Y37017D02*
X1377761D01*
Y13467D01*
X1350461D01*
Y37017D01*
G01X1346466Y16074D02*
Y10026D01*
G01X1347166Y-14026D02*
Y-20074D01*
G01X1346946Y38055D02*
X1365300D01*
G01X1377057Y75265D02*
X1380834D01*
Y66092D01*
X1384224D01*
Y58596D01*
G01X1358910Y84862D02*
X1372299D01*
Y75126D01*
X1374198D01*
G01X1379219Y38123D02*
Y43300D01*
X1382801D01*
G01X1384800Y56600D02*
X1386900D01*
Y47350D01*
X1383650D01*
Y46350D01*
G01X1358792Y97000D02*
Y87433D01*
G01X1376200Y38055D02*
X1380509D01*
Y36351D01*
X1382360D01*
G01X1390653Y44441D02*
Y46941D01*
X1391694D01*
X1392028Y46816D01*
X1392236Y46649D01*
X1392319Y46316D01*
X1392236Y45983D01*
X1391986Y45774D01*
X1391694Y45649D01*
X1390653D01*
G01X1391694D02*
X1392319Y44441D01*
G01X1394503D02*
X1394586Y44983D01*
X1394711Y45441D01*
X1394878Y45858D01*
X1395086Y46316D01*
X1395419Y46941D01*
X1393753D01*
G01X1397936Y45691D02*
X1398769D01*
Y44941D01*
X1398519Y44691D01*
X1398228Y44524D01*
X1397811Y44441D01*
X1397394Y44524D01*
X1397103Y44691D01*
X1396853Y44941D01*
X1396686Y45233D01*
X1396603Y45566D01*
Y45858D01*
X1396686Y46108D01*
X1396853Y46399D01*
X1397103Y46649D01*
X1397353Y46816D01*
X1397686Y46941D01*
X1397978D01*
X1398311Y46858D01*
X1398561Y46691D01*
G01X1399994Y46524D02*
X1400244Y46774D01*
X1400536Y46899D01*
X1400869Y46941D01*
X1401286Y46858D01*
X1401578Y46649D01*
X1401661Y46399D01*
X1401619Y46149D01*
X1401453Y45941D01*
X1400619Y45524D01*
X1400244Y45233D01*
X1399994Y44816D01*
X1399911Y44441D01*
X1401661D01*
G01X1402969Y44816D02*
X1403219Y44608D01*
X1403511Y44483D01*
X1403886Y44441D01*
X1404261Y44524D01*
X1404553Y44691D01*
X1404761Y44983D01*
X1404803Y45316D01*
X1404719Y45649D01*
X1404511Y45858D01*
X1404219Y46024D01*
X1403928Y46066D01*
X1403636Y46024D01*
X1403261Y45858D01*
X1403386Y46941D01*
X1404511D01*
G01X1398301Y64809D02*
Y65509D01*
X1385301D01*
Y64809D01*
G01Y59109D02*
Y58409D01*
X1398301D01*
Y59109D01*
G01X1415936Y65509D02*
Y75345D01*
X1392164D01*
X1389164Y72345D01*
Y65509D01*
G01Y58409D02*
Y51573D01*
X1392164Y48573D01*
X1415936D01*
G01X1379504Y67465D02*
X1375504D01*
Y60065D01*
G01X1401342Y42275D02*
X1401092Y42400D01*
X1400800Y42483D01*
X1400467D01*
X1400092Y42358D01*
X1399800Y42150D01*
X1399592Y41900D01*
X1399425Y41483D01*
X1399383Y41108D01*
X1399467Y40733D01*
X1399592Y40483D01*
X1399842Y40233D01*
X1400133Y40066D01*
X1400425Y39983D01*
X1400717D01*
X1401008Y40066D01*
X1401258Y40191D01*
X1401467Y40358D01*
G01X1403525Y39983D02*
X1403192Y40025D01*
X1402900Y40191D01*
X1402650Y40441D01*
X1402483Y40733D01*
X1402400Y41066D01*
Y41400D01*
X1402483Y41733D01*
X1402650Y42025D01*
X1402900Y42275D01*
X1403192Y42441D01*
X1403525Y42483D01*
X1403858Y42441D01*
X1404150Y42275D01*
X1404400Y42025D01*
X1404567Y41733D01*
X1404650Y41400D01*
Y41066D01*
X1404567Y40733D01*
X1404400Y40441D01*
X1404150Y40191D01*
X1403858Y40025D01*
X1403525Y39983D01*
G01X1405667D02*
Y42483D01*
X1407583Y39983D01*
Y42483D01*
G01X1408850Y39983D02*
X1410600Y42483D01*
G01X1408850D02*
X1410600Y39983D01*
G01X1412825D02*
X1413117Y40025D01*
X1413450Y40150D01*
X1413658Y40358D01*
X1413742Y40650D01*
X1413658Y40941D01*
X1413408Y41191D01*
X1413033Y41316D01*
X1412617D01*
X1412367Y41400D01*
X1412158Y41608D01*
X1412075Y41900D01*
X1412200Y42191D01*
X1412492Y42400D01*
X1412825Y42483D01*
X1413158Y42400D01*
X1413450Y42191D01*
X1413575Y41900D01*
X1413492Y41608D01*
X1413283Y41400D01*
X1413033Y41316D01*
X1412617D01*
X1412242Y41191D01*
X1411992Y40941D01*
X1411908Y40650D01*
X1411992Y40358D01*
X1412200Y40150D01*
X1412533Y40025D01*
X1412825Y39983D01*
G01X1389262Y95604D02*
X1411262D01*
Y77904D01*
X1389262D01*
Y95604D01*
G01X1388271Y90497D02*
Y85297D01*
G01X1381271Y90497D02*
Y82697D01*
G01X1388271Y90497D02*
X1381271D01*
G01X1388271Y77097D02*
Y85797D01*
G01X1381271Y77097D02*
X1388271D01*
G01X1381271Y83497D02*
Y77097D01*
G01X1380412Y90478D02*
Y85278D01*
G01X1373412Y90478D02*
Y82678D01*
G01X1380412Y90478D02*
X1373412D01*
G01X1380412Y77078D02*
Y85778D01*
G01X1373412Y77078D02*
X1380412D01*
G01X1373412Y83478D02*
Y77078D01*
G01X1369050Y72550D02*
Y48450D01*
X1344950D01*
Y72550D01*
X1369050D01*
G01X1366030Y70539D02*
X1367039D01*
Y69357D01*
G01X1346961Y69467D02*
Y70539D01*
G01X1348207Y50461D02*
X1346961D01*
Y51643D01*
G01X1367039Y51659D02*
Y50461D01*
X1365891D01*
G01X1346961Y70539D02*
X1348074D01*
G01X1388751Y125760D02*
X1388626Y125510D01*
X1388543Y125218D01*
Y124885D01*
X1388668Y124510D01*
X1388876Y124218D01*
X1389126Y124010D01*
X1389543Y123843D01*
X1389918Y123801D01*
X1390293Y123885D01*
X1390543Y124010D01*
X1390793Y124260D01*
X1390960Y124551D01*
X1391043Y124843D01*
Y125135D01*
X1390960Y125426D01*
X1390835Y125676D01*
X1390668Y125885D01*
G01X1391043Y127860D02*
X1390501Y127943D01*
X1390043Y128068D01*
X1389626Y128235D01*
X1389168Y128443D01*
X1388543Y128776D01*
Y127110D01*
G01X1391043Y130251D02*
X1388543D01*
Y131835D01*
G01X1389751Y131251D02*
Y130251D01*
G01X1390668Y133226D02*
X1390876Y133476D01*
X1391001Y133768D01*
X1391043Y134143D01*
X1390960Y134518D01*
X1390793Y134810D01*
X1390501Y135018D01*
X1390168Y135060D01*
X1389835Y134976D01*
X1389626Y134768D01*
X1389460Y134476D01*
X1389418Y134185D01*
X1389460Y133893D01*
X1389626Y133518D01*
X1388543Y133643D01*
Y134768D01*
G01X1379374Y126959D02*
X1376874D01*
Y128000D01*
X1376999Y128334D01*
X1377166Y128542D01*
X1377499Y128625D01*
X1377832Y128542D01*
X1378041Y128292D01*
X1378166Y128000D01*
Y126959D01*
G01Y128000D02*
X1379374Y128625D01*
G01Y130809D02*
X1378832Y130892D01*
X1378374Y131017D01*
X1377957Y131184D01*
X1377499Y131392D01*
X1376874Y131725D01*
Y130059D01*
G01X1379374Y133200D02*
X1376874D01*
Y134784D01*
G01X1378082Y134200D02*
Y133200D01*
G01X1379374Y137092D02*
X1376874D01*
X1377374Y136592D01*
G01X1379374D02*
Y137592D01*
G01X1378332Y139400D02*
X1378041Y139692D01*
X1377874Y139942D01*
X1377791Y140275D01*
X1377874Y140567D01*
X1378041Y140775D01*
X1378291Y140942D01*
X1378582Y140984D01*
X1378832Y140942D01*
X1379082Y140775D01*
X1379291Y140525D01*
X1379374Y140234D01*
X1379291Y139900D01*
X1379041Y139609D01*
X1378666Y139442D01*
X1378249Y139400D01*
X1377707Y139484D01*
X1377416Y139609D01*
X1377124Y139817D01*
X1376916Y140109D01*
X1376874Y140400D01*
X1376957Y140692D01*
X1377166Y140900D01*
G01X1375374Y127246D02*
X1372874D01*
Y128287D01*
X1372999Y128621D01*
X1373166Y128829D01*
X1373499Y128912D01*
X1373832Y128829D01*
X1374041Y128579D01*
X1374166Y128287D01*
Y127246D01*
G01Y128287D02*
X1375374Y128912D01*
G01Y131096D02*
X1374832Y131179D01*
X1374374Y131304D01*
X1373957Y131471D01*
X1373499Y131679D01*
X1372874Y132012D01*
Y130346D01*
G01X1375374Y133487D02*
X1372874D01*
Y135071D01*
G01X1374082Y134487D02*
Y133487D01*
G01X1375374Y137379D02*
X1372874D01*
X1373374Y136879D01*
G01X1375374D02*
Y137879D01*
G01X1375082Y139771D02*
X1375291Y140062D01*
X1375374Y140396D01*
X1375291Y140729D01*
X1375041Y141021D01*
X1374666Y141229D01*
X1374291Y141312D01*
X1373832D01*
X1373457Y141229D01*
X1373124Y141021D01*
X1372957Y140771D01*
X1372874Y140479D01*
X1372957Y140146D01*
X1373124Y139896D01*
X1373374Y139729D01*
X1373707Y139646D01*
X1373999Y139729D01*
X1374291Y139937D01*
X1374457Y140187D01*
X1374499Y140479D01*
X1374416Y140812D01*
X1374207Y141062D01*
X1373832Y141312D01*
G01X1367081Y128406D02*
X1364581D01*
Y129447D01*
X1364706Y129781D01*
X1364873Y129989D01*
X1365206Y130072D01*
X1365539Y129989D01*
X1365748Y129739D01*
X1365873Y129447D01*
Y128406D01*
G01Y129447D02*
X1367081Y130072D01*
G01Y132256D02*
X1366539Y132339D01*
X1366081Y132464D01*
X1365664Y132631D01*
X1365206Y132839D01*
X1364581Y133172D01*
Y131506D01*
G01X1367081Y134647D02*
X1364581D01*
Y136231D01*
G01X1365789Y135647D02*
Y134647D01*
G01X1367081Y138539D02*
X1364581D01*
X1365081Y138039D01*
G01X1367081D02*
Y139039D01*
G01X1366706Y140722D02*
X1366914Y140972D01*
X1367039Y141264D01*
X1367081Y141639D01*
X1366998Y142014D01*
X1366831Y142306D01*
X1366539Y142514D01*
X1366206Y142556D01*
X1365873Y142472D01*
X1365664Y142264D01*
X1365498Y141972D01*
X1365456Y141681D01*
X1365498Y141389D01*
X1365664Y141014D01*
X1364581Y141139D01*
Y142264D01*
G01X1350591Y132354D02*
Y134854D01*
X1351632D01*
X1351966Y134729D01*
X1352174Y134562D01*
X1352257Y134229D01*
X1352174Y133896D01*
X1351924Y133687D01*
X1351632Y133562D01*
X1350591D01*
G01X1351632D02*
X1352257Y132354D01*
G01X1354441D02*
X1354524Y132896D01*
X1354649Y133354D01*
X1354816Y133771D01*
X1355024Y134229D01*
X1355357Y134854D01*
X1353691D01*
G01X1356832Y132354D02*
Y134854D01*
X1358416D01*
G01X1357832Y133646D02*
X1356832D01*
G01X1360641Y132354D02*
X1360724Y132896D01*
X1360849Y133354D01*
X1361016Y133771D01*
X1361224Y134229D01*
X1361557Y134854D01*
X1359891D01*
G01X1384087Y131542D02*
X1383962Y131292D01*
X1383879Y131000D01*
Y130667D01*
X1384004Y130292D01*
X1384212Y130000D01*
X1384462Y129792D01*
X1384879Y129625D01*
X1385254Y129583D01*
X1385629Y129667D01*
X1385879Y129792D01*
X1386129Y130042D01*
X1386296Y130333D01*
X1386379Y130625D01*
Y130917D01*
X1386296Y131208D01*
X1386171Y131458D01*
X1386004Y131667D01*
G01X1386379Y133642D02*
X1385837Y133725D01*
X1385379Y133850D01*
X1384962Y134017D01*
X1384504Y134225D01*
X1383879Y134558D01*
Y132892D01*
G01X1386379Y136033D02*
X1383879D01*
Y137617D01*
G01X1385087Y137033D02*
Y136033D01*
G01X1385337Y139133D02*
X1385046Y139425D01*
X1384879Y139675D01*
X1384796Y140008D01*
X1384879Y140300D01*
X1385046Y140508D01*
X1385296Y140675D01*
X1385587Y140717D01*
X1385837Y140675D01*
X1386087Y140508D01*
X1386296Y140258D01*
X1386379Y139967D01*
X1386296Y139633D01*
X1386046Y139342D01*
X1385671Y139175D01*
X1385254Y139133D01*
X1384712Y139217D01*
X1384421Y139342D01*
X1384129Y139550D01*
X1383921Y139842D01*
X1383879Y140133D01*
X1383962Y140425D01*
X1384171Y140633D01*
G01X1368773Y129756D02*
X1368648Y129506D01*
X1368565Y129214D01*
Y128881D01*
X1368690Y128506D01*
X1368898Y128214D01*
X1369148Y128006D01*
X1369565Y127839D01*
X1369940Y127797D01*
X1370315Y127881D01*
X1370565Y128006D01*
X1370815Y128256D01*
X1370982Y128547D01*
X1371065Y128839D01*
Y129131D01*
X1370982Y129422D01*
X1370857Y129672D01*
X1370690Y129881D01*
G01X1371065Y131856D02*
X1370523Y131939D01*
X1370065Y132064D01*
X1369648Y132231D01*
X1369190Y132439D01*
X1368565Y132772D01*
Y131106D01*
G01X1371065Y134247D02*
X1368565D01*
Y135831D01*
G01X1369773Y135247D02*
Y134247D01*
G01X1371065Y138139D02*
X1368565D01*
X1369065Y137639D01*
G01X1371065D02*
Y138639D01*
G01Y141239D02*
X1368565D01*
X1369065Y140739D01*
G01X1371065D02*
Y141739D01*
G01X1398507Y123948D02*
X1396007D01*
Y125532D01*
G01X1397215Y124948D02*
Y123948D01*
G01X1397174Y128173D02*
X1397049Y128340D01*
X1396840Y128465D01*
X1396549Y128548D01*
X1396299Y128465D01*
X1396132Y128298D01*
X1396007Y128007D01*
Y126882D01*
X1398507D01*
Y128257D01*
X1398340Y128548D01*
X1398090Y128715D01*
X1397799Y128798D01*
X1397507Y128715D01*
X1397257Y128465D01*
X1397174Y128173D01*
Y126882D01*
G01X1398507Y130857D02*
X1397965Y130940D01*
X1397507Y131065D01*
X1397090Y131232D01*
X1396632Y131440D01*
X1396007Y131773D01*
Y130107D01*
G01X1398507Y133248D02*
X1396007D01*
Y134832D01*
G01X1397215Y134248D02*
Y133248D01*
G01X1398507Y137140D02*
X1396007D01*
X1396507Y136640D01*
G01X1398507D02*
Y137640D01*
G01X1394815Y139393D02*
Y142493D01*
X1396271D01*
G01X1395735Y140995D02*
X1394815D01*
G01X1397915Y141976D02*
X1398145Y142286D01*
X1398413Y142441D01*
X1398720Y142493D01*
X1399103Y142390D01*
X1399371Y142131D01*
X1399448Y141821D01*
X1399410Y141511D01*
X1399256Y141253D01*
X1398490Y140736D01*
X1398145Y140375D01*
X1397915Y139858D01*
X1397838Y139393D01*
X1399448D01*
G01X1401743Y142493D02*
X1401436Y142390D01*
X1401206Y142131D01*
X1401053Y141821D01*
X1400938Y141408D01*
X1400900Y140943D01*
X1400938Y140478D01*
X1401053Y140065D01*
X1401206Y139755D01*
X1401436Y139496D01*
X1401743Y139393D01*
X1402050Y139496D01*
X1402280Y139755D01*
X1402433Y140065D01*
X1402548Y140478D01*
X1402586Y140943D01*
X1402548Y141408D01*
X1402433Y141821D01*
X1402280Y142131D01*
X1402050Y142390D01*
X1401743Y142493D01*
G01X1399233Y100244D02*
X1398983Y100369D01*
X1398691Y100452D01*
X1398358D01*
X1397983Y100327D01*
X1397691Y100119D01*
X1397483Y99869D01*
X1397316Y99452D01*
X1397274Y99077D01*
X1397358Y98702D01*
X1397483Y98452D01*
X1397733Y98202D01*
X1398024Y98035D01*
X1398316Y97952D01*
X1398608D01*
X1398899Y98035D01*
X1399149Y98160D01*
X1399358Y98327D01*
G01X1401333Y97952D02*
X1401416Y98494D01*
X1401541Y98952D01*
X1401708Y99369D01*
X1401916Y99827D01*
X1402249Y100452D01*
X1400583D01*
G01X1403724Y97952D02*
Y100452D01*
X1405308D01*
G01X1404724Y99244D02*
X1403724D01*
G01X1407533Y97952D02*
X1407616Y98494D01*
X1407741Y98952D01*
X1407908Y99369D01*
X1408116Y99827D01*
X1408449Y100452D01*
X1406783D01*
G01X1345134Y113433D02*
Y111767D01*
X1342634D01*
Y113433D01*
G01X1343842Y112767D02*
Y111767D01*
G01X1342634Y114783D02*
X1344426D01*
X1344801Y114950D01*
X1345051Y115283D01*
X1345134Y115700D01*
X1345051Y116117D01*
X1344801Y116450D01*
X1344426Y116617D01*
X1342634D01*
G01X1345134Y118717D02*
X1344592Y118800D01*
X1344134Y118925D01*
X1343717Y119092D01*
X1343259Y119300D01*
X1342634Y119633D01*
Y117967D01*
G01X1345134Y121108D02*
X1342634D01*
Y122692D01*
G01X1343842Y122108D02*
Y121108D01*
G01X1345134Y125000D02*
X1342634D01*
X1343134Y124500D01*
G01X1345134D02*
Y125500D01*
G01X1346050Y98800D02*
Y126100D01*
X1373350D01*
Y98800D01*
X1346050D01*
G01X1371905Y101041D02*
Y100245D01*
X1371107D01*
G01Y124655D02*
X1371905D01*
Y123859D01*
G01X1347495D02*
Y124655D01*
X1348279D01*
G01Y100245D02*
X1347495D01*
Y101041D01*
G01X1388389Y215659D02*
Y218759D01*
X1387929Y218139D01*
G01Y215659D02*
X1388849D01*
G01X1391489Y218759D02*
X1391182Y218656D01*
X1390952Y218397D01*
X1390799Y218087D01*
X1390684Y217674D01*
X1390646Y217209D01*
X1390684Y216744D01*
X1390799Y216331D01*
X1390952Y216021D01*
X1391182Y215762D01*
X1391489Y215659D01*
X1391796Y215762D01*
X1392026Y216021D01*
X1392179Y216331D01*
X1392294Y216744D01*
X1392332Y217209D01*
X1392294Y217674D01*
X1392179Y218087D01*
X1392026Y218397D01*
X1391796Y218656D01*
X1391489Y218759D01*
G01X1394512Y215091D02*
X1394666Y215762D01*
G01X1397689Y215659D02*
Y218759D01*
X1397229Y218139D01*
G01Y215659D02*
X1398149D01*
G01X1400061Y218242D02*
X1400291Y218552D01*
X1400559Y218707D01*
X1400866Y218759D01*
X1401249Y218656D01*
X1401517Y218397D01*
X1401594Y218087D01*
X1401556Y217777D01*
X1401402Y217519D01*
X1400636Y217002D01*
X1400291Y216641D01*
X1400061Y216124D01*
X1399984Y215659D01*
X1401594D01*
G01X1406031D02*
X1406989Y218759D01*
X1407947Y215659D01*
G01X1407602Y216744D02*
X1406376D01*
G01X1409246Y215659D02*
Y218759D01*
X1410012D01*
X1410319Y218604D01*
X1410549Y218397D01*
X1410741Y218087D01*
X1410894Y217726D01*
X1410932Y217209D01*
X1410894Y216692D01*
X1410741Y216331D01*
X1410549Y216021D01*
X1410319Y215814D01*
X1410012Y215659D01*
X1409246D01*
G01X1412422D02*
Y218759D01*
X1413381D01*
X1413687Y218604D01*
X1413879Y218397D01*
X1413956Y217984D01*
X1413879Y217571D01*
X1413649Y217312D01*
X1413381Y217157D01*
X1412422D01*
G01X1413381D02*
X1413956Y215659D01*
G01X1418546D02*
Y218759D01*
X1419312D01*
X1419619Y218604D01*
X1419849Y218397D01*
X1420041Y218087D01*
X1420194Y217726D01*
X1420232Y217209D01*
X1420194Y216692D01*
X1420041Y216331D01*
X1419849Y216021D01*
X1419619Y215814D01*
X1419312Y215659D01*
X1418546D01*
G01X1421722Y218759D02*
Y215659D01*
X1423256D01*
G01X1425589D02*
Y217054D01*
X1424822Y218759D01*
G01X1426356D02*
X1425589Y217054D01*
G01X1430946Y215659D02*
Y218759D01*
X1431712D01*
X1432019Y218604D01*
X1432249Y218397D01*
X1432441Y218087D01*
X1432594Y217726D01*
X1432632Y217209D01*
X1432594Y216692D01*
X1432441Y216331D01*
X1432249Y216021D01*
X1432019Y215814D01*
X1431712Y215659D01*
X1430946D01*
G01X1434429Y218759D02*
X1435349D01*
G01X1434889D02*
Y215659D01*
G01X1434429D02*
X1435349D01*
G01X1437184Y216072D02*
X1437491Y215814D01*
X1437836Y215659D01*
X1438142D01*
X1438449Y215814D01*
X1438679Y216072D01*
X1438794Y216434D01*
X1438717Y216796D01*
X1438526Y217106D01*
X1438181Y217312D01*
X1437721Y217416D01*
X1437452Y217622D01*
X1437337Y217984D01*
X1437414Y218346D01*
X1437606Y218604D01*
X1437874Y218759D01*
X1438142D01*
X1438411Y218656D01*
X1438641Y218397D01*
G01X1440131Y215659D02*
X1441089Y218759D01*
X1442047Y215659D01*
G01X1441702Y216744D02*
X1440476D01*
G01X1444496Y217312D02*
X1444649Y217467D01*
X1444764Y217726D01*
X1444841Y218087D01*
X1444764Y218397D01*
X1444611Y218604D01*
X1444342Y218759D01*
X1443307D01*
Y215659D01*
X1444572D01*
X1444841Y215866D01*
X1444994Y216176D01*
X1445071Y216537D01*
X1444994Y216899D01*
X1444764Y217209D01*
X1444496Y217312D01*
X1443307D01*
G01X1446522Y218759D02*
Y215659D01*
X1448056D01*
G01X1451156D02*
X1449622D01*
Y218759D01*
X1451156D01*
G01X1450542Y217261D02*
X1449622D01*
G01X1452646Y215659D02*
Y218759D01*
X1453412D01*
X1453719Y218604D01*
X1453949Y218397D01*
X1454141Y218087D01*
X1454294Y217726D01*
X1454332Y217209D01*
X1454294Y216692D01*
X1454141Y216331D01*
X1453949Y216021D01*
X1453719Y215814D01*
X1453412Y215659D01*
X1452646D01*
G01X1386139Y225993D02*
Y219993D01*
X1455639D01*
Y231993D01*
X1403839D01*
Y213993D01*
X1386139D01*
Y219993D01*
G01X1373986Y185451D02*
Y191951D01*
G01Y227451D02*
Y191951D01*
G01Y210451D02*
X1373000D01*
G01X1390195Y177473D02*
X1391153Y180573D01*
X1392111Y177473D01*
G01X1391766Y178558D02*
X1390540D01*
G01X1393525Y180056D02*
X1393755Y180366D01*
X1394023Y180521D01*
X1394330Y180573D01*
X1394713Y180470D01*
X1394981Y180211D01*
X1395058Y179901D01*
X1395020Y179591D01*
X1394866Y179333D01*
X1394100Y178816D01*
X1393755Y178455D01*
X1393525Y177938D01*
X1393448Y177473D01*
X1395058D01*
G01X1397353Y180573D02*
X1397046Y180470D01*
X1396816Y180211D01*
X1396663Y179901D01*
X1396548Y179488D01*
X1396510Y179023D01*
X1396548Y178558D01*
X1396663Y178145D01*
X1396816Y177835D01*
X1397046Y177576D01*
X1397353Y177473D01*
X1397660Y177576D01*
X1397890Y177835D01*
X1398043Y178145D01*
X1398158Y178558D01*
X1398196Y179023D01*
X1398158Y179488D01*
X1398043Y179901D01*
X1397890Y180211D01*
X1397660Y180470D01*
X1397353Y180573D01*
G01X1394522Y230383D02*
X1394752Y230693D01*
X1395020Y230848D01*
X1395327Y230900D01*
X1395710Y230797D01*
X1395978Y230538D01*
X1396055Y230228D01*
X1396017Y229918D01*
X1395863Y229660D01*
X1395097Y229143D01*
X1394752Y228782D01*
X1394522Y228265D01*
X1394445Y227800D01*
X1396055D01*
G01X1398273Y227232D02*
X1398427Y227903D01*
G01X1401910Y227800D02*
Y230900D01*
X1400492Y228678D01*
X1402408D01*
G01X1406922Y227800D02*
Y230900D01*
X1408378D01*
G01X1407842Y229402D02*
X1406922D01*
G01X1410750Y227800D02*
X1410443Y227852D01*
X1410175Y228058D01*
X1409945Y228368D01*
X1409792Y228730D01*
X1409715Y229143D01*
Y229557D01*
X1409792Y229970D01*
X1409945Y230332D01*
X1410175Y230642D01*
X1410443Y230848D01*
X1410750Y230900D01*
X1411057Y230848D01*
X1411325Y230642D01*
X1411555Y230332D01*
X1411708Y229970D01*
X1411785Y229557D01*
Y229143D01*
X1411708Y228730D01*
X1411555Y228368D01*
X1411325Y228058D01*
X1411057Y227852D01*
X1410750Y227800D01*
G01X1413083D02*
Y230900D01*
X1414042D01*
X1414348Y230745D01*
X1414540Y230538D01*
X1414617Y230125D01*
X1414540Y229712D01*
X1414310Y229453D01*
X1414042Y229298D01*
X1413083D01*
G01X1414042D02*
X1414617Y227800D01*
G01X1417793Y230642D02*
X1417563Y230797D01*
X1417295Y230900D01*
X1416988D01*
X1416643Y230745D01*
X1416375Y230487D01*
X1416183Y230177D01*
X1416030Y229660D01*
X1415992Y229195D01*
X1416068Y228730D01*
X1416183Y228420D01*
X1416413Y228110D01*
X1416682Y227903D01*
X1416950Y227800D01*
X1417218D01*
X1417487Y227903D01*
X1417717Y228058D01*
X1417908Y228265D01*
G01X1420817Y227800D02*
X1419283D01*
Y230900D01*
X1420817D01*
G01X1420203Y229402D02*
X1419283D01*
G01X1425483Y227800D02*
Y230900D01*
X1426403D01*
X1426710Y230745D01*
X1426940Y230383D01*
X1427017Y229970D01*
X1426940Y229557D01*
X1426748Y229247D01*
X1426403Y229092D01*
X1425483D01*
G01X1428200Y230900D02*
X1428737Y227800D01*
X1429350Y230900D01*
X1429963Y227800D01*
X1430500Y230900D01*
G01X1431683Y227800D02*
Y230900D01*
X1432642D01*
X1432948Y230745D01*
X1433140Y230538D01*
X1433217Y230125D01*
X1433140Y229712D01*
X1432910Y229453D01*
X1432642Y229298D01*
X1431683D01*
G01X1432642D02*
X1433217Y227800D01*
G01X1438650D02*
X1438343Y227852D01*
X1438075Y228058D01*
X1437845Y228368D01*
X1437692Y228730D01*
X1437615Y229143D01*
Y229557D01*
X1437692Y229970D01*
X1437845Y230332D01*
X1438075Y230642D01*
X1438343Y230848D01*
X1438650Y230900D01*
X1438957Y230848D01*
X1439225Y230642D01*
X1439455Y230332D01*
X1439608Y229970D01*
X1439685Y229557D01*
Y229143D01*
X1439608Y228730D01*
X1439455Y228368D01*
X1439225Y228058D01*
X1438957Y227852D01*
X1438650Y227800D01*
G01X1440868D02*
Y230900D01*
X1442632Y227800D01*
Y230900D01*
G01X1391637Y221821D02*
X1391906Y221562D01*
X1392212Y221459D01*
X1392519Y221562D01*
X1392787Y221872D01*
X1392979Y222337D01*
X1393056Y222802D01*
Y223371D01*
X1392979Y223836D01*
X1392787Y224249D01*
X1392557Y224456D01*
X1392289Y224559D01*
X1391982Y224456D01*
X1391752Y224249D01*
X1391599Y223939D01*
X1391522Y223526D01*
X1391599Y223164D01*
X1391791Y222802D01*
X1392021Y222596D01*
X1392289Y222544D01*
X1392596Y222647D01*
X1392826Y222906D01*
X1393056Y223371D01*
G01X1395312Y220891D02*
X1395466Y221562D01*
G01X1398489Y221459D02*
Y224559D01*
X1398029Y223939D01*
G01Y221459D02*
X1398949D01*
G01X1401589D02*
Y224559D01*
X1401129Y223939D01*
G01Y221459D02*
X1402049D01*
G01X1406946Y224559D02*
Y222337D01*
X1407099Y221872D01*
X1407406Y221562D01*
X1407789Y221459D01*
X1408172Y221562D01*
X1408479Y221872D01*
X1408632Y222337D01*
Y224559D01*
G01X1409931Y221459D02*
X1410889Y224559D01*
X1411847Y221459D01*
G01X1411502Y222544D02*
X1410276D01*
G01X1413222Y221459D02*
Y224559D01*
X1414181D01*
X1414487Y224404D01*
X1414679Y224197D01*
X1414756Y223784D01*
X1414679Y223371D01*
X1414449Y223112D01*
X1414181Y222957D01*
X1413222D01*
G01X1414181D02*
X1414756Y221459D01*
G01X1417089Y224559D02*
Y221459D01*
G01X1416207Y224559D02*
X1417971D01*
G01X1424132Y224301D02*
X1423902Y224456D01*
X1423634Y224559D01*
X1423327D01*
X1422982Y224404D01*
X1422714Y224146D01*
X1422522Y223836D01*
X1422369Y223319D01*
X1422331Y222854D01*
X1422407Y222389D01*
X1422522Y222079D01*
X1422752Y221769D01*
X1423021Y221562D01*
X1423289Y221459D01*
X1423557D01*
X1423826Y221562D01*
X1424056Y221717D01*
X1424247Y221924D01*
G01X1425584Y221459D02*
Y224559D01*
G01X1427194D02*
Y221459D01*
G01Y223009D02*
X1425584D01*
G01X1431822Y224559D02*
Y221459D01*
X1433356D01*
G01X1436532Y224301D02*
X1436302Y224456D01*
X1436034Y224559D01*
X1435727D01*
X1435382Y224404D01*
X1435114Y224146D01*
X1434922Y223836D01*
X1434769Y223319D01*
X1434731Y222854D01*
X1434807Y222389D01*
X1434922Y222079D01*
X1435152Y221769D01*
X1435421Y221562D01*
X1435689Y221459D01*
X1435957D01*
X1436226Y221562D01*
X1436456Y221717D01*
X1436647Y221924D01*
G01X1437946Y221459D02*
Y224559D01*
G01X1439402D02*
X1437946Y222647D01*
G01X1439632Y221459D02*
X1438597Y223526D01*
G01X1442656Y221459D02*
X1441122D01*
Y224559D01*
X1442656D01*
G01X1442042Y223061D02*
X1441122D01*
G01X1444146Y221459D02*
Y224559D01*
X1444912D01*
X1445219Y224404D01*
X1445449Y224197D01*
X1445641Y223887D01*
X1445794Y223526D01*
X1445832Y223009D01*
X1445794Y222492D01*
X1445641Y222131D01*
X1445449Y221821D01*
X1445219Y221614D01*
X1444912Y221459D01*
X1444146D01*
G01X1401900Y225993D02*
X1455639D01*
G01X1396000Y231993D02*
X1393500D01*
G01X1386139Y230500D02*
Y225993D01*
X1399000D01*
G01X1390500Y231993D02*
X1388500D01*
G01X1403839D02*
X1399000D01*
G01X1354145Y364900D02*
Y358900D01*
X1379200D01*
Y340400D01*
G01X1400667Y387367D02*
Y389867D01*
X1401708D01*
X1402042Y389742D01*
X1402250Y389575D01*
X1402333Y389242D01*
X1402250Y388909D01*
X1402000Y388700D01*
X1401708Y388575D01*
X1400667D01*
G01X1401708D02*
X1402333Y387367D01*
G01X1404517D02*
X1404600Y387909D01*
X1404725Y388367D01*
X1404892Y388784D01*
X1405100Y389242D01*
X1405433Y389867D01*
X1403767D01*
G01X1408617Y389659D02*
X1408367Y389784D01*
X1408075Y389867D01*
X1407742D01*
X1407367Y389742D01*
X1407075Y389534D01*
X1406867Y389284D01*
X1406700Y388867D01*
X1406658Y388492D01*
X1406742Y388117D01*
X1406867Y387867D01*
X1407117Y387617D01*
X1407408Y387450D01*
X1407700Y387367D01*
X1407992D01*
X1408283Y387450D01*
X1408533Y387575D01*
X1408742Y387742D01*
G01X1410008Y389450D02*
X1410258Y389700D01*
X1410550Y389825D01*
X1410883Y389867D01*
X1411300Y389784D01*
X1411592Y389575D01*
X1411675Y389325D01*
X1411633Y389075D01*
X1411467Y388867D01*
X1410633Y388450D01*
X1410258Y388159D01*
X1410008Y387742D01*
X1409925Y387367D01*
X1411675D01*
G01X1412983Y387742D02*
X1413233Y387534D01*
X1413525Y387409D01*
X1413900Y387367D01*
X1414275Y387450D01*
X1414567Y387617D01*
X1414775Y387909D01*
X1414817Y388242D01*
X1414733Y388575D01*
X1414525Y388784D01*
X1414233Y388950D01*
X1413942Y388992D01*
X1413650Y388950D01*
X1413275Y388784D01*
X1413400Y389867D01*
X1414525D01*
G01X1397417Y379100D02*
Y381600D01*
X1398458D01*
X1398792Y381475D01*
X1399000Y381308D01*
X1399083Y380975D01*
X1399000Y380642D01*
X1398750Y380433D01*
X1398458Y380308D01*
X1397417D01*
G01X1398458D02*
X1399083Y379100D01*
G01X1401350Y381600D02*
Y379100D01*
G01X1400392Y381600D02*
X1402308D01*
G01X1404950Y379100D02*
Y381600D01*
X1403408Y379808D01*
X1405492D01*
G01X1407467Y379100D02*
X1407550Y379642D01*
X1407675Y380100D01*
X1407842Y380517D01*
X1408050Y380975D01*
X1408383Y381600D01*
X1406717D01*
G01X1393382Y369945D02*
X1393132Y370070D01*
X1392840Y370153D01*
X1392507D01*
X1392132Y370028D01*
X1391840Y369820D01*
X1391632Y369570D01*
X1391465Y369153D01*
X1391423Y368778D01*
X1391507Y368403D01*
X1391632Y368153D01*
X1391882Y367903D01*
X1392173Y367736D01*
X1392465Y367653D01*
X1392757D01*
X1393048Y367736D01*
X1393298Y367861D01*
X1393507Y368028D01*
G01X1395482Y367653D02*
X1395565Y368195D01*
X1395690Y368653D01*
X1395857Y369070D01*
X1396065Y369528D01*
X1396398Y370153D01*
X1394732D01*
G01X1399582Y369945D02*
X1399332Y370070D01*
X1399040Y370153D01*
X1398707D01*
X1398332Y370028D01*
X1398040Y369820D01*
X1397832Y369570D01*
X1397665Y369153D01*
X1397623Y368778D01*
X1397707Y368403D01*
X1397832Y368153D01*
X1398082Y367903D01*
X1398373Y367736D01*
X1398665Y367653D01*
X1398957D01*
X1399248Y367736D01*
X1399498Y367861D01*
X1399707Y368028D01*
G01X1401765Y367653D02*
Y370153D01*
X1401265Y369653D01*
G01Y367653D02*
X1402265D01*
G01X1404073Y369736D02*
X1404323Y369986D01*
X1404615Y370111D01*
X1404948Y370153D01*
X1405365Y370070D01*
X1405657Y369861D01*
X1405740Y369611D01*
X1405698Y369361D01*
X1405532Y369153D01*
X1404698Y368736D01*
X1404323Y368445D01*
X1404073Y368028D01*
X1403990Y367653D01*
X1405740D01*
G01X1369717Y363992D02*
X1369467Y364117D01*
X1369175Y364200D01*
X1368842D01*
X1368467Y364075D01*
X1368175Y363867D01*
X1367967Y363617D01*
X1367800Y363200D01*
X1367758Y362825D01*
X1367842Y362450D01*
X1367967Y362200D01*
X1368217Y361950D01*
X1368508Y361783D01*
X1368800Y361700D01*
X1369092D01*
X1369383Y361783D01*
X1369633Y361908D01*
X1369842Y362075D01*
G01X1371817Y361700D02*
X1371900Y362242D01*
X1372025Y362700D01*
X1372192Y363117D01*
X1372400Y363575D01*
X1372733Y364200D01*
X1371067D01*
G01X1375917Y363992D02*
X1375667Y364117D01*
X1375375Y364200D01*
X1375042D01*
X1374667Y364075D01*
X1374375Y363867D01*
X1374167Y363617D01*
X1374000Y363200D01*
X1373958Y362825D01*
X1374042Y362450D01*
X1374167Y362200D01*
X1374417Y361950D01*
X1374708Y361783D01*
X1375000Y361700D01*
X1375292D01*
X1375583Y361783D01*
X1375833Y361908D01*
X1376042Y362075D01*
G01X1378100Y361700D02*
Y364200D01*
X1377600Y363700D01*
G01Y361700D02*
X1378600D01*
G01X1381200D02*
Y364200D01*
X1380700Y363700D01*
G01Y361700D02*
X1381700D01*
G01X1393664Y377170D02*
X1393414Y377295D01*
X1393122Y377378D01*
X1392789D01*
X1392414Y377253D01*
X1392122Y377045D01*
X1391914Y376795D01*
X1391747Y376378D01*
X1391705Y376003D01*
X1391789Y375628D01*
X1391914Y375378D01*
X1392164Y375128D01*
X1392455Y374961D01*
X1392747Y374878D01*
X1393039D01*
X1393330Y374961D01*
X1393580Y375086D01*
X1393789Y375253D01*
G01X1395764Y374878D02*
X1395847Y375420D01*
X1395972Y375878D01*
X1396139Y376295D01*
X1396347Y376753D01*
X1396680Y377378D01*
X1395014D01*
G01X1399864Y377170D02*
X1399614Y377295D01*
X1399322Y377378D01*
X1398989D01*
X1398614Y377253D01*
X1398322Y377045D01*
X1398114Y376795D01*
X1397947Y376378D01*
X1397905Y376003D01*
X1397989Y375628D01*
X1398114Y375378D01*
X1398364Y375128D01*
X1398655Y374961D01*
X1398947Y374878D01*
X1399239D01*
X1399530Y374961D01*
X1399780Y375086D01*
X1399989Y375253D01*
G01X1402047Y374878D02*
Y377378D01*
X1401547Y376878D01*
G01Y374878D02*
X1402547D01*
G01X1405647D02*
Y377378D01*
X1404105Y375586D01*
X1406189D01*
G01X1399567Y394559D02*
X1399317Y394684D01*
X1399025Y394767D01*
X1398692D01*
X1398317Y394642D01*
X1398025Y394434D01*
X1397817Y394184D01*
X1397650Y393767D01*
X1397608Y393392D01*
X1397692Y393017D01*
X1397817Y392767D01*
X1398067Y392517D01*
X1398358Y392350D01*
X1398650Y392267D01*
X1398942D01*
X1399233Y392350D01*
X1399483Y392475D01*
X1399692Y392642D01*
G01X1401750Y394767D02*
Y392267D01*
G01X1400792Y394767D02*
X1402708D01*
G01X1404767Y392267D02*
X1404850Y392809D01*
X1404975Y393267D01*
X1405142Y393684D01*
X1405350Y394142D01*
X1405683Y394767D01*
X1404017D01*
G01X1407950D02*
X1407617Y394684D01*
X1407367Y394475D01*
X1407200Y394225D01*
X1407075Y393892D01*
X1407033Y393517D01*
X1407075Y393142D01*
X1407200Y392809D01*
X1407367Y392559D01*
X1407617Y392350D01*
X1407950Y392267D01*
X1408283Y392350D01*
X1408533Y392559D01*
X1408700Y392809D01*
X1408825Y393142D01*
X1408867Y393517D01*
X1408825Y393892D01*
X1408700Y394225D01*
X1408533Y394475D01*
X1408283Y394684D01*
X1407950Y394767D01*
G01X1399267Y385659D02*
X1399017Y385784D01*
X1398725Y385867D01*
X1398392D01*
X1398017Y385742D01*
X1397725Y385534D01*
X1397517Y385284D01*
X1397350Y384867D01*
X1397308Y384492D01*
X1397392Y384117D01*
X1397517Y383867D01*
X1397767Y383617D01*
X1398058Y383450D01*
X1398350Y383367D01*
X1398642D01*
X1398933Y383450D01*
X1399183Y383575D01*
X1399392Y383742D01*
G01X1401450Y385867D02*
Y383367D01*
G01X1400492Y385867D02*
X1402408D01*
G01X1404467Y383367D02*
X1404550Y383909D01*
X1404675Y384367D01*
X1404842Y384784D01*
X1405050Y385242D01*
X1405383Y385867D01*
X1403717D01*
G01X1407650Y383367D02*
Y385867D01*
X1407150Y385367D01*
G01Y383367D02*
X1408150D01*
G01X1355017Y361800D02*
Y364300D01*
X1356058D01*
X1356392Y364175D01*
X1356600Y364008D01*
X1356683Y363675D01*
X1356600Y363342D01*
X1356350Y363133D01*
X1356058Y363008D01*
X1355017D01*
G01X1356058D02*
X1356683Y361800D01*
G01X1358950Y364300D02*
Y361800D01*
G01X1357992Y364300D02*
X1359908D01*
G01X1362550Y361800D02*
Y364300D01*
X1361008Y362508D01*
X1363092D01*
G01X1365150Y361800D02*
X1365442Y361842D01*
X1365775Y361967D01*
X1365983Y362175D01*
X1366067Y362467D01*
X1365983Y362758D01*
X1365733Y363008D01*
X1365358Y363133D01*
X1364942D01*
X1364692Y363217D01*
X1364483Y363425D01*
X1364400Y363717D01*
X1364525Y364008D01*
X1364817Y364217D01*
X1365150Y364300D01*
X1365483Y364217D01*
X1365775Y364008D01*
X1365900Y363717D01*
X1365817Y363425D01*
X1365608Y363217D01*
X1365358Y363133D01*
X1364942D01*
X1364567Y363008D01*
X1364317Y362758D01*
X1364233Y362467D01*
X1364317Y362175D01*
X1364525Y361967D01*
X1364858Y361842D01*
X1365150Y361800D01*
G01X1377641Y414771D02*
X1399641D01*
Y397071D01*
X1377641D01*
Y414771D01*
G01X1374633Y366667D02*
X1372967D01*
Y369167D01*
X1374633D01*
G01X1373967Y367959D02*
X1372967D01*
G01X1375983Y369167D02*
Y367375D01*
X1376150Y367000D01*
X1376483Y366750D01*
X1376900Y366667D01*
X1377317Y366750D01*
X1377650Y367000D01*
X1377817Y367375D01*
Y369167D01*
G01X1379917Y366667D02*
X1380000Y367209D01*
X1380125Y367667D01*
X1380292Y368084D01*
X1380500Y368542D01*
X1380833Y369167D01*
X1379167D01*
G01X1384017Y368959D02*
X1383767Y369084D01*
X1383475Y369167D01*
X1383142D01*
X1382767Y369042D01*
X1382475Y368834D01*
X1382267Y368584D01*
X1382100Y368167D01*
X1382058Y367792D01*
X1382142Y367417D01*
X1382267Y367167D01*
X1382517Y366917D01*
X1382808Y366750D01*
X1383100Y366667D01*
X1383392D01*
X1383683Y366750D01*
X1383933Y366875D01*
X1384142Y367042D01*
G01X1386200Y366667D02*
Y369167D01*
X1385700Y368667D01*
G01Y366667D02*
X1386700D01*
G01X1352768Y395885D02*
X1380068D01*
Y372335D01*
X1352768D01*
Y395885D01*
G01X1347950Y380950D02*
Y374902D01*
G01X1388282Y422220D02*
Y425320D01*
X1389738D01*
G01X1389202Y423822D02*
X1388282D01*
G01X1391382Y424803D02*
X1391612Y425113D01*
X1391880Y425268D01*
X1392187Y425320D01*
X1392570Y425217D01*
X1392838Y424958D01*
X1392915Y424648D01*
X1392877Y424338D01*
X1392723Y424080D01*
X1391957Y423563D01*
X1391612Y423202D01*
X1391382Y422685D01*
X1391305Y422220D01*
X1392915D01*
G01X1395210Y425320D02*
X1394903Y425217D01*
X1394673Y424958D01*
X1394520Y424648D01*
X1394405Y424235D01*
X1394367Y423770D01*
X1394405Y423305D01*
X1394520Y422892D01*
X1394673Y422582D01*
X1394903Y422323D01*
X1395210Y422220D01*
X1395517Y422323D01*
X1395747Y422582D01*
X1395900Y422892D01*
X1396015Y423305D01*
X1396053Y423770D01*
X1396015Y424235D01*
X1395900Y424648D01*
X1395747Y424958D01*
X1395517Y425217D01*
X1395210Y425320D01*
G01X1355259Y407533D02*
X1355134Y407283D01*
X1355051Y406991D01*
Y406658D01*
X1355176Y406283D01*
X1355384Y405991D01*
X1355634Y405783D01*
X1356051Y405616D01*
X1356426Y405574D01*
X1356801Y405658D01*
X1357051Y405783D01*
X1357301Y406033D01*
X1357468Y406324D01*
X1357551Y406616D01*
Y406908D01*
X1357468Y407199D01*
X1357343Y407449D01*
X1357176Y407658D01*
G01X1357551Y409633D02*
X1357009Y409716D01*
X1356551Y409841D01*
X1356134Y410008D01*
X1355676Y410216D01*
X1355051Y410549D01*
Y408883D01*
G01X1355259Y413733D02*
X1355134Y413483D01*
X1355051Y413191D01*
Y412858D01*
X1355176Y412483D01*
X1355384Y412191D01*
X1355634Y411983D01*
X1356051Y411816D01*
X1356426Y411774D01*
X1356801Y411858D01*
X1357051Y411983D01*
X1357301Y412233D01*
X1357468Y412524D01*
X1357551Y412816D01*
Y413108D01*
X1357468Y413399D01*
X1357343Y413649D01*
X1357176Y413858D01*
G01X1357551Y415916D02*
X1355051D01*
X1355551Y415416D01*
G01X1357551D02*
Y416416D01*
G01Y418933D02*
X1357009Y419016D01*
X1356551Y419141D01*
X1356134Y419308D01*
X1355676Y419516D01*
X1355051Y419849D01*
Y418183D01*
G01X1351606Y407746D02*
X1351481Y407496D01*
X1351398Y407204D01*
Y406871D01*
X1351523Y406496D01*
X1351731Y406204D01*
X1351981Y405996D01*
X1352398Y405829D01*
X1352773Y405787D01*
X1353148Y405871D01*
X1353398Y405996D01*
X1353648Y406246D01*
X1353815Y406537D01*
X1353898Y406829D01*
Y407121D01*
X1353815Y407412D01*
X1353690Y407662D01*
X1353523Y407871D01*
G01X1353898Y409846D02*
X1353356Y409929D01*
X1352898Y410054D01*
X1352481Y410221D01*
X1352023Y410429D01*
X1351398Y410762D01*
Y409096D01*
G01X1351606Y413946D02*
X1351481Y413696D01*
X1351398Y413404D01*
Y413071D01*
X1351523Y412696D01*
X1351731Y412404D01*
X1351981Y412196D01*
X1352398Y412029D01*
X1352773Y411987D01*
X1353148Y412071D01*
X1353398Y412196D01*
X1353648Y412446D01*
X1353815Y412737D01*
X1353898Y413029D01*
Y413321D01*
X1353815Y413612D01*
X1353690Y413862D01*
X1353523Y414071D01*
G01X1353898Y416129D02*
X1351398D01*
X1351898Y415629D01*
G01X1353898D02*
Y416629D01*
G01Y419229D02*
X1353856Y419521D01*
X1353731Y419854D01*
X1353523Y420062D01*
X1353231Y420146D01*
X1352940Y420062D01*
X1352690Y419812D01*
X1352565Y419437D01*
Y419021D01*
X1352481Y418771D01*
X1352273Y418562D01*
X1351981Y418479D01*
X1351690Y418604D01*
X1351481Y418896D01*
X1351398Y419229D01*
X1351481Y419562D01*
X1351690Y419854D01*
X1351981Y419979D01*
X1352273Y419896D01*
X1352481Y419687D01*
X1352565Y419437D01*
Y419021D01*
X1352690Y418646D01*
X1352940Y418396D01*
X1353231Y418312D01*
X1353523Y418396D01*
X1353731Y418604D01*
X1353856Y418937D01*
X1353898Y419229D01*
G01X1346917Y462659D02*
X1346667Y462784D01*
X1346375Y462867D01*
X1346042D01*
X1345667Y462742D01*
X1345375Y462534D01*
X1345167Y462284D01*
X1345000Y461867D01*
X1344958Y461492D01*
X1345042Y461117D01*
X1345167Y460867D01*
X1345417Y460617D01*
X1345708Y460450D01*
X1346000Y460367D01*
X1346292D01*
X1346583Y460450D01*
X1346833Y460575D01*
X1347042Y460742D01*
G01X1348308Y461409D02*
X1348600Y461700D01*
X1348850Y461867D01*
X1349183Y461950D01*
X1349475Y461867D01*
X1349683Y461700D01*
X1349850Y461450D01*
X1349892Y461159D01*
X1349850Y460909D01*
X1349683Y460659D01*
X1349433Y460450D01*
X1349142Y460367D01*
X1348808Y460450D01*
X1348517Y460700D01*
X1348350Y461075D01*
X1348308Y461492D01*
X1348392Y462034D01*
X1348517Y462325D01*
X1348725Y462617D01*
X1349017Y462825D01*
X1349308Y462867D01*
X1349600Y462784D01*
X1349808Y462575D01*
G01X1352533Y461700D02*
X1352700Y461825D01*
X1352825Y462034D01*
X1352908Y462325D01*
X1352825Y462575D01*
X1352658Y462742D01*
X1352367Y462867D01*
X1351242D01*
Y460367D01*
X1352617D01*
X1352908Y460534D01*
X1353075Y460784D01*
X1353158Y461075D01*
X1353075Y461367D01*
X1352825Y461617D01*
X1352533Y461700D01*
X1351242D01*
G01X1355300Y460367D02*
Y462867D01*
X1354800Y462367D01*
G01Y460367D02*
X1355800D01*
G01X1358400D02*
X1358692Y460409D01*
X1359025Y460534D01*
X1359233Y460742D01*
X1359317Y461034D01*
X1359233Y461325D01*
X1358983Y461575D01*
X1358608Y461700D01*
X1358192D01*
X1357942Y461784D01*
X1357733Y461992D01*
X1357650Y462284D01*
X1357775Y462575D01*
X1358067Y462784D01*
X1358400Y462867D01*
X1358733Y462784D01*
X1359025Y462575D01*
X1359150Y462284D01*
X1359067Y461992D01*
X1358858Y461784D01*
X1358608Y461700D01*
X1358192D01*
X1357817Y461575D01*
X1357567Y461325D01*
X1357483Y461034D01*
X1357567Y460742D01*
X1357775Y460534D01*
X1358108Y460409D01*
X1358400Y460367D01*
G01X1370576Y424543D02*
X1370326Y424668D01*
X1370034Y424751D01*
X1369701D01*
X1369326Y424626D01*
X1369034Y424418D01*
X1368826Y424168D01*
X1368659Y423751D01*
X1368617Y423376D01*
X1368701Y423001D01*
X1368826Y422751D01*
X1369076Y422501D01*
X1369367Y422334D01*
X1369659Y422251D01*
X1369951D01*
X1370242Y422334D01*
X1370492Y422459D01*
X1370701Y422626D01*
G01X1371967Y424334D02*
X1372217Y424584D01*
X1372509Y424709D01*
X1372842Y424751D01*
X1373259Y424668D01*
X1373551Y424459D01*
X1373634Y424209D01*
X1373592Y423959D01*
X1373426Y423751D01*
X1372592Y423334D01*
X1372217Y423043D01*
X1371967Y422626D01*
X1371884Y422251D01*
X1373634D01*
G01X1375067Y424334D02*
X1375317Y424584D01*
X1375609Y424709D01*
X1375942Y424751D01*
X1376359Y424668D01*
X1376651Y424459D01*
X1376734Y424209D01*
X1376692Y423959D01*
X1376526Y423751D01*
X1375692Y423334D01*
X1375317Y423043D01*
X1375067Y422626D01*
X1374984Y422251D01*
X1376734D01*
G01X1377709Y424751D02*
X1378292Y422251D01*
X1378959Y424751D01*
X1379626Y422251D01*
X1380209Y424751D01*
G01X1381267Y424334D02*
X1381517Y424584D01*
X1381809Y424709D01*
X1382142Y424751D01*
X1382559Y424668D01*
X1382851Y424459D01*
X1382934Y424209D01*
X1382892Y423959D01*
X1382726Y423751D01*
X1381892Y423334D01*
X1381517Y423043D01*
X1381267Y422626D01*
X1381184Y422251D01*
X1382934D01*
G01X1385159D02*
X1385451Y422293D01*
X1385784Y422418D01*
X1385992Y422626D01*
X1386076Y422918D01*
X1385992Y423209D01*
X1385742Y423459D01*
X1385367Y423584D01*
X1384951D01*
X1384701Y423668D01*
X1384492Y423876D01*
X1384409Y424168D01*
X1384534Y424459D01*
X1384826Y424668D01*
X1385159Y424751D01*
X1385492Y424668D01*
X1385784Y424459D01*
X1385909Y424168D01*
X1385826Y423876D01*
X1385617Y423668D01*
X1385367Y423584D01*
X1384951D01*
X1384576Y423459D01*
X1384326Y423209D01*
X1384242Y422918D01*
X1384326Y422626D01*
X1384534Y422418D01*
X1384867Y422293D01*
X1385159Y422251D01*
G01X1356848Y424402D02*
X1356598Y424527D01*
X1356306Y424610D01*
X1355973D01*
X1355598Y424485D01*
X1355306Y424277D01*
X1355098Y424027D01*
X1354931Y423610D01*
X1354889Y423235D01*
X1354973Y422860D01*
X1355098Y422610D01*
X1355348Y422360D01*
X1355639Y422193D01*
X1355931Y422110D01*
X1356223D01*
X1356514Y422193D01*
X1356764Y422318D01*
X1356973Y422485D01*
G01X1358948Y422110D02*
X1359031Y422652D01*
X1359156Y423110D01*
X1359323Y423527D01*
X1359531Y423985D01*
X1359864Y424610D01*
X1358198D01*
G01X1363048Y424402D02*
X1362798Y424527D01*
X1362506Y424610D01*
X1362173D01*
X1361798Y424485D01*
X1361506Y424277D01*
X1361298Y424027D01*
X1361131Y423610D01*
X1361089Y423235D01*
X1361173Y422860D01*
X1361298Y422610D01*
X1361548Y422360D01*
X1361839Y422193D01*
X1362131Y422110D01*
X1362423D01*
X1362714Y422193D01*
X1362964Y422318D01*
X1363173Y422485D01*
G01X1365148Y422110D02*
X1365231Y422652D01*
X1365356Y423110D01*
X1365523Y423527D01*
X1365731Y423985D01*
X1366064Y424610D01*
X1364398D01*
G01X1382083Y418964D02*
Y416464D01*
X1383749D01*
G01X1385933D02*
X1386016Y417006D01*
X1386141Y417464D01*
X1386308Y417881D01*
X1386516Y418339D01*
X1386849Y418964D01*
X1385183D01*
G01X1390033Y418756D02*
X1389783Y418881D01*
X1389491Y418964D01*
X1389158D01*
X1388783Y418839D01*
X1388491Y418631D01*
X1388283Y418381D01*
X1388116Y417964D01*
X1388074Y417589D01*
X1388158Y417214D01*
X1388283Y416964D01*
X1388533Y416714D01*
X1388824Y416547D01*
X1389116Y416464D01*
X1389408D01*
X1389699Y416547D01*
X1389949Y416672D01*
X1390158Y416839D01*
G01X1392216Y416464D02*
Y418964D01*
X1391716Y418464D01*
G01Y416464D02*
X1392716D01*
G01X1375922Y497117D02*
X1375797Y496867D01*
X1375714Y496575D01*
Y496242D01*
X1375839Y495867D01*
X1376047Y495575D01*
X1376297Y495367D01*
X1376714Y495200D01*
X1377089Y495158D01*
X1377464Y495242D01*
X1377714Y495367D01*
X1377964Y495617D01*
X1378131Y495908D01*
X1378214Y496200D01*
Y496492D01*
X1378131Y496783D01*
X1378006Y497033D01*
X1377839Y497242D01*
G01X1378214Y499217D02*
X1377672Y499300D01*
X1377214Y499425D01*
X1376797Y499592D01*
X1376339Y499800D01*
X1375714Y500133D01*
Y498467D01*
G01X1376881Y502733D02*
X1376756Y502900D01*
X1376547Y503025D01*
X1376256Y503108D01*
X1376006Y503025D01*
X1375839Y502858D01*
X1375714Y502567D01*
Y501442D01*
X1378214D01*
Y502817D01*
X1378047Y503108D01*
X1377797Y503275D01*
X1377506Y503358D01*
X1377214Y503275D01*
X1376964Y503025D01*
X1376881Y502733D01*
Y501442D01*
G01X1377839Y504583D02*
X1378047Y504833D01*
X1378172Y505125D01*
X1378214Y505500D01*
X1378131Y505875D01*
X1377964Y506167D01*
X1377672Y506375D01*
X1377339Y506417D01*
X1377006Y506333D01*
X1376797Y506125D01*
X1376631Y505833D01*
X1376589Y505542D01*
X1376631Y505250D01*
X1376797Y504875D01*
X1375714Y505000D01*
Y506125D01*
G01X1360750Y483967D02*
X1358250D01*
Y485008D01*
X1358375Y485342D01*
X1358542Y485550D01*
X1358875Y485633D01*
X1359208Y485550D01*
X1359417Y485300D01*
X1359542Y485008D01*
Y483967D01*
G01Y485008D02*
X1360750Y485633D01*
G01Y487817D02*
X1360208Y487900D01*
X1359750Y488025D01*
X1359333Y488192D01*
X1358875Y488400D01*
X1358250Y488733D01*
Y487067D01*
G01X1359417Y491333D02*
X1359292Y491500D01*
X1359083Y491625D01*
X1358792Y491708D01*
X1358542Y491625D01*
X1358375Y491458D01*
X1358250Y491167D01*
Y490042D01*
X1360750D01*
Y491417D01*
X1360583Y491708D01*
X1360333Y491875D01*
X1360042Y491958D01*
X1359750Y491875D01*
X1359500Y491625D01*
X1359417Y491333D01*
Y490042D01*
G01X1360750Y494100D02*
X1358250D01*
X1358750Y493600D01*
G01X1360750D02*
Y494600D01*
G01Y497700D02*
X1358250D01*
X1360042Y496158D01*
Y498242D01*
G01X1398533Y488367D02*
X1396033D01*
Y489408D01*
X1396158Y489742D01*
X1396325Y489950D01*
X1396658Y490033D01*
X1396991Y489950D01*
X1397200Y489700D01*
X1397325Y489408D01*
Y488367D01*
G01Y489408D02*
X1398533Y490033D01*
G01Y492217D02*
X1397991Y492300D01*
X1397533Y492425D01*
X1397116Y492592D01*
X1396658Y492800D01*
X1396033Y493133D01*
Y491467D01*
G01X1397200Y495733D02*
X1397075Y495900D01*
X1396866Y496025D01*
X1396575Y496108D01*
X1396325Y496025D01*
X1396158Y495858D01*
X1396033Y495567D01*
Y494442D01*
X1398533D01*
Y495817D01*
X1398366Y496108D01*
X1398116Y496275D01*
X1397825Y496358D01*
X1397533Y496275D01*
X1397283Y496025D01*
X1397200Y495733D01*
Y494442D01*
G01X1398533Y498500D02*
X1396033D01*
X1396533Y498000D01*
G01X1398533D02*
Y499000D01*
G01Y501517D02*
X1397991Y501600D01*
X1397533Y501725D01*
X1397116Y501892D01*
X1396658Y502100D01*
X1396033Y502433D01*
Y500767D01*
G01X1394133Y488467D02*
X1391633D01*
Y489508D01*
X1391758Y489842D01*
X1391925Y490050D01*
X1392258Y490133D01*
X1392591Y490050D01*
X1392800Y489800D01*
X1392925Y489508D01*
Y488467D01*
G01Y489508D02*
X1394133Y490133D01*
G01Y492317D02*
X1393591Y492400D01*
X1393133Y492525D01*
X1392716Y492692D01*
X1392258Y492900D01*
X1391633Y493233D01*
Y491567D01*
G01X1392800Y495833D02*
X1392675Y496000D01*
X1392466Y496125D01*
X1392175Y496208D01*
X1391925Y496125D01*
X1391758Y495958D01*
X1391633Y495667D01*
Y494542D01*
X1394133D01*
Y495917D01*
X1393966Y496208D01*
X1393716Y496375D01*
X1393425Y496458D01*
X1393133Y496375D01*
X1392883Y496125D01*
X1392800Y495833D01*
Y494542D01*
G01X1394133Y498600D02*
X1391633D01*
X1392133Y498100D01*
G01X1394133D02*
Y499100D01*
G01X1392050Y500908D02*
X1391800Y501158D01*
X1391675Y501450D01*
X1391633Y501783D01*
X1391716Y502200D01*
X1391925Y502492D01*
X1392175Y502575D01*
X1392425Y502533D01*
X1392633Y502367D01*
X1393050Y501533D01*
X1393341Y501158D01*
X1393758Y500908D01*
X1394133Y500825D01*
Y502575D01*
G01X1344817Y496292D02*
X1344567Y496417D01*
X1344275Y496500D01*
X1343942D01*
X1343567Y496375D01*
X1343275Y496167D01*
X1343067Y495917D01*
X1342900Y495500D01*
X1342858Y495125D01*
X1342942Y494750D01*
X1343067Y494500D01*
X1343317Y494250D01*
X1343608Y494083D01*
X1343900Y494000D01*
X1344192D01*
X1344483Y494083D01*
X1344733Y494208D01*
X1344942Y494375D01*
G01X1346917Y494000D02*
X1347000Y494542D01*
X1347125Y495000D01*
X1347292Y495417D01*
X1347500Y495875D01*
X1347833Y496500D01*
X1346167D01*
G01X1350433Y495333D02*
X1350600Y495458D01*
X1350725Y495667D01*
X1350808Y495958D01*
X1350725Y496208D01*
X1350558Y496375D01*
X1350267Y496500D01*
X1349142D01*
Y494000D01*
X1350517D01*
X1350808Y494167D01*
X1350975Y494417D01*
X1351058Y494708D01*
X1350975Y495000D01*
X1350725Y495250D01*
X1350433Y495333D01*
X1349142D01*
G01X1353200Y494000D02*
Y496500D01*
X1352700Y496000D01*
G01Y494000D02*
X1353700D01*
G01X1356300Y496500D02*
X1355967Y496417D01*
X1355717Y496208D01*
X1355550Y495958D01*
X1355425Y495625D01*
X1355383Y495250D01*
X1355425Y494875D01*
X1355550Y494542D01*
X1355717Y494292D01*
X1355967Y494083D01*
X1356300Y494000D01*
X1356633Y494083D01*
X1356883Y494292D01*
X1357050Y494542D01*
X1357175Y494875D01*
X1357217Y495250D01*
X1357175Y495625D01*
X1357050Y495958D01*
X1356883Y496208D01*
X1356633Y496417D01*
X1356300Y496500D01*
G01X1357617Y506092D02*
X1357367Y506217D01*
X1357075Y506300D01*
X1356742D01*
X1356367Y506175D01*
X1356075Y505967D01*
X1355867Y505717D01*
X1355700Y505300D01*
X1355658Y504925D01*
X1355742Y504550D01*
X1355867Y504300D01*
X1356117Y504050D01*
X1356408Y503883D01*
X1356700Y503800D01*
X1356992D01*
X1357283Y503883D01*
X1357533Y504008D01*
X1357742Y504175D01*
G01X1359717Y503800D02*
X1359800Y504342D01*
X1359925Y504800D01*
X1360092Y505217D01*
X1360300Y505675D01*
X1360633Y506300D01*
X1358967D01*
G01X1363233Y505133D02*
X1363400Y505258D01*
X1363525Y505467D01*
X1363608Y505758D01*
X1363525Y506008D01*
X1363358Y506175D01*
X1363067Y506300D01*
X1361942D01*
Y503800D01*
X1363317D01*
X1363608Y503967D01*
X1363775Y504217D01*
X1363858Y504508D01*
X1363775Y504800D01*
X1363525Y505050D01*
X1363233Y505133D01*
X1361942D01*
G01X1366000Y503800D02*
Y506300D01*
X1365500Y505800D01*
G01Y503800D02*
X1366500D01*
G01X1368308Y505883D02*
X1368558Y506133D01*
X1368850Y506258D01*
X1369183Y506300D01*
X1369600Y506217D01*
X1369892Y506008D01*
X1369975Y505758D01*
X1369933Y505508D01*
X1369767Y505300D01*
X1368933Y504883D01*
X1368558Y504592D01*
X1368308Y504175D01*
X1368225Y503800D01*
X1369975D01*
G01X1347617Y470059D02*
X1347367Y470184D01*
X1347075Y470267D01*
X1346742D01*
X1346367Y470142D01*
X1346075Y469934D01*
X1345867Y469684D01*
X1345700Y469267D01*
X1345658Y468892D01*
X1345742Y468517D01*
X1345867Y468267D01*
X1346117Y468017D01*
X1346408Y467850D01*
X1346700Y467767D01*
X1346992D01*
X1347283Y467850D01*
X1347533Y467975D01*
X1347742Y468142D01*
G01X1349008Y468809D02*
X1349300Y469100D01*
X1349550Y469267D01*
X1349883Y469350D01*
X1350175Y469267D01*
X1350383Y469100D01*
X1350550Y468850D01*
X1350592Y468559D01*
X1350550Y468309D01*
X1350383Y468059D01*
X1350133Y467850D01*
X1349842Y467767D01*
X1349508Y467850D01*
X1349217Y468100D01*
X1349050Y468475D01*
X1349008Y468892D01*
X1349092Y469434D01*
X1349217Y469725D01*
X1349425Y470017D01*
X1349717Y470225D01*
X1350008Y470267D01*
X1350300Y470184D01*
X1350508Y469975D01*
G01X1353233Y469100D02*
X1353400Y469225D01*
X1353525Y469434D01*
X1353608Y469725D01*
X1353525Y469975D01*
X1353358Y470142D01*
X1353067Y470267D01*
X1351942D01*
Y467767D01*
X1353317D01*
X1353608Y467934D01*
X1353775Y468184D01*
X1353858Y468475D01*
X1353775Y468767D01*
X1353525Y469017D01*
X1353233Y469100D01*
X1351942D01*
G01X1356000Y467767D02*
Y470267D01*
X1355500Y469767D01*
G01Y467767D02*
X1356500D01*
G01X1359017D02*
X1359100Y468309D01*
X1359225Y468767D01*
X1359392Y469184D01*
X1359600Y469642D01*
X1359933Y470267D01*
X1358267D01*
G01X1399161Y510601D02*
X1399036Y510351D01*
X1398953Y510059D01*
Y509726D01*
X1399078Y509351D01*
X1399286Y509059D01*
X1399536Y508851D01*
X1399953Y508684D01*
X1400328Y508642D01*
X1400703Y508726D01*
X1400953Y508851D01*
X1401203Y509101D01*
X1401370Y509392D01*
X1401453Y509684D01*
Y509976D01*
X1401370Y510267D01*
X1401245Y510517D01*
X1401078Y510726D01*
G01X1401453Y512784D02*
X1398953D01*
X1399453Y512284D01*
G01X1401453D02*
Y513284D01*
G01X1399370Y515092D02*
X1399120Y515342D01*
X1398995Y515634D01*
X1398953Y515967D01*
X1399036Y516384D01*
X1399245Y516676D01*
X1399495Y516759D01*
X1399745Y516717D01*
X1399953Y516551D01*
X1400370Y515717D01*
X1400661Y515342D01*
X1401078Y515092D01*
X1401453Y515009D01*
Y516759D01*
G01X1398953Y517734D02*
X1401453Y518317D01*
X1398953Y518984D01*
X1401453Y519651D01*
X1398953Y520234D01*
G01X1399370Y521292D02*
X1399120Y521542D01*
X1398995Y521834D01*
X1398953Y522167D01*
X1399036Y522584D01*
X1399245Y522876D01*
X1399495Y522959D01*
X1399745Y522917D01*
X1399953Y522751D01*
X1400370Y521917D01*
X1400661Y521542D01*
X1401078Y521292D01*
X1401453Y521209D01*
Y522959D01*
G01X1381794Y493718D02*
X1379294D01*
Y495302D01*
G01X1380502Y494718D02*
Y493718D01*
G01X1380461Y497943D02*
X1380336Y498110D01*
X1380127Y498235D01*
X1379836Y498318D01*
X1379586Y498235D01*
X1379419Y498068D01*
X1379294Y497777D01*
Y496652D01*
X1381794D01*
Y498027D01*
X1381627Y498318D01*
X1381377Y498485D01*
X1381086Y498568D01*
X1380794Y498485D01*
X1380544Y498235D01*
X1380461Y497943D01*
Y496652D01*
G01X1381794Y500627D02*
X1381252Y500710D01*
X1380794Y500835D01*
X1380377Y501002D01*
X1379919Y501210D01*
X1379294Y501543D01*
Y499877D01*
G01X1380461Y504143D02*
X1380336Y504310D01*
X1380127Y504435D01*
X1379836Y504518D01*
X1379586Y504435D01*
X1379419Y504268D01*
X1379294Y503977D01*
Y502852D01*
X1381794D01*
Y504227D01*
X1381627Y504518D01*
X1381377Y504685D01*
X1381086Y504768D01*
X1380794Y504685D01*
X1380544Y504435D01*
X1380461Y504143D01*
Y502852D01*
G01X1381794Y506910D02*
X1379294D01*
X1379794Y506410D01*
G01X1381794D02*
Y507410D01*
G01X1395953Y511651D02*
X1393453D01*
Y512692D01*
X1393578Y513026D01*
X1393745Y513234D01*
X1394078Y513317D01*
X1394411Y513234D01*
X1394620Y512984D01*
X1394745Y512692D01*
Y511651D01*
G01Y512692D02*
X1395953Y513317D01*
G01Y515584D02*
X1393453D01*
X1393953Y515084D01*
G01X1395953D02*
Y516084D01*
G01X1393870Y517892D02*
X1393620Y518142D01*
X1393495Y518434D01*
X1393453Y518767D01*
X1393536Y519184D01*
X1393745Y519476D01*
X1393995Y519559D01*
X1394245Y519517D01*
X1394453Y519351D01*
X1394870Y518517D01*
X1395161Y518142D01*
X1395578Y517892D01*
X1395953Y517809D01*
Y519559D01*
G01X1393453Y520534D02*
X1395953Y521117D01*
X1393453Y521784D01*
X1395953Y522451D01*
X1393453Y523034D01*
G01X1395953Y524884D02*
X1393453D01*
X1393953Y524384D01*
G01X1395953D02*
Y525384D01*
G01X1393453Y527984D02*
X1393536Y527651D01*
X1393745Y527401D01*
X1393995Y527234D01*
X1394328Y527109D01*
X1394703Y527067D01*
X1395078Y527109D01*
X1395411Y527234D01*
X1395661Y527401D01*
X1395870Y527651D01*
X1395953Y527984D01*
X1395870Y528317D01*
X1395661Y528567D01*
X1395411Y528734D01*
X1395078Y528859D01*
X1394703Y528901D01*
X1394328Y528859D01*
X1393995Y528734D01*
X1393745Y528567D01*
X1393536Y528317D01*
X1393453Y527984D01*
G01X1371767Y492459D02*
X1371517Y492584D01*
X1371225Y492667D01*
X1370892D01*
X1370517Y492542D01*
X1370225Y492334D01*
X1370017Y492084D01*
X1369850Y491667D01*
X1369808Y491292D01*
X1369892Y490917D01*
X1370017Y490667D01*
X1370267Y490417D01*
X1370558Y490250D01*
X1370850Y490167D01*
X1371142D01*
X1371433Y490250D01*
X1371683Y490375D01*
X1371892Y490542D01*
G01X1373867Y490167D02*
X1373950Y490709D01*
X1374075Y491167D01*
X1374242Y491584D01*
X1374450Y492042D01*
X1374783Y492667D01*
X1373117D01*
G01X1377383Y491500D02*
X1377550Y491625D01*
X1377675Y491834D01*
X1377758Y492125D01*
X1377675Y492375D01*
X1377508Y492542D01*
X1377217Y492667D01*
X1376092D01*
Y490167D01*
X1377467D01*
X1377758Y490334D01*
X1377925Y490584D01*
X1378008Y490875D01*
X1377925Y491167D01*
X1377675Y491417D01*
X1377383Y491500D01*
X1376092D01*
G01X1380150Y490167D02*
X1380442Y490209D01*
X1380775Y490334D01*
X1380983Y490542D01*
X1381067Y490834D01*
X1380983Y491125D01*
X1380733Y491375D01*
X1380358Y491500D01*
X1379942D01*
X1379692Y491584D01*
X1379483Y491792D01*
X1379400Y492084D01*
X1379525Y492375D01*
X1379817Y492584D01*
X1380150Y492667D01*
X1380483Y492584D01*
X1380775Y492375D01*
X1380900Y492084D01*
X1380817Y491792D01*
X1380608Y491584D01*
X1380358Y491500D01*
X1379942D01*
X1379567Y491375D01*
X1379317Y491125D01*
X1379233Y490834D01*
X1379317Y490542D01*
X1379525Y490334D01*
X1379858Y490209D01*
X1380150Y490167D01*
G01X1372834Y510033D02*
Y508367D01*
X1370334D01*
Y510033D01*
G01X1371542Y509367D02*
Y508367D01*
G01X1370334Y511383D02*
X1372126D01*
X1372501Y511550D01*
X1372751Y511883D01*
X1372834Y512300D01*
X1372751Y512717D01*
X1372501Y513050D01*
X1372126Y513217D01*
X1370334D01*
G01X1372834Y515317D02*
X1372292Y515400D01*
X1371834Y515525D01*
X1371417Y515692D01*
X1370959Y515900D01*
X1370334Y516233D01*
Y514567D01*
G01X1371501Y518833D02*
X1371376Y519000D01*
X1371167Y519125D01*
X1370876Y519208D01*
X1370626Y519125D01*
X1370459Y518958D01*
X1370334Y518667D01*
Y517542D01*
X1372834D01*
Y518917D01*
X1372667Y519208D01*
X1372417Y519375D01*
X1372126Y519458D01*
X1371834Y519375D01*
X1371584Y519125D01*
X1371501Y518833D01*
Y517542D01*
G01X1372834Y521600D02*
X1370334D01*
X1370834Y521100D01*
G01X1372834D02*
Y522100D01*
G01X1366705Y511641D02*
Y510845D01*
X1365907D01*
G01X1343079D02*
X1342295D01*
Y511641D01*
G01X1353600Y614500D02*
Y586500D01*
X1357200D01*
G01X1393880Y575637D02*
X1391380D01*
Y576678D01*
X1391505Y577012D01*
X1391672Y577220D01*
X1392005Y577303D01*
X1392338Y577220D01*
X1392547Y576970D01*
X1392672Y576678D01*
Y575637D01*
G01Y576678D02*
X1393880Y577303D01*
G01Y579487D02*
X1393338Y579570D01*
X1392880Y579695D01*
X1392463Y579862D01*
X1392005Y580070D01*
X1391380Y580403D01*
Y578737D01*
G01X1393880Y581628D02*
X1391380Y582670D01*
X1393880Y583712D01*
G01X1393005Y583337D02*
Y582003D01*
G01X1391797Y584978D02*
X1391547Y585228D01*
X1391422Y585520D01*
X1391380Y585853D01*
X1391463Y586270D01*
X1391672Y586562D01*
X1391922Y586645D01*
X1392172Y586603D01*
X1392380Y586437D01*
X1392797Y585603D01*
X1393088Y585228D01*
X1393505Y584978D01*
X1393880Y584895D01*
Y586645D01*
G01Y588870D02*
X1391380D01*
X1391880Y588370D01*
G01X1393880D02*
Y589370D01*
G01X1358967Y543967D02*
Y546467D01*
X1360008D01*
X1360342Y546342D01*
X1360550Y546175D01*
X1360633Y545842D01*
X1360550Y545509D01*
X1360300Y545300D01*
X1360008Y545175D01*
X1358967D01*
G01X1360008D02*
X1360633Y543967D01*
G01X1362817D02*
X1362900Y544509D01*
X1363025Y544967D01*
X1363192Y545384D01*
X1363400Y545842D01*
X1363733Y546467D01*
X1362067D01*
G01X1364958Y543967D02*
X1366000Y546467D01*
X1367042Y543967D01*
G01X1366667Y544842D02*
X1365333D01*
G01X1369100Y543967D02*
Y546467D01*
X1368600Y545967D01*
G01Y543967D02*
X1369600D01*
G01X1371283Y544342D02*
X1371533Y544134D01*
X1371825Y544009D01*
X1372200Y543967D01*
X1372575Y544050D01*
X1372867Y544217D01*
X1373075Y544509D01*
X1373117Y544842D01*
X1373033Y545175D01*
X1372825Y545384D01*
X1372533Y545550D01*
X1372242Y545592D01*
X1371950Y545550D01*
X1371575Y545384D01*
X1371700Y546467D01*
X1372825D01*
G01X1374667Y542766D02*
Y545266D01*
X1375708D01*
X1376042Y545141D01*
X1376250Y544974D01*
X1376333Y544641D01*
X1376250Y544308D01*
X1376000Y544099D01*
X1375708Y543974D01*
X1374667D01*
G01X1375708D02*
X1376333Y542766D01*
G01X1378517D02*
X1378600Y543308D01*
X1378725Y543766D01*
X1378892Y544183D01*
X1379100Y544641D01*
X1379433Y545266D01*
X1377767D01*
G01X1380658Y542766D02*
X1381700Y545266D01*
X1382742Y542766D01*
G01X1382367Y543641D02*
X1381033D01*
G01X1384800Y542766D02*
Y545266D01*
X1384300Y544766D01*
G01Y542766D02*
X1385300D01*
G01X1387900Y545266D02*
X1387567Y545183D01*
X1387317Y544974D01*
X1387150Y544724D01*
X1387025Y544391D01*
X1386983Y544016D01*
X1387025Y543641D01*
X1387150Y543308D01*
X1387317Y543058D01*
X1387567Y542849D01*
X1387900Y542766D01*
X1388233Y542849D01*
X1388483Y543058D01*
X1388650Y543308D01*
X1388775Y543641D01*
X1388817Y544016D01*
X1388775Y544391D01*
X1388650Y544724D01*
X1388483Y544974D01*
X1388233Y545183D01*
X1387900Y545266D01*
G01X1387517Y553666D02*
Y556166D01*
X1388558D01*
X1388892Y556041D01*
X1389100Y555874D01*
X1389183Y555541D01*
X1389100Y555208D01*
X1388850Y554999D01*
X1388558Y554874D01*
X1387517D01*
G01X1388558D02*
X1389183Y553666D01*
G01X1391367D02*
X1391450Y554208D01*
X1391575Y554666D01*
X1391742Y555083D01*
X1391950Y555541D01*
X1392283Y556166D01*
X1390617D01*
G01X1393508Y553666D02*
X1394550Y556166D01*
X1395592Y553666D01*
G01X1395217Y554541D02*
X1393883D01*
G01X1397650Y553666D02*
X1397942Y553708D01*
X1398275Y553833D01*
X1398483Y554041D01*
X1398567Y554333D01*
X1398483Y554624D01*
X1398233Y554874D01*
X1397858Y554999D01*
X1397442D01*
X1397192Y555083D01*
X1396983Y555291D01*
X1396900Y555583D01*
X1397025Y555874D01*
X1397317Y556083D01*
X1397650Y556166D01*
X1397983Y556083D01*
X1398275Y555874D01*
X1398400Y555583D01*
X1398317Y555291D01*
X1398108Y555083D01*
X1397858Y554999D01*
X1397442D01*
X1397067Y554874D01*
X1396817Y554624D01*
X1396733Y554333D01*
X1396817Y554041D01*
X1397025Y553833D01*
X1397358Y553708D01*
X1397650Y553666D01*
G01X1382786Y571048D02*
Y573548D01*
X1383827D01*
X1384161Y573423D01*
X1384369Y573256D01*
X1384452Y572923D01*
X1384369Y572590D01*
X1384119Y572381D01*
X1383827Y572256D01*
X1382786D01*
G01X1383827D02*
X1384452Y571048D01*
G01X1386719Y573548D02*
Y571048D01*
G01X1385761Y573548D02*
X1387677D01*
G01X1388902Y571548D02*
X1389152Y571256D01*
X1389486Y571090D01*
X1389861Y571048D01*
X1390194Y571090D01*
X1390527Y571298D01*
X1390736Y571548D01*
X1390777Y571798D01*
X1390694Y572090D01*
X1390402Y572298D01*
X1390111Y572381D01*
X1389736D01*
G01X1390111D02*
X1390361Y572506D01*
X1390569Y572715D01*
X1390652Y572965D01*
X1390569Y573215D01*
X1390361Y573423D01*
X1389986Y573548D01*
X1389611Y573506D01*
X1389236Y573340D01*
G01X1392919Y571048D02*
Y573548D01*
X1392419Y573048D01*
G01Y571048D02*
X1393419D01*
G01X1346343Y557843D02*
X1346218Y557593D01*
X1346135Y557301D01*
Y556968D01*
X1346260Y556593D01*
X1346468Y556301D01*
X1346718Y556093D01*
X1347135Y555926D01*
X1347510Y555884D01*
X1347885Y555968D01*
X1348135Y556093D01*
X1348385Y556343D01*
X1348552Y556634D01*
X1348635Y556926D01*
Y557218D01*
X1348552Y557509D01*
X1348427Y557759D01*
X1348260Y557968D01*
G01X1346135Y560026D02*
X1348635D01*
G01X1346135Y559068D02*
Y560984D01*
G01X1348635Y563626D02*
X1346135D01*
X1347927Y562084D01*
Y564168D01*
G01X1348635Y566143D02*
X1348093Y566226D01*
X1347635Y566351D01*
X1347218Y566518D01*
X1346760Y566726D01*
X1346135Y567059D01*
Y565393D01*
G01X1362817Y551258D02*
X1362567Y551383D01*
X1362275Y551466D01*
X1361942D01*
X1361567Y551341D01*
X1361275Y551133D01*
X1361067Y550883D01*
X1360900Y550466D01*
X1360858Y550091D01*
X1360942Y549716D01*
X1361067Y549466D01*
X1361317Y549216D01*
X1361608Y549049D01*
X1361900Y548966D01*
X1362192D01*
X1362483Y549049D01*
X1362733Y549174D01*
X1362942Y549341D01*
G01X1364917Y548966D02*
X1365000Y549508D01*
X1365125Y549966D01*
X1365292Y550383D01*
X1365500Y550841D01*
X1365833Y551466D01*
X1364167D01*
G01X1367058Y548966D02*
X1368100Y551466D01*
X1369142Y548966D01*
G01X1368767Y549841D02*
X1367433D01*
G01X1370408Y551049D02*
X1370658Y551299D01*
X1370950Y551424D01*
X1371283Y551466D01*
X1371700Y551383D01*
X1371992Y551174D01*
X1372075Y550924D01*
X1372033Y550674D01*
X1371867Y550466D01*
X1371033Y550049D01*
X1370658Y549758D01*
X1370408Y549341D01*
X1370325Y548966D01*
X1372075D01*
G01X1374300D02*
Y551466D01*
X1373800Y550966D01*
G01Y548966D02*
X1374800D01*
G01X1373596Y556255D02*
X1373346Y556380D01*
X1373054Y556463D01*
X1372721D01*
X1372346Y556338D01*
X1372054Y556130D01*
X1371846Y555880D01*
X1371679Y555463D01*
X1371637Y555088D01*
X1371721Y554713D01*
X1371846Y554463D01*
X1372096Y554213D01*
X1372387Y554046D01*
X1372679Y553963D01*
X1372971D01*
X1373262Y554046D01*
X1373512Y554171D01*
X1373721Y554338D01*
G01X1375696Y553963D02*
X1375779Y554505D01*
X1375904Y554963D01*
X1376071Y555380D01*
X1376279Y555838D01*
X1376612Y556463D01*
X1374946D01*
G01X1377837Y553963D02*
X1378879Y556463D01*
X1379921Y553963D01*
G01X1379546Y554838D02*
X1378212D01*
G01X1381187Y556046D02*
X1381437Y556296D01*
X1381729Y556421D01*
X1382062Y556463D01*
X1382479Y556380D01*
X1382771Y556171D01*
X1382854Y555921D01*
X1382812Y555671D01*
X1382646Y555463D01*
X1381812Y555046D01*
X1381437Y554755D01*
X1381187Y554338D01*
X1381104Y553963D01*
X1382854D01*
G01X1385079Y556463D02*
X1384746Y556380D01*
X1384496Y556171D01*
X1384329Y555921D01*
X1384204Y555588D01*
X1384162Y555213D01*
X1384204Y554838D01*
X1384329Y554505D01*
X1384496Y554255D01*
X1384746Y554046D01*
X1385079Y553963D01*
X1385412Y554046D01*
X1385662Y554255D01*
X1385829Y554505D01*
X1385954Y554838D01*
X1385996Y555213D01*
X1385954Y555588D01*
X1385829Y555921D01*
X1385662Y556171D01*
X1385412Y556380D01*
X1385079Y556463D01*
G01X1370489Y533547D02*
X1370364Y533297D01*
X1370281Y533005D01*
Y532672D01*
X1370406Y532297D01*
X1370614Y532005D01*
X1370864Y531797D01*
X1371281Y531630D01*
X1371656Y531588D01*
X1372031Y531672D01*
X1372281Y531797D01*
X1372531Y532047D01*
X1372698Y532338D01*
X1372781Y532630D01*
Y532922D01*
X1372698Y533213D01*
X1372573Y533463D01*
X1372406Y533672D01*
G01X1372781Y535647D02*
X1372239Y535730D01*
X1371781Y535855D01*
X1371364Y536022D01*
X1370906Y536230D01*
X1370281Y536563D01*
Y534897D01*
G01X1371448Y539163D02*
X1371323Y539330D01*
X1371114Y539455D01*
X1370823Y539538D01*
X1370573Y539455D01*
X1370406Y539288D01*
X1370281Y538997D01*
Y537872D01*
X1372781D01*
Y539247D01*
X1372614Y539538D01*
X1372364Y539705D01*
X1372073Y539788D01*
X1371781Y539705D01*
X1371531Y539455D01*
X1371448Y539163D01*
Y537872D01*
G01X1371739Y541138D02*
X1371448Y541430D01*
X1371281Y541680D01*
X1371198Y542013D01*
X1371281Y542305D01*
X1371448Y542513D01*
X1371698Y542680D01*
X1371989Y542722D01*
X1372239Y542680D01*
X1372489Y542513D01*
X1372698Y542263D01*
X1372781Y541972D01*
X1372698Y541638D01*
X1372448Y541347D01*
X1372073Y541180D01*
X1371656Y541138D01*
X1371114Y541222D01*
X1370823Y541347D01*
X1370531Y541555D01*
X1370323Y541847D01*
X1370281Y542138D01*
X1370364Y542430D01*
X1370573Y542638D01*
G01X1385417Y559392D02*
X1385167Y559517D01*
X1384875Y559600D01*
X1384542D01*
X1384167Y559475D01*
X1383875Y559267D01*
X1383667Y559017D01*
X1383500Y558600D01*
X1383458Y558225D01*
X1383542Y557850D01*
X1383667Y557600D01*
X1383917Y557350D01*
X1384208Y557183D01*
X1384500Y557100D01*
X1384792D01*
X1385083Y557183D01*
X1385333Y557308D01*
X1385542Y557475D01*
G01X1387517Y557100D02*
X1387600Y557642D01*
X1387725Y558100D01*
X1387892Y558517D01*
X1388100Y558975D01*
X1388433Y559600D01*
X1386767D01*
G01X1389658Y557100D02*
X1390700Y559600D01*
X1391742Y557100D01*
G01X1391367Y557975D02*
X1390033D01*
G01X1393008Y559183D02*
X1393258Y559433D01*
X1393550Y559558D01*
X1393883Y559600D01*
X1394300Y559517D01*
X1394592Y559308D01*
X1394675Y559058D01*
X1394633Y558808D01*
X1394467Y558600D01*
X1393633Y558183D01*
X1393258Y557892D01*
X1393008Y557475D01*
X1392925Y557100D01*
X1394675D01*
G01X1396108Y559183D02*
X1396358Y559433D01*
X1396650Y559558D01*
X1396983Y559600D01*
X1397400Y559517D01*
X1397692Y559308D01*
X1397775Y559058D01*
X1397733Y558808D01*
X1397567Y558600D01*
X1396733Y558183D01*
X1396358Y557892D01*
X1396108Y557475D01*
X1396025Y557100D01*
X1397775D01*
G01X1379817Y552558D02*
X1379567Y552683D01*
X1379275Y552766D01*
X1378942D01*
X1378567Y552641D01*
X1378275Y552433D01*
X1378067Y552183D01*
X1377900Y551766D01*
X1377858Y551391D01*
X1377942Y551016D01*
X1378067Y550766D01*
X1378317Y550516D01*
X1378608Y550349D01*
X1378900Y550266D01*
X1379192D01*
X1379483Y550349D01*
X1379733Y550474D01*
X1379942Y550641D01*
G01X1381917Y550266D02*
X1382000Y550808D01*
X1382125Y551266D01*
X1382292Y551683D01*
X1382500Y552141D01*
X1382833Y552766D01*
X1381167D01*
G01X1384058Y550266D02*
X1385100Y552766D01*
X1386142Y550266D01*
G01X1385767Y551141D02*
X1384433D01*
G01X1387408Y552349D02*
X1387658Y552599D01*
X1387950Y552724D01*
X1388283Y552766D01*
X1388700Y552683D01*
X1388992Y552474D01*
X1389075Y552224D01*
X1389033Y551974D01*
X1388867Y551766D01*
X1388033Y551349D01*
X1387658Y551058D01*
X1387408Y550641D01*
X1387325Y550266D01*
X1389075D01*
G01X1390592Y550558D02*
X1390883Y550349D01*
X1391217Y550266D01*
X1391550Y550349D01*
X1391842Y550599D01*
X1392050Y550974D01*
X1392133Y551349D01*
Y551808D01*
X1392050Y552183D01*
X1391842Y552516D01*
X1391592Y552683D01*
X1391300Y552766D01*
X1390967Y552683D01*
X1390717Y552516D01*
X1390550Y552266D01*
X1390467Y551933D01*
X1390550Y551641D01*
X1390758Y551349D01*
X1391008Y551183D01*
X1391300Y551141D01*
X1391633Y551224D01*
X1391883Y551433D01*
X1392133Y551808D01*
G01X1392664Y538952D02*
X1396664D01*
Y546352D01*
G01X1347037Y546698D02*
Y549198D01*
X1348078D01*
X1348412Y549073D01*
X1348620Y548906D01*
X1348703Y548573D01*
X1348620Y548240D01*
X1348370Y548031D01*
X1348078Y547906D01*
X1347037D01*
G01X1348078D02*
X1348703Y546698D01*
G01X1350970Y549198D02*
Y546698D01*
G01X1350012Y549198D02*
X1351928D01*
G01X1353153Y547198D02*
X1353403Y546906D01*
X1353737Y546740D01*
X1354112Y546698D01*
X1354445Y546740D01*
X1354778Y546948D01*
X1354987Y547198D01*
X1355028Y547448D01*
X1354945Y547740D01*
X1354653Y547948D01*
X1354362Y548031D01*
X1353987D01*
G01X1354362D02*
X1354612Y548156D01*
X1354820Y548365D01*
X1354903Y548615D01*
X1354820Y548865D01*
X1354612Y549073D01*
X1354237Y549198D01*
X1353862Y549156D01*
X1353487Y548990D01*
G01X1356378Y548781D02*
X1356628Y549031D01*
X1356920Y549156D01*
X1357253Y549198D01*
X1357670Y549115D01*
X1357962Y548906D01*
X1358045Y548656D01*
X1358003Y548406D01*
X1357837Y548198D01*
X1357003Y547781D01*
X1356628Y547490D01*
X1356378Y547073D01*
X1356295Y546698D01*
X1358045D01*
G01X1402510Y531905D02*
Y556005D01*
X1426610D01*
Y531905D01*
X1402510D01*
G01X1365907Y535255D02*
X1366705D01*
Y534459D01*
G01X1342295D02*
Y535255D01*
X1343079D01*
G01X1352333Y590033D02*
Y588367D01*
X1349833D01*
Y590033D01*
G01X1351041Y589367D02*
Y588367D01*
G01X1349833Y591383D02*
X1351625D01*
X1352000Y591550D01*
X1352250Y591883D01*
X1352333Y592300D01*
X1352250Y592717D01*
X1352000Y593050D01*
X1351625Y593217D01*
X1349833D01*
G01X1352333Y595317D02*
X1351791Y595400D01*
X1351333Y595525D01*
X1350916Y595692D01*
X1350458Y595900D01*
X1349833Y596233D01*
Y594567D01*
G01X1352333Y597458D02*
X1349833Y598500D01*
X1352333Y599542D01*
G01X1351458Y599167D02*
Y597833D01*
G01X1352333Y602100D02*
X1349833D01*
X1351625Y600558D01*
Y602642D01*
G01X1354461Y583873D02*
X1381761D01*
Y560323D01*
X1354461D01*
Y583873D01*
G01X1348350Y574006D02*
Y567958D01*
G01X1401700Y566380D02*
X1394900D01*
Y585480D01*
X1397500Y588080D01*
X1401700D01*
G01X1387867Y615967D02*
Y622967D01*
X1392933D01*
G01X1391067Y619584D02*
X1387867D01*
G01X1407200Y624700D02*
X1349500D01*
Y615600D01*
X1350100D01*
G01X1391800Y594223D02*
Y590200D01*
X1380085D01*
Y588366D01*
G01X1405515Y597903D02*
X1393045D01*
G01X1398941Y596718D02*
X1398691Y596843D01*
X1398399Y596926D01*
X1398066D01*
X1397691Y596801D01*
X1397399Y596593D01*
X1397191Y596343D01*
X1397024Y595926D01*
X1396982Y595551D01*
X1397066Y595176D01*
X1397191Y594926D01*
X1397441Y594676D01*
X1397732Y594509D01*
X1398024Y594426D01*
X1398316D01*
X1398607Y594509D01*
X1398857Y594634D01*
X1399066Y594801D01*
G01X1401124Y596926D02*
Y594426D01*
G01X1400166Y596926D02*
X1402082D01*
G01X1404724Y594426D02*
Y596926D01*
X1403182Y595134D01*
X1405266D01*
G01X1406532Y595468D02*
X1406824Y595759D01*
X1407074Y595926D01*
X1407407Y596009D01*
X1407699Y595926D01*
X1407907Y595759D01*
X1408074Y595509D01*
X1408116Y595218D01*
X1408074Y594968D01*
X1407907Y594718D01*
X1407657Y594509D01*
X1407366Y594426D01*
X1407032Y594509D01*
X1406741Y594759D01*
X1406574Y595134D01*
X1406532Y595551D01*
X1406616Y596093D01*
X1406741Y596384D01*
X1406949Y596676D01*
X1407241Y596884D01*
X1407532Y596926D01*
X1407824Y596843D01*
X1408032Y596634D01*
G01X1354461Y615073D02*
X1381761D01*
Y591523D01*
X1354461D01*
Y615073D01*
G01X1348250Y602906D02*
Y596858D01*
G01X1365600Y656900D02*
Y659900D01*
X1366600D01*
X1367000Y659750D01*
X1367300Y659550D01*
X1367550Y659250D01*
X1367750Y658900D01*
X1367800Y658400D01*
X1367750Y657900D01*
X1367550Y657550D01*
X1367300Y657250D01*
X1367000Y657050D01*
X1366600Y656900D01*
X1365600D01*
G01X1369550Y658250D02*
X1371150D01*
X1371000Y658600D01*
X1370750Y658800D01*
X1370400Y658900D01*
X1370050Y658850D01*
X1369750Y658700D01*
X1369550Y658350D01*
X1369450Y658050D01*
Y657750D01*
X1369550Y657450D01*
X1369800Y657150D01*
X1370100Y656950D01*
X1370450Y656900D01*
X1370800Y657000D01*
X1371150Y657300D01*
G01X1373900Y656900D02*
Y659900D01*
G01X1377500D02*
Y656900D01*
G01X1376800Y658900D02*
X1378200D01*
G01X1382000Y656900D02*
Y658900D01*
G01Y658550D02*
X1381800Y658750D01*
X1381500Y658850D01*
X1381150Y658900D01*
X1380800Y658800D01*
X1380500Y658600D01*
X1380300Y658300D01*
X1380200Y657900D01*
X1380300Y657500D01*
X1380500Y657200D01*
X1380800Y657000D01*
X1381150Y656900D01*
X1381500Y656950D01*
X1381800Y657100D01*
X1382000Y657300D01*
G01X1383200Y655900D02*
X1386200D01*
G01X1387300Y659900D02*
Y656900D01*
X1389300D01*
G01X1391900D02*
Y659900D01*
X1391300Y659300D01*
G01Y656900D02*
X1392500D01*
G01X1395500Y659900D02*
X1395100Y659800D01*
X1394800Y659550D01*
X1394600Y659250D01*
X1394450Y658850D01*
X1394400Y658400D01*
X1394450Y657950D01*
X1394600Y657550D01*
X1394800Y657250D01*
X1395100Y657000D01*
X1395500Y656900D01*
X1395900Y657000D01*
X1396200Y657250D01*
X1396400Y657550D01*
X1396550Y657950D01*
X1396600Y658400D01*
X1396550Y658850D01*
X1396400Y659250D01*
X1396200Y659550D01*
X1395900Y659800D01*
X1395500Y659900D01*
G01X1397600Y655900D02*
X1400600D01*
G01X1402700Y656900D02*
Y659900D01*
X1402100Y659300D01*
G01Y656900D02*
X1403300D01*
G01X1406300Y659900D02*
X1405900Y659800D01*
X1405600Y659550D01*
X1405400Y659250D01*
X1405250Y658850D01*
X1405200Y658400D01*
X1405250Y657950D01*
X1405400Y657550D01*
X1405600Y657250D01*
X1405900Y657000D01*
X1406300Y656900D01*
X1406700Y657000D01*
X1407000Y657250D01*
X1407200Y657550D01*
X1407350Y657950D01*
X1407400Y658400D01*
X1407350Y658850D01*
X1407200Y659250D01*
X1407000Y659550D01*
X1406700Y659800D01*
X1406300Y659900D01*
G01X1409900Y658900D02*
Y656900D01*
G01Y659700D02*
X1409800Y659750D01*
Y659850D01*
X1409900Y659900D01*
X1410000Y659850D01*
Y659750D01*
X1409900Y659700D01*
G01X1412650Y656900D02*
Y658900D01*
G01Y658400D02*
X1412850Y658650D01*
X1413150Y658850D01*
X1413550Y658900D01*
X1413900Y658850D01*
X1414200Y658650D01*
X1414350Y658300D01*
Y656900D01*
G01X1417900Y658650D02*
X1417550Y658850D01*
X1417250Y658900D01*
X1416850Y658800D01*
X1416550Y658600D01*
X1416350Y658250D01*
X1416300Y657900D01*
X1416350Y657550D01*
X1416550Y657250D01*
X1416850Y657000D01*
X1417250Y656900D01*
X1417600Y657000D01*
X1417900Y657200D01*
G01X1419850Y656900D02*
Y659900D01*
G01Y658450D02*
X1420100Y658700D01*
X1420350Y658850D01*
X1420750Y658900D01*
X1421050Y658850D01*
X1421400Y658650D01*
X1421550Y658350D01*
Y656900D01*
G01X1436258Y-38257D02*
X1418258D01*
Y-56257D01*
X1436258D01*
Y-38257D01*
G01X1456258D02*
X1438258D01*
Y-56257D01*
X1456258D01*
Y-38257D01*
G01X1447088Y6931D02*
X1448698Y10031D01*
G01X1447088D02*
X1448698Y6931D01*
G01X1450993D02*
X1451261Y6983D01*
X1451568Y7138D01*
X1451760Y7396D01*
X1451836Y7758D01*
X1451760Y8119D01*
X1451530Y8429D01*
X1451185Y8584D01*
X1450801D01*
X1450571Y8688D01*
X1450380Y8946D01*
X1450303Y9308D01*
X1450418Y9669D01*
X1450686Y9928D01*
X1450993Y10031D01*
X1451300Y9928D01*
X1451568Y9669D01*
X1451683Y9308D01*
X1451606Y8946D01*
X1451415Y8688D01*
X1451185Y8584D01*
X1450801D01*
X1450456Y8429D01*
X1450226Y8119D01*
X1450150Y7758D01*
X1450226Y7396D01*
X1450418Y7138D01*
X1450725Y6983D01*
X1450993Y6931D01*
G01X1456388Y7344D02*
X1456695Y7086D01*
X1457040Y6931D01*
X1457346D01*
X1457653Y7086D01*
X1457883Y7344D01*
X1457998Y7706D01*
X1457921Y8068D01*
X1457730Y8378D01*
X1457385Y8584D01*
X1456925Y8688D01*
X1456656Y8894D01*
X1456541Y9256D01*
X1456618Y9618D01*
X1456810Y9876D01*
X1457078Y10031D01*
X1457346D01*
X1457615Y9928D01*
X1457845Y9669D01*
G01X1459526Y10031D02*
Y6931D01*
X1461060D01*
G01X1463393D02*
X1463086Y6983D01*
X1462818Y7189D01*
X1462588Y7499D01*
X1462435Y7861D01*
X1462358Y8274D01*
Y8688D01*
X1462435Y9101D01*
X1462588Y9463D01*
X1462818Y9773D01*
X1463086Y9979D01*
X1463393Y10031D01*
X1463700Y9979D01*
X1463968Y9773D01*
X1464198Y9463D01*
X1464351Y9101D01*
X1464428Y8688D01*
Y8274D01*
X1464351Y7861D01*
X1464198Y7499D01*
X1463968Y7189D01*
X1463700Y6983D01*
X1463393Y6931D01*
G01X1466493Y10031D02*
Y6931D01*
G01X1465611Y10031D02*
X1467375D01*
G01X1441122Y3578D02*
X1441352Y3888D01*
X1441620Y4043D01*
X1441927Y4095D01*
X1442310Y3992D01*
X1442578Y3733D01*
X1442655Y3423D01*
X1442617Y3113D01*
X1442463Y2855D01*
X1441697Y2338D01*
X1441352Y1977D01*
X1441122Y1460D01*
X1441045Y995D01*
X1442655D01*
G01X1456717Y1500D02*
X1456925Y1250D01*
X1457175Y1083D01*
X1457467Y1000D01*
X1457800Y1083D01*
X1458050Y1250D01*
X1458300Y1500D01*
X1458383Y1833D01*
Y3500D01*
G01X1460567Y1000D02*
X1460650Y1542D01*
X1460775Y2000D01*
X1460942Y2417D01*
X1461150Y2875D01*
X1461483Y3500D01*
X1459817D01*
G01X1464000Y2250D02*
X1464833D01*
Y1500D01*
X1464583Y1250D01*
X1464292Y1083D01*
X1463875Y1000D01*
X1463458Y1083D01*
X1463167Y1250D01*
X1462917Y1500D01*
X1462750Y1792D01*
X1462667Y2125D01*
Y2417D01*
X1462750Y2667D01*
X1462917Y2958D01*
X1463167Y3208D01*
X1463417Y3375D01*
X1463750Y3500D01*
X1464042D01*
X1464375Y3417D01*
X1464625Y3250D01*
G01X1465933Y1500D02*
X1466183Y1208D01*
X1466517Y1042D01*
X1466892Y1000D01*
X1467225Y1042D01*
X1467558Y1250D01*
X1467767Y1500D01*
X1467808Y1750D01*
X1467725Y2042D01*
X1467433Y2250D01*
X1467142Y2333D01*
X1466767D01*
G01X1467142D02*
X1467392Y2458D01*
X1467600Y2667D01*
X1467683Y2917D01*
X1467600Y3167D01*
X1467392Y3375D01*
X1467017Y3500D01*
X1466642Y3458D01*
X1466267Y3292D01*
G01X1497000Y50D02*
Y-20050D01*
X1437000D01*
Y50D01*
X1497000D01*
G01X1440723Y58345D02*
X1441030Y58087D01*
X1441375Y57932D01*
X1441681D01*
X1441988Y58087D01*
X1442218Y58345D01*
X1442333Y58707D01*
X1442256Y59069D01*
X1442065Y59379D01*
X1441720Y59585D01*
X1441260Y59689D01*
X1440991Y59895D01*
X1440876Y60257D01*
X1440953Y60619D01*
X1441145Y60877D01*
X1441413Y61032D01*
X1441681D01*
X1441950Y60929D01*
X1442180Y60670D01*
G01X1445395Y57932D02*
X1443861D01*
Y61032D01*
X1445395D01*
G01X1444781Y59534D02*
X1443861D01*
G01X1448571Y60774D02*
X1448341Y60929D01*
X1448073Y61032D01*
X1447766D01*
X1447421Y60877D01*
X1447153Y60619D01*
X1446961Y60309D01*
X1446808Y59792D01*
X1446770Y59327D01*
X1446846Y58862D01*
X1446961Y58552D01*
X1447191Y58242D01*
X1447460Y58035D01*
X1447728Y57932D01*
X1447996D01*
X1448265Y58035D01*
X1448495Y58190D01*
X1448686Y58397D01*
G01X1449985Y61032D02*
Y58810D01*
X1450138Y58345D01*
X1450445Y58035D01*
X1450828Y57932D01*
X1451211Y58035D01*
X1451518Y58345D01*
X1451671Y58810D01*
Y61032D01*
G01X1453161Y57932D02*
Y61032D01*
X1454120D01*
X1454426Y60877D01*
X1454618Y60670D01*
X1454695Y60257D01*
X1454618Y59844D01*
X1454388Y59585D01*
X1454120Y59430D01*
X1453161D01*
G01X1454120D02*
X1454695Y57932D01*
G01X1457795D02*
X1456261D01*
Y61032D01*
X1457795D01*
G01X1457181Y59534D02*
X1456261D01*
G01X1462500Y57932D02*
Y61032D01*
X1463956D01*
G01X1463420Y59534D02*
X1462500D01*
G01X1465561Y61032D02*
Y57932D01*
X1467095D01*
G01X1468470D02*
X1469428Y61032D01*
X1470386Y57932D01*
G01X1470041Y59017D02*
X1468815D01*
G01X1471723Y58345D02*
X1472030Y58087D01*
X1472375Y57932D01*
X1472681D01*
X1472988Y58087D01*
X1473218Y58345D01*
X1473333Y58707D01*
X1473256Y59069D01*
X1473065Y59379D01*
X1472720Y59585D01*
X1472260Y59689D01*
X1471991Y59895D01*
X1471876Y60257D01*
X1471953Y60619D01*
X1472145Y60877D01*
X1472413Y61032D01*
X1472681D01*
X1472950Y60929D01*
X1473180Y60670D01*
G01X1474823Y57932D02*
Y61032D01*
G01X1476433D02*
Y57932D01*
G01Y59482D02*
X1474823D01*
G01X1422700Y45067D02*
X1420200D01*
Y46108D01*
X1420325Y46442D01*
X1420492Y46650D01*
X1420825Y46733D01*
X1421158Y46650D01*
X1421367Y46400D01*
X1421492Y46108D01*
Y45067D01*
G01Y46108D02*
X1422700Y46733D01*
G01Y49000D02*
X1422658Y49292D01*
X1422533Y49625D01*
X1422325Y49833D01*
X1422033Y49917D01*
X1421742Y49833D01*
X1421492Y49583D01*
X1421367Y49208D01*
Y48792D01*
X1421283Y48542D01*
X1421075Y48333D01*
X1420783Y48250D01*
X1420492Y48375D01*
X1420283Y48667D01*
X1420200Y49000D01*
X1420283Y49333D01*
X1420492Y49625D01*
X1420783Y49750D01*
X1421075Y49667D01*
X1421283Y49458D01*
X1421367Y49208D01*
Y48792D01*
X1421492Y48417D01*
X1421742Y48167D01*
X1422033Y48083D01*
X1422325Y48167D01*
X1422533Y48375D01*
X1422658Y48708D01*
X1422700Y49000D01*
G01X1420200Y50850D02*
X1422700Y51433D01*
X1420200Y52100D01*
X1422700Y52767D01*
X1420200Y53350D01*
G01X1422700Y55200D02*
X1420200D01*
X1420700Y54700D01*
G01X1422700D02*
Y55700D01*
G01X1422200Y57383D02*
X1422492Y57633D01*
X1422658Y57967D01*
X1422700Y58342D01*
X1422658Y58675D01*
X1422450Y59008D01*
X1422200Y59217D01*
X1421950Y59258D01*
X1421658Y59175D01*
X1421450Y58883D01*
X1421367Y58592D01*
Y58217D01*
G01Y58592D02*
X1421242Y58842D01*
X1421033Y59050D01*
X1420783Y59133D01*
X1420533Y59050D01*
X1420325Y58842D01*
X1420200Y58467D01*
X1420242Y58092D01*
X1420408Y57717D01*
G01X1419200Y45067D02*
X1416700D01*
Y46108D01*
X1416825Y46442D01*
X1416992Y46650D01*
X1417325Y46733D01*
X1417658Y46650D01*
X1417867Y46400D01*
X1417992Y46108D01*
Y45067D01*
G01Y46108D02*
X1419200Y46733D01*
G01Y49000D02*
X1419158Y49292D01*
X1419033Y49625D01*
X1418825Y49833D01*
X1418533Y49917D01*
X1418242Y49833D01*
X1417992Y49583D01*
X1417867Y49208D01*
Y48792D01*
X1417783Y48542D01*
X1417575Y48333D01*
X1417283Y48250D01*
X1416992Y48375D01*
X1416783Y48667D01*
X1416700Y49000D01*
X1416783Y49333D01*
X1416992Y49625D01*
X1417283Y49750D01*
X1417575Y49667D01*
X1417783Y49458D01*
X1417867Y49208D01*
Y48792D01*
X1417992Y48417D01*
X1418242Y48167D01*
X1418533Y48083D01*
X1418825Y48167D01*
X1419033Y48375D01*
X1419158Y48708D01*
X1419200Y49000D01*
G01X1416700Y50850D02*
X1419200Y51433D01*
X1416700Y52100D01*
X1419200Y52767D01*
X1416700Y53350D01*
G01X1419200Y55200D02*
X1416700D01*
X1417200Y54700D01*
G01X1419200D02*
Y55700D01*
G01Y58800D02*
X1416700D01*
X1418492Y57258D01*
Y59342D01*
G01X1447537Y48561D02*
X1447287Y48686D01*
X1446995Y48769D01*
X1446662D01*
X1446287Y48644D01*
X1445995Y48436D01*
X1445787Y48186D01*
X1445620Y47769D01*
X1445578Y47394D01*
X1445662Y47019D01*
X1445787Y46769D01*
X1446037Y46519D01*
X1446328Y46352D01*
X1446620Y46269D01*
X1446912D01*
X1447203Y46352D01*
X1447453Y46477D01*
X1447662Y46644D01*
G01X1449637Y46269D02*
X1449720Y46811D01*
X1449845Y47269D01*
X1450012Y47686D01*
X1450220Y48144D01*
X1450553Y48769D01*
X1448887D01*
G01X1453070Y47519D02*
X1453903D01*
Y46769D01*
X1453653Y46519D01*
X1453362Y46352D01*
X1452945Y46269D01*
X1452528Y46352D01*
X1452237Y46519D01*
X1451987Y46769D01*
X1451820Y47061D01*
X1451737Y47394D01*
Y47686D01*
X1451820Y47936D01*
X1451987Y48227D01*
X1452237Y48477D01*
X1452487Y48644D01*
X1452820Y48769D01*
X1453112D01*
X1453445Y48686D01*
X1453695Y48519D01*
G01X1455920Y46269D02*
Y48769D01*
X1455420Y48269D01*
G01Y46269D02*
X1456420D01*
G01X1458228Y48352D02*
X1458478Y48602D01*
X1458770Y48727D01*
X1459103Y48769D01*
X1459520Y48686D01*
X1459812Y48477D01*
X1459895Y48227D01*
X1459853Y47977D01*
X1459687Y47769D01*
X1458853Y47352D01*
X1458478Y47061D01*
X1458228Y46644D01*
X1458145Y46269D01*
X1459895D01*
G01X1447117Y52259D02*
X1446867Y52384D01*
X1446575Y52467D01*
X1446242D01*
X1445867Y52342D01*
X1445575Y52134D01*
X1445367Y51884D01*
X1445200Y51467D01*
X1445158Y51092D01*
X1445242Y50717D01*
X1445367Y50467D01*
X1445617Y50217D01*
X1445908Y50050D01*
X1446200Y49967D01*
X1446492D01*
X1446783Y50050D01*
X1447033Y50175D01*
X1447242Y50342D01*
G01X1449217Y49967D02*
X1449300Y50509D01*
X1449425Y50967D01*
X1449592Y51384D01*
X1449800Y51842D01*
X1450133Y52467D01*
X1448467D01*
G01X1452650Y51217D02*
X1453483D01*
Y50467D01*
X1453233Y50217D01*
X1452942Y50050D01*
X1452525Y49967D01*
X1452108Y50050D01*
X1451817Y50217D01*
X1451567Y50467D01*
X1451400Y50759D01*
X1451317Y51092D01*
Y51384D01*
X1451400Y51634D01*
X1451567Y51925D01*
X1451817Y52175D01*
X1452067Y52342D01*
X1452400Y52467D01*
X1452692D01*
X1453025Y52384D01*
X1453275Y52217D01*
G01X1455500Y49967D02*
Y52467D01*
X1455000Y51967D01*
G01Y49967D02*
X1456000D01*
G01X1458600D02*
Y52467D01*
X1458100Y51967D01*
G01Y49967D02*
X1459100D01*
G01X1462734Y52694D02*
X1462484Y52819D01*
X1462192Y52902D01*
X1461859D01*
X1461484Y52777D01*
X1461192Y52569D01*
X1460984Y52319D01*
X1460817Y51902D01*
X1460775Y51527D01*
X1460859Y51152D01*
X1460984Y50902D01*
X1461234Y50652D01*
X1461525Y50485D01*
X1461817Y50402D01*
X1462109D01*
X1462400Y50485D01*
X1462650Y50610D01*
X1462859Y50777D01*
G01X1464834Y50402D02*
X1464917Y50944D01*
X1465042Y51402D01*
X1465209Y51819D01*
X1465417Y52277D01*
X1465750Y52902D01*
X1464084D01*
G01X1468267Y51652D02*
X1469100D01*
Y50902D01*
X1468850Y50652D01*
X1468559Y50485D01*
X1468142Y50402D01*
X1467725Y50485D01*
X1467434Y50652D01*
X1467184Y50902D01*
X1467017Y51194D01*
X1466934Y51527D01*
Y51819D01*
X1467017Y52069D01*
X1467184Y52360D01*
X1467434Y52610D01*
X1467684Y52777D01*
X1468017Y52902D01*
X1468309D01*
X1468642Y52819D01*
X1468892Y52652D01*
G01X1471117Y50402D02*
Y52902D01*
X1470617Y52402D01*
G01Y50402D02*
X1471617D01*
G01X1473300Y50902D02*
X1473550Y50610D01*
X1473884Y50444D01*
X1474259Y50402D01*
X1474592Y50444D01*
X1474925Y50652D01*
X1475134Y50902D01*
X1475175Y51152D01*
X1475092Y51444D01*
X1474800Y51652D01*
X1474509Y51735D01*
X1474134D01*
G01X1474509D02*
X1474759Y51860D01*
X1474967Y52069D01*
X1475050Y52319D01*
X1474967Y52569D01*
X1474759Y52777D01*
X1474384Y52902D01*
X1474009Y52860D01*
X1473634Y52694D01*
G01X1464234Y49194D02*
X1463984Y49319D01*
X1463692Y49402D01*
X1463359D01*
X1462984Y49277D01*
X1462692Y49069D01*
X1462484Y48819D01*
X1462317Y48402D01*
X1462275Y48027D01*
X1462359Y47652D01*
X1462484Y47402D01*
X1462734Y47152D01*
X1463025Y46985D01*
X1463317Y46902D01*
X1463609D01*
X1463900Y46985D01*
X1464150Y47110D01*
X1464359Y47277D01*
G01X1466334Y46902D02*
X1466417Y47444D01*
X1466542Y47902D01*
X1466709Y48319D01*
X1466917Y48777D01*
X1467250Y49402D01*
X1465584D01*
G01X1469767Y48152D02*
X1470600D01*
Y47402D01*
X1470350Y47152D01*
X1470059Y46985D01*
X1469642Y46902D01*
X1469225Y46985D01*
X1468934Y47152D01*
X1468684Y47402D01*
X1468517Y47694D01*
X1468434Y48027D01*
Y48319D01*
X1468517Y48569D01*
X1468684Y48860D01*
X1468934Y49110D01*
X1469184Y49277D01*
X1469517Y49402D01*
X1469809D01*
X1470142Y49319D01*
X1470392Y49152D01*
G01X1472617Y46902D02*
Y49402D01*
X1472117Y48902D01*
G01Y46902D02*
X1473117D01*
G01X1476217D02*
Y49402D01*
X1474675Y47610D01*
X1476759D01*
G01X1434408Y46817D02*
X1434283Y46567D01*
X1434200Y46275D01*
Y45942D01*
X1434325Y45567D01*
X1434533Y45275D01*
X1434783Y45067D01*
X1435200Y44900D01*
X1435575Y44858D01*
X1435950Y44942D01*
X1436200Y45067D01*
X1436450Y45317D01*
X1436617Y45608D01*
X1436700Y45900D01*
Y46192D01*
X1436617Y46483D01*
X1436492Y46733D01*
X1436325Y46942D01*
G01X1436700Y48917D02*
X1436158Y49000D01*
X1435700Y49125D01*
X1435283Y49292D01*
X1434825Y49500D01*
X1434200Y49833D01*
Y48167D01*
G01X1435450Y52350D02*
Y53183D01*
X1436200D01*
X1436450Y52933D01*
X1436617Y52642D01*
X1436700Y52225D01*
X1436617Y51808D01*
X1436450Y51517D01*
X1436200Y51267D01*
X1435908Y51100D01*
X1435575Y51017D01*
X1435283D01*
X1435033Y51100D01*
X1434742Y51267D01*
X1434492Y51517D01*
X1434325Y51767D01*
X1434200Y52100D01*
Y52392D01*
X1434283Y52725D01*
X1434450Y52975D01*
G01X1436700Y55200D02*
X1436658Y55492D01*
X1436533Y55825D01*
X1436325Y56033D01*
X1436033Y56117D01*
X1435742Y56033D01*
X1435492Y55783D01*
X1435367Y55408D01*
Y54992D01*
X1435283Y54742D01*
X1435075Y54533D01*
X1434783Y54450D01*
X1434492Y54575D01*
X1434283Y54867D01*
X1434200Y55200D01*
X1434283Y55533D01*
X1434492Y55825D01*
X1434783Y55950D01*
X1435075Y55867D01*
X1435283Y55658D01*
X1435367Y55408D01*
Y54992D01*
X1435492Y54617D01*
X1435742Y54367D01*
X1436033Y54283D01*
X1436325Y54367D01*
X1436533Y54575D01*
X1436658Y54908D01*
X1436700Y55200D01*
G01X1423908Y46817D02*
X1423783Y46567D01*
X1423700Y46275D01*
Y45942D01*
X1423825Y45567D01*
X1424033Y45275D01*
X1424283Y45067D01*
X1424700Y44900D01*
X1425075Y44858D01*
X1425450Y44942D01*
X1425700Y45067D01*
X1425950Y45317D01*
X1426117Y45608D01*
X1426200Y45900D01*
Y46192D01*
X1426117Y46483D01*
X1425992Y46733D01*
X1425825Y46942D01*
G01X1426200Y48917D02*
X1425658Y49000D01*
X1425200Y49125D01*
X1424783Y49292D01*
X1424325Y49500D01*
X1423700Y49833D01*
Y48167D01*
G01X1424950Y52350D02*
Y53183D01*
X1425700D01*
X1425950Y52933D01*
X1426117Y52642D01*
X1426200Y52225D01*
X1426117Y51808D01*
X1425950Y51517D01*
X1425700Y51267D01*
X1425408Y51100D01*
X1425075Y51017D01*
X1424783D01*
X1424533Y51100D01*
X1424242Y51267D01*
X1423992Y51517D01*
X1423825Y51767D01*
X1423700Y52100D01*
Y52392D01*
X1423783Y52725D01*
X1423950Y52975D01*
G01X1425825Y54283D02*
X1426033Y54533D01*
X1426158Y54825D01*
X1426200Y55200D01*
X1426117Y55575D01*
X1425950Y55867D01*
X1425658Y56075D01*
X1425325Y56117D01*
X1424992Y56033D01*
X1424783Y55825D01*
X1424617Y55533D01*
X1424575Y55242D01*
X1424617Y54950D01*
X1424783Y54575D01*
X1423700Y54700D01*
Y55825D01*
G01X1430908Y46817D02*
X1430783Y46567D01*
X1430700Y46275D01*
Y45942D01*
X1430825Y45567D01*
X1431033Y45275D01*
X1431283Y45067D01*
X1431700Y44900D01*
X1432075Y44858D01*
X1432450Y44942D01*
X1432700Y45067D01*
X1432950Y45317D01*
X1433117Y45608D01*
X1433200Y45900D01*
Y46192D01*
X1433117Y46483D01*
X1432992Y46733D01*
X1432825Y46942D01*
G01X1433200Y48917D02*
X1432658Y49000D01*
X1432200Y49125D01*
X1431783Y49292D01*
X1431325Y49500D01*
X1430700Y49833D01*
Y48167D01*
G01X1431950Y52350D02*
Y53183D01*
X1432700D01*
X1432950Y52933D01*
X1433117Y52642D01*
X1433200Y52225D01*
X1433117Y51808D01*
X1432950Y51517D01*
X1432700Y51267D01*
X1432408Y51100D01*
X1432075Y51017D01*
X1431783D01*
X1431533Y51100D01*
X1431242Y51267D01*
X1430992Y51517D01*
X1430825Y51767D01*
X1430700Y52100D01*
Y52392D01*
X1430783Y52725D01*
X1430950Y52975D01*
G01X1433200Y55117D02*
X1432658Y55200D01*
X1432200Y55325D01*
X1431783Y55492D01*
X1431325Y55700D01*
X1430700Y56033D01*
Y54367D01*
G01X1427408Y46817D02*
X1427283Y46567D01*
X1427200Y46275D01*
Y45942D01*
X1427325Y45567D01*
X1427533Y45275D01*
X1427783Y45067D01*
X1428200Y44900D01*
X1428575Y44858D01*
X1428950Y44942D01*
X1429200Y45067D01*
X1429450Y45317D01*
X1429617Y45608D01*
X1429700Y45900D01*
Y46192D01*
X1429617Y46483D01*
X1429492Y46733D01*
X1429325Y46942D01*
G01X1429700Y48917D02*
X1429158Y49000D01*
X1428700Y49125D01*
X1428283Y49292D01*
X1427825Y49500D01*
X1427200Y49833D01*
Y48167D01*
G01X1428450Y52350D02*
Y53183D01*
X1429200D01*
X1429450Y52933D01*
X1429617Y52642D01*
X1429700Y52225D01*
X1429617Y51808D01*
X1429450Y51517D01*
X1429200Y51267D01*
X1428908Y51100D01*
X1428575Y51017D01*
X1428283D01*
X1428033Y51100D01*
X1427742Y51267D01*
X1427492Y51517D01*
X1427325Y51767D01*
X1427200Y52100D01*
Y52392D01*
X1427283Y52725D01*
X1427450Y52975D01*
G01X1428658Y54408D02*
X1428367Y54700D01*
X1428200Y54950D01*
X1428117Y55283D01*
X1428200Y55575D01*
X1428367Y55783D01*
X1428617Y55950D01*
X1428908Y55992D01*
X1429158Y55950D01*
X1429408Y55783D01*
X1429617Y55533D01*
X1429700Y55242D01*
X1429617Y54908D01*
X1429367Y54617D01*
X1428992Y54450D01*
X1428575Y54408D01*
X1428033Y54492D01*
X1427742Y54617D01*
X1427450Y54825D01*
X1427242Y55117D01*
X1427200Y55408D01*
X1427283Y55700D01*
X1427492Y55908D01*
G01X1437908Y46817D02*
X1437783Y46567D01*
X1437700Y46275D01*
Y45942D01*
X1437825Y45567D01*
X1438033Y45275D01*
X1438283Y45067D01*
X1438700Y44900D01*
X1439075Y44858D01*
X1439450Y44942D01*
X1439700Y45067D01*
X1439950Y45317D01*
X1440117Y45608D01*
X1440200Y45900D01*
Y46192D01*
X1440117Y46483D01*
X1439992Y46733D01*
X1439825Y46942D01*
G01X1440200Y48917D02*
X1439658Y49000D01*
X1439200Y49125D01*
X1438783Y49292D01*
X1438325Y49500D01*
X1437700Y49833D01*
Y48167D01*
G01X1438950Y52350D02*
Y53183D01*
X1439700D01*
X1439950Y52933D01*
X1440117Y52642D01*
X1440200Y52225D01*
X1440117Y51808D01*
X1439950Y51517D01*
X1439700Y51267D01*
X1439408Y51100D01*
X1439075Y51017D01*
X1438783D01*
X1438533Y51100D01*
X1438242Y51267D01*
X1437992Y51517D01*
X1437825Y51767D01*
X1437700Y52100D01*
Y52392D01*
X1437783Y52725D01*
X1437950Y52975D01*
G01X1439908Y54492D02*
X1440117Y54783D01*
X1440200Y55117D01*
X1440117Y55450D01*
X1439867Y55742D01*
X1439492Y55950D01*
X1439117Y56033D01*
X1438658D01*
X1438283Y55950D01*
X1437950Y55742D01*
X1437783Y55492D01*
X1437700Y55200D01*
X1437783Y54867D01*
X1437950Y54617D01*
X1438200Y54450D01*
X1438533Y54367D01*
X1438825Y54450D01*
X1439117Y54658D01*
X1439283Y54908D01*
X1439325Y55200D01*
X1439242Y55533D01*
X1439033Y55783D01*
X1438658Y56033D01*
G01X1441208Y42617D02*
X1441083Y42367D01*
X1441000Y42075D01*
Y41742D01*
X1441125Y41367D01*
X1441333Y41075D01*
X1441583Y40867D01*
X1442000Y40700D01*
X1442375Y40658D01*
X1442750Y40742D01*
X1443000Y40867D01*
X1443250Y41117D01*
X1443417Y41408D01*
X1443500Y41700D01*
Y41992D01*
X1443417Y42283D01*
X1443292Y42533D01*
X1443125Y42742D01*
G01X1443500Y44717D02*
X1442958Y44800D01*
X1442500Y44925D01*
X1442083Y45092D01*
X1441625Y45300D01*
X1441000Y45633D01*
Y43967D01*
G01X1442250Y48150D02*
Y48983D01*
X1443000D01*
X1443250Y48733D01*
X1443417Y48442D01*
X1443500Y48025D01*
X1443417Y47608D01*
X1443250Y47317D01*
X1443000Y47067D01*
X1442708Y46900D01*
X1442375Y46817D01*
X1442083D01*
X1441833Y46900D01*
X1441542Y47067D01*
X1441292Y47317D01*
X1441125Y47567D01*
X1441000Y47900D01*
Y48192D01*
X1441083Y48525D01*
X1441250Y48775D01*
G01X1443500Y51000D02*
X1441000D01*
X1441500Y50500D01*
G01X1443500D02*
Y51500D01*
G01X1441000Y54100D02*
X1441083Y53767D01*
X1441292Y53517D01*
X1441542Y53350D01*
X1441875Y53225D01*
X1442250Y53183D01*
X1442625Y53225D01*
X1442958Y53350D01*
X1443208Y53517D01*
X1443417Y53767D01*
X1443500Y54100D01*
X1443417Y54433D01*
X1443208Y54683D01*
X1442958Y54850D01*
X1442625Y54975D01*
X1442250Y55017D01*
X1441875Y54975D01*
X1441542Y54850D01*
X1441292Y54683D01*
X1441083Y54433D01*
X1441000Y54100D01*
G01X1418549Y67117D02*
X1418424Y66867D01*
X1418341Y66575D01*
Y66242D01*
X1418466Y65867D01*
X1418674Y65575D01*
X1418924Y65367D01*
X1419341Y65200D01*
X1419716Y65158D01*
X1420091Y65242D01*
X1420341Y65367D01*
X1420591Y65617D01*
X1420758Y65908D01*
X1420841Y66200D01*
Y66492D01*
X1420758Y66783D01*
X1420633Y67033D01*
X1420466Y67242D01*
G01X1420841Y69217D02*
X1420299Y69300D01*
X1419841Y69425D01*
X1419424Y69592D01*
X1418966Y69800D01*
X1418341Y70133D01*
Y68467D01*
G01X1419591Y72650D02*
Y73483D01*
X1420341D01*
X1420591Y73233D01*
X1420758Y72942D01*
X1420841Y72525D01*
X1420758Y72108D01*
X1420591Y71817D01*
X1420341Y71567D01*
X1420049Y71400D01*
X1419716Y71317D01*
X1419424D01*
X1419174Y71400D01*
X1418883Y71567D01*
X1418633Y71817D01*
X1418466Y72067D01*
X1418341Y72400D01*
Y72692D01*
X1418424Y73025D01*
X1418591Y73275D01*
G01X1418758Y74708D02*
X1418508Y74958D01*
X1418383Y75250D01*
X1418341Y75583D01*
X1418424Y76000D01*
X1418633Y76292D01*
X1418883Y76375D01*
X1419133Y76333D01*
X1419341Y76167D01*
X1419758Y75333D01*
X1420049Y74958D01*
X1420466Y74708D01*
X1420841Y74625D01*
Y76375D01*
G01X1415936Y48573D02*
Y58409D01*
G01X1492026Y62755D02*
X1437931D01*
Y112951D01*
X1492026D01*
Y62755D01*
G01X1421133Y82317D02*
X1423633D01*
Y83983D01*
G01Y86167D02*
X1423091Y86250D01*
X1422633Y86375D01*
X1422216Y86542D01*
X1421758Y86750D01*
X1421133Y87083D01*
Y85417D01*
G01X1423633Y88558D02*
X1421133D01*
Y90142D01*
G01X1422341Y89558D02*
Y88558D01*
G01X1421550Y91658D02*
X1421300Y91908D01*
X1421175Y92200D01*
X1421133Y92533D01*
X1421216Y92950D01*
X1421425Y93242D01*
X1421675Y93325D01*
X1421925Y93283D01*
X1422133Y93117D01*
X1422550Y92283D01*
X1422841Y91908D01*
X1423258Y91658D01*
X1423633Y91575D01*
Y93325D01*
G01X1432977Y92545D02*
X1427977D01*
Y95079D01*
G01X1430394Y94145D02*
Y92545D01*
G01X1432977Y100112D02*
X1429644D01*
G01X1430227D02*
X1429894Y99845D01*
X1429727Y99445D01*
X1429644Y98979D01*
X1429810Y98512D01*
X1430144Y98112D01*
X1430644Y97845D01*
X1431310Y97712D01*
X1431977Y97845D01*
X1432477Y98112D01*
X1432810Y98512D01*
X1432977Y98979D01*
X1432894Y99445D01*
X1432644Y99845D01*
X1432310Y100112D01*
G01X1430060Y105079D02*
X1429727Y104612D01*
X1429644Y104212D01*
X1429810Y103679D01*
X1430144Y103279D01*
X1430727Y103012D01*
X1431310Y102945D01*
X1431894Y103012D01*
X1432394Y103279D01*
X1432810Y103679D01*
X1432977Y104212D01*
X1432810Y104679D01*
X1432477Y105079D01*
G01X1427977Y109112D02*
X1432977D01*
G01X1429644Y108179D02*
Y110045D01*
G01X1432977Y114212D02*
X1432894Y113812D01*
X1432560Y113412D01*
X1431977Y113145D01*
X1431310Y113012D01*
X1430644Y113145D01*
X1430060Y113412D01*
X1429727Y113812D01*
X1429644Y114212D01*
X1429727Y114612D01*
X1430060Y115012D01*
X1430644Y115279D01*
X1431310Y115345D01*
X1431977Y115279D01*
X1432560Y115012D01*
X1432894Y114612D01*
X1432977Y114212D01*
G01Y118379D02*
X1429644D01*
G01X1430310D02*
X1429977Y118712D01*
X1429727Y119045D01*
X1429644Y119512D01*
X1429727Y119845D01*
X1429977Y120245D01*
G01X1434477Y123012D02*
X1434644Y123412D01*
X1434477Y123945D01*
X1434144Y124279D01*
X1433727Y124545D01*
X1432394Y124945D01*
X1429644Y125812D01*
G01Y123679D02*
X1432394Y124945D01*
G01X1427977Y133812D02*
Y135412D01*
G01Y134612D02*
X1432977D01*
G01Y133812D02*
Y135412D01*
G01Y138245D02*
X1427977D01*
Y139579D01*
X1428227Y140112D01*
X1428560Y140512D01*
X1429060Y140845D01*
X1429644Y141112D01*
X1430477Y141179D01*
X1431310Y141112D01*
X1431894Y140845D01*
X1432394Y140512D01*
X1432727Y140112D01*
X1432977Y139579D01*
Y138245D01*
G01X1433144Y144812D02*
X1433060Y144679D01*
X1432894D01*
X1432810Y144812D01*
X1432894Y144945D01*
X1433060D01*
X1433144Y144812D01*
G01X1430894D02*
X1430810Y144679D01*
X1430644D01*
X1430560Y144812D01*
X1430644Y144945D01*
X1430810D01*
X1430894Y144812D01*
G01X1431977Y148579D02*
X1432477Y148912D01*
X1432810Y149312D01*
X1432977Y149779D01*
X1432810Y150312D01*
X1432477Y150712D01*
X1431977Y151112D01*
X1431310Y151245D01*
X1427977D01*
G01X1419486Y80537D02*
X1416986D01*
Y81578D01*
X1417111Y81912D01*
X1417278Y82120D01*
X1417611Y82203D01*
X1417944Y82120D01*
X1418153Y81870D01*
X1418278Y81578D01*
Y80537D01*
G01Y81578D02*
X1419486Y82203D01*
G01Y84470D02*
X1416986D01*
X1417486Y83970D01*
G01X1419486D02*
Y84970D01*
G01X1417403Y86778D02*
X1417153Y87028D01*
X1417028Y87320D01*
X1416986Y87653D01*
X1417069Y88070D01*
X1417278Y88362D01*
X1417528Y88445D01*
X1417778Y88403D01*
X1417986Y88237D01*
X1418403Y87403D01*
X1418694Y87028D01*
X1419111Y86778D01*
X1419486Y86695D01*
Y88445D01*
G01X1416986Y89420D02*
X1419486Y90003D01*
X1416986Y90670D01*
X1419486Y91337D01*
X1416986Y91920D01*
G01X1417403Y92978D02*
X1417153Y93228D01*
X1417028Y93520D01*
X1416986Y93853D01*
X1417069Y94270D01*
X1417278Y94562D01*
X1417528Y94645D01*
X1417778Y94603D01*
X1417986Y94437D01*
X1418403Y93603D01*
X1418694Y93228D01*
X1419111Y92978D01*
X1419486Y92895D01*
Y94645D01*
G01X1415286Y80637D02*
X1412786D01*
Y81678D01*
X1412911Y82012D01*
X1413078Y82220D01*
X1413411Y82303D01*
X1413744Y82220D01*
X1413953Y81970D01*
X1414078Y81678D01*
Y80637D01*
G01Y81678D02*
X1415286Y82303D01*
G01Y84570D02*
X1412786D01*
X1413286Y84070D01*
G01X1415286D02*
Y85070D01*
G01X1413203Y86878D02*
X1412953Y87128D01*
X1412828Y87420D01*
X1412786Y87753D01*
X1412869Y88170D01*
X1413078Y88462D01*
X1413328Y88545D01*
X1413578Y88503D01*
X1413786Y88337D01*
X1414203Y87503D01*
X1414494Y87128D01*
X1414911Y86878D01*
X1415286Y86795D01*
Y88545D01*
G01X1412786Y89520D02*
X1415286Y90103D01*
X1412786Y90770D01*
X1415286Y91437D01*
X1412786Y92020D01*
G01X1415286Y93870D02*
X1412786D01*
X1413286Y93370D01*
G01X1415286D02*
Y94370D01*
G01X1455917Y116700D02*
Y119200D01*
X1456958D01*
X1457292Y119075D01*
X1457500Y118908D01*
X1457583Y118575D01*
X1457500Y118242D01*
X1457250Y118033D01*
X1456958Y117908D01*
X1455917D01*
G01X1456958D02*
X1457583Y116700D01*
G01X1459850D02*
X1460142Y116742D01*
X1460475Y116867D01*
X1460683Y117075D01*
X1460767Y117367D01*
X1460683Y117658D01*
X1460433Y117908D01*
X1460058Y118033D01*
X1459642D01*
X1459392Y118117D01*
X1459183Y118325D01*
X1459100Y118617D01*
X1459225Y118908D01*
X1459517Y119117D01*
X1459850Y119200D01*
X1460183Y119117D01*
X1460475Y118908D01*
X1460600Y118617D01*
X1460517Y118325D01*
X1460308Y118117D01*
X1460058Y118033D01*
X1459642D01*
X1459267Y117908D01*
X1459017Y117658D01*
X1458933Y117367D01*
X1459017Y117075D01*
X1459225Y116867D01*
X1459558Y116742D01*
X1459850Y116700D01*
G01X1462158D02*
Y119200D01*
X1463742D01*
G01X1463158Y117992D02*
X1462158D01*
G01X1466050Y116700D02*
Y119200D01*
X1465550Y118700D01*
G01Y116700D02*
X1466550D01*
G01X1469150D02*
X1469442Y116742D01*
X1469775Y116867D01*
X1469983Y117075D01*
X1470067Y117367D01*
X1469983Y117658D01*
X1469733Y117908D01*
X1469358Y118033D01*
X1468942D01*
X1468692Y118117D01*
X1468483Y118325D01*
X1468400Y118617D01*
X1468525Y118908D01*
X1468817Y119117D01*
X1469150Y119200D01*
X1469483Y119117D01*
X1469775Y118908D01*
X1469900Y118617D01*
X1469817Y118325D01*
X1469608Y118117D01*
X1469358Y118033D01*
X1468942D01*
X1468567Y117908D01*
X1468317Y117658D01*
X1468233Y117367D01*
X1468317Y117075D01*
X1468525Y116867D01*
X1468858Y116742D01*
X1469150Y116700D01*
G01X1456217Y120700D02*
Y123200D01*
X1457258D01*
X1457592Y123075D01*
X1457800Y122908D01*
X1457883Y122575D01*
X1457800Y122242D01*
X1457550Y122033D01*
X1457258Y121908D01*
X1456217D01*
G01X1457258D02*
X1457883Y120700D01*
G01X1460150D02*
X1460442Y120742D01*
X1460775Y120867D01*
X1460983Y121075D01*
X1461067Y121367D01*
X1460983Y121658D01*
X1460733Y121908D01*
X1460358Y122033D01*
X1459942D01*
X1459692Y122117D01*
X1459483Y122325D01*
X1459400Y122617D01*
X1459525Y122908D01*
X1459817Y123117D01*
X1460150Y123200D01*
X1460483Y123117D01*
X1460775Y122908D01*
X1460900Y122617D01*
X1460817Y122325D01*
X1460608Y122117D01*
X1460358Y122033D01*
X1459942D01*
X1459567Y121908D01*
X1459317Y121658D01*
X1459233Y121367D01*
X1459317Y121075D01*
X1459525Y120867D01*
X1459858Y120742D01*
X1460150Y120700D01*
G01X1462458D02*
Y123200D01*
X1464042D01*
G01X1463458Y121992D02*
X1462458D01*
G01X1465558Y122783D02*
X1465808Y123033D01*
X1466100Y123158D01*
X1466433Y123200D01*
X1466850Y123117D01*
X1467142Y122908D01*
X1467225Y122658D01*
X1467183Y122408D01*
X1467017Y122200D01*
X1466183Y121783D01*
X1465808Y121492D01*
X1465558Y121075D01*
X1465475Y120700D01*
X1467225D01*
G01X1469450D02*
Y123200D01*
X1468950Y122700D01*
G01Y120700D02*
X1469950D01*
G01X1441209Y119092D02*
X1440959Y119217D01*
X1440667Y119300D01*
X1440334D01*
X1439959Y119175D01*
X1439667Y118967D01*
X1439459Y118717D01*
X1439292Y118300D01*
X1439250Y117925D01*
X1439334Y117550D01*
X1439459Y117300D01*
X1439709Y117050D01*
X1440000Y116883D01*
X1440292Y116800D01*
X1440584D01*
X1440875Y116883D01*
X1441125Y117008D01*
X1441334Y117175D01*
G01X1443392Y116800D02*
X1443684Y116842D01*
X1444017Y116967D01*
X1444225Y117175D01*
X1444309Y117467D01*
X1444225Y117758D01*
X1443975Y118008D01*
X1443600Y118133D01*
X1443184D01*
X1442934Y118217D01*
X1442725Y118425D01*
X1442642Y118717D01*
X1442767Y119008D01*
X1443059Y119217D01*
X1443392Y119300D01*
X1443725Y119217D01*
X1444017Y119008D01*
X1444142Y118717D01*
X1444059Y118425D01*
X1443850Y118217D01*
X1443600Y118133D01*
X1443184D01*
X1442809Y118008D01*
X1442559Y117758D01*
X1442475Y117467D01*
X1442559Y117175D01*
X1442767Y116967D01*
X1443100Y116842D01*
X1443392Y116800D01*
G01X1445700D02*
Y119300D01*
X1447284D01*
G01X1446700Y118092D02*
X1445700D01*
G01X1449592Y116800D02*
Y119300D01*
X1449092Y118800D01*
G01Y116800D02*
X1450092D01*
G01X1451775Y117300D02*
X1452025Y117008D01*
X1452359Y116842D01*
X1452734Y116800D01*
X1453067Y116842D01*
X1453400Y117050D01*
X1453609Y117300D01*
X1453650Y117550D01*
X1453567Y117842D01*
X1453275Y118050D01*
X1452984Y118133D01*
X1452609D01*
G01X1452984D02*
X1453234Y118258D01*
X1453442Y118467D01*
X1453525Y118717D01*
X1453442Y118967D01*
X1453234Y119175D01*
X1452859Y119300D01*
X1452484Y119258D01*
X1452109Y119092D01*
G01X1442009Y127192D02*
X1441759Y127317D01*
X1441467Y127400D01*
X1441134D01*
X1440759Y127275D01*
X1440467Y127067D01*
X1440259Y126817D01*
X1440092Y126400D01*
X1440050Y126025D01*
X1440134Y125650D01*
X1440259Y125400D01*
X1440509Y125150D01*
X1440800Y124983D01*
X1441092Y124900D01*
X1441384D01*
X1441675Y124983D01*
X1441925Y125108D01*
X1442134Y125275D01*
G01X1444192Y124900D02*
X1444484Y124942D01*
X1444817Y125067D01*
X1445025Y125275D01*
X1445109Y125567D01*
X1445025Y125858D01*
X1444775Y126108D01*
X1444400Y126233D01*
X1443984D01*
X1443734Y126317D01*
X1443525Y126525D01*
X1443442Y126817D01*
X1443567Y127108D01*
X1443859Y127317D01*
X1444192Y127400D01*
X1444525Y127317D01*
X1444817Y127108D01*
X1444942Y126817D01*
X1444859Y126525D01*
X1444650Y126317D01*
X1444400Y126233D01*
X1443984D01*
X1443609Y126108D01*
X1443359Y125858D01*
X1443275Y125567D01*
X1443359Y125275D01*
X1443567Y125067D01*
X1443900Y124942D01*
X1444192Y124900D01*
G01X1446500D02*
Y127400D01*
X1448084D01*
G01X1447500Y126192D02*
X1446500D01*
G01X1450392Y124900D02*
Y127400D01*
X1449892Y126900D01*
G01Y124900D02*
X1450892D01*
G01X1453492D02*
Y127400D01*
X1452992Y126900D01*
G01Y124900D02*
X1453992D01*
G01X1441109Y122892D02*
X1440859Y123017D01*
X1440567Y123100D01*
X1440234D01*
X1439859Y122975D01*
X1439567Y122767D01*
X1439359Y122517D01*
X1439192Y122100D01*
X1439150Y121725D01*
X1439234Y121350D01*
X1439359Y121100D01*
X1439609Y120850D01*
X1439900Y120683D01*
X1440192Y120600D01*
X1440484D01*
X1440775Y120683D01*
X1441025Y120808D01*
X1441234Y120975D01*
G01X1443292Y120600D02*
X1443584Y120642D01*
X1443917Y120767D01*
X1444125Y120975D01*
X1444209Y121267D01*
X1444125Y121558D01*
X1443875Y121808D01*
X1443500Y121933D01*
X1443084D01*
X1442834Y122017D01*
X1442625Y122225D01*
X1442542Y122517D01*
X1442667Y122808D01*
X1442959Y123017D01*
X1443292Y123100D01*
X1443625Y123017D01*
X1443917Y122808D01*
X1444042Y122517D01*
X1443959Y122225D01*
X1443750Y122017D01*
X1443500Y121933D01*
X1443084D01*
X1442709Y121808D01*
X1442459Y121558D01*
X1442375Y121267D01*
X1442459Y120975D01*
X1442667Y120767D01*
X1443000Y120642D01*
X1443292Y120600D01*
G01X1445600D02*
Y123100D01*
X1447184D01*
G01X1446600Y121892D02*
X1445600D01*
G01X1449492Y120600D02*
Y123100D01*
X1448992Y122600D01*
G01Y120600D02*
X1449992D01*
G01X1451675Y120975D02*
X1451925Y120767D01*
X1452217Y120642D01*
X1452592Y120600D01*
X1452967Y120683D01*
X1453259Y120850D01*
X1453467Y121142D01*
X1453509Y121475D01*
X1453425Y121808D01*
X1453217Y122017D01*
X1452925Y122183D01*
X1452634Y122225D01*
X1452342Y122183D01*
X1451967Y122017D01*
X1452092Y123100D01*
X1453217D01*
G01X1457967Y126992D02*
X1457717Y127117D01*
X1457425Y127200D01*
X1457092D01*
X1456717Y127075D01*
X1456425Y126867D01*
X1456217Y126617D01*
X1456050Y126200D01*
X1456008Y125825D01*
X1456092Y125450D01*
X1456217Y125200D01*
X1456467Y124950D01*
X1456758Y124783D01*
X1457050Y124700D01*
X1457342D01*
X1457633Y124783D01*
X1457883Y124908D01*
X1458092Y125075D01*
G01X1460150Y124700D02*
X1460442Y124742D01*
X1460775Y124867D01*
X1460983Y125075D01*
X1461067Y125367D01*
X1460983Y125658D01*
X1460733Y125908D01*
X1460358Y126033D01*
X1459942D01*
X1459692Y126117D01*
X1459483Y126325D01*
X1459400Y126617D01*
X1459525Y126908D01*
X1459817Y127117D01*
X1460150Y127200D01*
X1460483Y127117D01*
X1460775Y126908D01*
X1460900Y126617D01*
X1460817Y126325D01*
X1460608Y126117D01*
X1460358Y126033D01*
X1459942D01*
X1459567Y125908D01*
X1459317Y125658D01*
X1459233Y125367D01*
X1459317Y125075D01*
X1459525Y124867D01*
X1459858Y124742D01*
X1460150Y124700D01*
G01X1462458D02*
Y127200D01*
X1464042D01*
G01X1463458Y125992D02*
X1462458D01*
G01X1466350Y124700D02*
Y127200D01*
X1465850Y126700D01*
G01Y124700D02*
X1466850D01*
G01X1468658Y126783D02*
X1468908Y127033D01*
X1469200Y127158D01*
X1469533Y127200D01*
X1469950Y127117D01*
X1470242Y126908D01*
X1470325Y126658D01*
X1470283Y126408D01*
X1470117Y126200D01*
X1469283Y125783D01*
X1468908Y125492D01*
X1468658Y125075D01*
X1468575Y124700D01*
X1470325D01*
G01X1444709Y130992D02*
X1444459Y131117D01*
X1444167Y131200D01*
X1443834D01*
X1443459Y131075D01*
X1443167Y130867D01*
X1442959Y130617D01*
X1442792Y130200D01*
X1442750Y129825D01*
X1442834Y129450D01*
X1442959Y129200D01*
X1443209Y128950D01*
X1443500Y128783D01*
X1443792Y128700D01*
X1444084D01*
X1444375Y128783D01*
X1444625Y128908D01*
X1444834Y129075D01*
G01X1446892Y128700D02*
X1447184Y128742D01*
X1447517Y128867D01*
X1447725Y129075D01*
X1447809Y129367D01*
X1447725Y129658D01*
X1447475Y129908D01*
X1447100Y130033D01*
X1446684D01*
X1446434Y130117D01*
X1446225Y130325D01*
X1446142Y130617D01*
X1446267Y130908D01*
X1446559Y131117D01*
X1446892Y131200D01*
X1447225Y131117D01*
X1447517Y130908D01*
X1447642Y130617D01*
X1447559Y130325D01*
X1447350Y130117D01*
X1447100Y130033D01*
X1446684D01*
X1446309Y129908D01*
X1446059Y129658D01*
X1445975Y129367D01*
X1446059Y129075D01*
X1446267Y128867D01*
X1446600Y128742D01*
X1446892Y128700D01*
G01X1449200D02*
Y131200D01*
X1450784D01*
G01X1450200Y129992D02*
X1449200D01*
G01X1452300Y129742D02*
X1452592Y130033D01*
X1452842Y130200D01*
X1453175Y130283D01*
X1453467Y130200D01*
X1453675Y130033D01*
X1453842Y129783D01*
X1453884Y129492D01*
X1453842Y129242D01*
X1453675Y128992D01*
X1453425Y128783D01*
X1453134Y128700D01*
X1452800Y128783D01*
X1452509Y129033D01*
X1452342Y129408D01*
X1452300Y129825D01*
X1452384Y130367D01*
X1452509Y130658D01*
X1452717Y130950D01*
X1453009Y131158D01*
X1453300Y131200D01*
X1453592Y131117D01*
X1453800Y130908D01*
G01X1457967Y130792D02*
X1457717Y130917D01*
X1457425Y131000D01*
X1457092D01*
X1456717Y130875D01*
X1456425Y130667D01*
X1456217Y130417D01*
X1456050Y130000D01*
X1456008Y129625D01*
X1456092Y129250D01*
X1456217Y129000D01*
X1456467Y128750D01*
X1456758Y128583D01*
X1457050Y128500D01*
X1457342D01*
X1457633Y128583D01*
X1457883Y128708D01*
X1458092Y128875D01*
G01X1460150Y128500D02*
X1460442Y128542D01*
X1460775Y128667D01*
X1460983Y128875D01*
X1461067Y129167D01*
X1460983Y129458D01*
X1460733Y129708D01*
X1460358Y129833D01*
X1459942D01*
X1459692Y129917D01*
X1459483Y130125D01*
X1459400Y130417D01*
X1459525Y130708D01*
X1459817Y130917D01*
X1460150Y131000D01*
X1460483Y130917D01*
X1460775Y130708D01*
X1460900Y130417D01*
X1460817Y130125D01*
X1460608Y129917D01*
X1460358Y129833D01*
X1459942D01*
X1459567Y129708D01*
X1459317Y129458D01*
X1459233Y129167D01*
X1459317Y128875D01*
X1459525Y128667D01*
X1459858Y128542D01*
X1460150Y128500D01*
G01X1462458D02*
Y131000D01*
X1464042D01*
G01X1463458Y129792D02*
X1462458D01*
G01X1466267Y128500D02*
X1466350Y129042D01*
X1466475Y129500D01*
X1466642Y129917D01*
X1466850Y130375D01*
X1467183Y131000D01*
X1465517D01*
G01X1440726Y133768D02*
X1440674Y134036D01*
X1440519Y134343D01*
X1440261Y134535D01*
X1439899Y134611D01*
X1439538Y134535D01*
X1439228Y134305D01*
X1439073Y133960D01*
Y133576D01*
X1438969Y133346D01*
X1438711Y133155D01*
X1438349Y133078D01*
X1437988Y133193D01*
X1437729Y133461D01*
X1437626Y133768D01*
X1437729Y134075D01*
X1437988Y134343D01*
X1438349Y134458D01*
X1438711Y134381D01*
X1438969Y134190D01*
X1439073Y133960D01*
Y133576D01*
X1439228Y133231D01*
X1439538Y133001D01*
X1439899Y132925D01*
X1440261Y133001D01*
X1440519Y133193D01*
X1440674Y133500D01*
X1440726Y133768D01*
G01X1436985Y185678D02*
X1491080D01*
Y135482D01*
X1436985D01*
Y185678D01*
G01X1411990Y154767D02*
X1412240Y154975D01*
X1412407Y155225D01*
X1412490Y155517D01*
X1412407Y155850D01*
X1412240Y156100D01*
X1411990Y156350D01*
X1411657Y156433D01*
X1409990D01*
G01X1411448Y157908D02*
X1411157Y158200D01*
X1410990Y158450D01*
X1410907Y158783D01*
X1410990Y159075D01*
X1411157Y159283D01*
X1411407Y159450D01*
X1411698Y159492D01*
X1411948Y159450D01*
X1412198Y159283D01*
X1412407Y159033D01*
X1412490Y158742D01*
X1412407Y158408D01*
X1412157Y158117D01*
X1411782Y157950D01*
X1411365Y157908D01*
X1410823Y157992D01*
X1410532Y158117D01*
X1410240Y158325D01*
X1410032Y158617D01*
X1409990Y158908D01*
X1410073Y159200D01*
X1410282Y159408D01*
G01X1412490Y162633D02*
Y160967D01*
X1409990D01*
Y162633D01*
G01X1411198Y161967D02*
Y160967D01*
G01X1412490Y164900D02*
X1409990D01*
X1410490Y164400D01*
G01X1412490D02*
Y165400D01*
G01X1455639Y219993D02*
Y213993D01*
X1403839D01*
G01X1432890Y160943D02*
X1434682D01*
X1435057Y161110D01*
X1435307Y161443D01*
X1435390Y161860D01*
X1435307Y162277D01*
X1435057Y162610D01*
X1434682Y162777D01*
X1432890D01*
G01X1435390Y164960D02*
X1435348Y165252D01*
X1435223Y165585D01*
X1435015Y165793D01*
X1434723Y165877D01*
X1434432Y165793D01*
X1434182Y165543D01*
X1434057Y165168D01*
Y164752D01*
X1433973Y164502D01*
X1433765Y164293D01*
X1433473Y164210D01*
X1433182Y164335D01*
X1432973Y164627D01*
X1432890Y164960D01*
X1432973Y165293D01*
X1433182Y165585D01*
X1433473Y165710D01*
X1433765Y165627D01*
X1433973Y165418D01*
X1434057Y165168D01*
Y164752D01*
X1434182Y164377D01*
X1434432Y164127D01*
X1434723Y164043D01*
X1435015Y164127D01*
X1435223Y164335D01*
X1435348Y164668D01*
X1435390Y164960D01*
G01Y167268D02*
X1432890D01*
Y168852D01*
G01X1434098Y168268D02*
Y167268D01*
G01X1433307Y170368D02*
X1433057Y170618D01*
X1432932Y170910D01*
X1432890Y171243D01*
X1432973Y171660D01*
X1433182Y171952D01*
X1433432Y172035D01*
X1433682Y171993D01*
X1433890Y171827D01*
X1434307Y170993D01*
X1434598Y170618D01*
X1435015Y170368D01*
X1435390Y170285D01*
Y172035D01*
G01X1417494Y237725D02*
X1414394D01*
X1415014Y237265D01*
G01X1417494D02*
Y238185D01*
G01X1418062Y240748D02*
X1417391Y240902D01*
G01X1416874Y243082D02*
X1417236Y243312D01*
X1417442Y243618D01*
X1417494Y243963D01*
X1417442Y244270D01*
X1417184Y244577D01*
X1416874Y244768D01*
X1416564Y244807D01*
X1416202Y244730D01*
X1415944Y244462D01*
X1415841Y244193D01*
Y243848D01*
G01Y244193D02*
X1415686Y244423D01*
X1415427Y244615D01*
X1415117Y244692D01*
X1414807Y244615D01*
X1414549Y244423D01*
X1414394Y244078D01*
X1414446Y243733D01*
X1414652Y243388D01*
G01X1418062Y246948D02*
X1417391Y247102D01*
G01X1417494Y250048D02*
X1416822Y250125D01*
X1416254Y250240D01*
X1415737Y250393D01*
X1415169Y250585D01*
X1414394Y250892D01*
Y249358D01*
G01X1418062Y253148D02*
X1417391Y253302D01*
G01X1417132Y255673D02*
X1417391Y255942D01*
X1417494Y256248D01*
X1417391Y256555D01*
X1417081Y256823D01*
X1416616Y257015D01*
X1416151Y257092D01*
X1415582D01*
X1415117Y257015D01*
X1414704Y256823D01*
X1414497Y256593D01*
X1414394Y256325D01*
X1414497Y256018D01*
X1414704Y255788D01*
X1415014Y255635D01*
X1415427Y255558D01*
X1415789Y255635D01*
X1416151Y255827D01*
X1416357Y256057D01*
X1416409Y256325D01*
X1416306Y256632D01*
X1416047Y256862D01*
X1415582Y257092D01*
G01X1417494Y264743D02*
X1414394D01*
X1417494Y266507D01*
X1414394D01*
G01X1417494Y268725D02*
X1417442Y268418D01*
X1417236Y268150D01*
X1416926Y267920D01*
X1416564Y267767D01*
X1416151Y267690D01*
X1415737D01*
X1415324Y267767D01*
X1414962Y267920D01*
X1414652Y268150D01*
X1414446Y268418D01*
X1414394Y268725D01*
X1414446Y269032D01*
X1414652Y269300D01*
X1414962Y269530D01*
X1415324Y269683D01*
X1415737Y269760D01*
X1416151D01*
X1416564Y269683D01*
X1416926Y269530D01*
X1417236Y269300D01*
X1417442Y269032D01*
X1417494Y268725D01*
G01Y271058D02*
X1414394D01*
Y272017D01*
X1414549Y272323D01*
X1414756Y272515D01*
X1415169Y272592D01*
X1415582Y272515D01*
X1415841Y272285D01*
X1415996Y272017D01*
Y271058D01*
G01Y272017D02*
X1417494Y272592D01*
G01Y273928D02*
X1414394D01*
X1416977Y274925D01*
X1414394Y275922D01*
X1417494D01*
G01Y277067D02*
X1414394Y278025D01*
X1417494Y278983D01*
G01X1416409Y278638D02*
Y277412D01*
G01X1414394Y280358D02*
X1417494D01*
Y281892D01*
G01X1422594Y235335D02*
X1419494D01*
X1421716Y233917D01*
Y235833D01*
G01X1423162Y237898D02*
X1422491Y238052D01*
G01X1421302Y240347D02*
X1420941Y240615D01*
X1420734Y240845D01*
X1420631Y241152D01*
X1420734Y241420D01*
X1420941Y241612D01*
X1421251Y241765D01*
X1421612Y241803D01*
X1421922Y241765D01*
X1422232Y241612D01*
X1422491Y241382D01*
X1422594Y241113D01*
X1422491Y240807D01*
X1422181Y240538D01*
X1421716Y240385D01*
X1421199Y240347D01*
X1420527Y240423D01*
X1420166Y240538D01*
X1419804Y240730D01*
X1419546Y240998D01*
X1419494Y241267D01*
X1419597Y241535D01*
X1419856Y241727D01*
G01X1423162Y244098D02*
X1422491Y244252D01*
G01X1422594Y247275D02*
X1422542Y247543D01*
X1422387Y247850D01*
X1422129Y248042D01*
X1421767Y248118D01*
X1421406Y248042D01*
X1421096Y247812D01*
X1420941Y247467D01*
Y247083D01*
X1420837Y246853D01*
X1420579Y246662D01*
X1420217Y246585D01*
X1419856Y246700D01*
X1419597Y246968D01*
X1419494Y247275D01*
X1419597Y247582D01*
X1419856Y247850D01*
X1420217Y247965D01*
X1420579Y247888D01*
X1420837Y247697D01*
X1420941Y247467D01*
Y247083D01*
X1421096Y246738D01*
X1421406Y246508D01*
X1421767Y246432D01*
X1422129Y246508D01*
X1422387Y246700D01*
X1422542Y247007D01*
X1422594Y247275D01*
G01X1423162Y250298D02*
X1422491Y250452D01*
G01X1422594Y253475D02*
X1419494D01*
X1420114Y253015D01*
G01X1422594D02*
Y253935D01*
G01X1419494Y256575D02*
X1419597Y256268D01*
X1419856Y256038D01*
X1420166Y255885D01*
X1420579Y255770D01*
X1421044Y255732D01*
X1421509Y255770D01*
X1421922Y255885D01*
X1422232Y256038D01*
X1422491Y256268D01*
X1422594Y256575D01*
X1422491Y256882D01*
X1422232Y257112D01*
X1421922Y257265D01*
X1421509Y257380D01*
X1421044Y257418D01*
X1420579Y257380D01*
X1420166Y257265D01*
X1419856Y257112D01*
X1419597Y256882D01*
X1419494Y256575D01*
G01X1427940Y248732D02*
X1428302Y248962D01*
X1428508Y249268D01*
X1428560Y249613D01*
X1428508Y249920D01*
X1428250Y250227D01*
X1427940Y250418D01*
X1427630Y250457D01*
X1427268Y250380D01*
X1427010Y250112D01*
X1426907Y249843D01*
Y249498D01*
G01Y249843D02*
X1426752Y250073D01*
X1426493Y250265D01*
X1426183Y250342D01*
X1425873Y250265D01*
X1425615Y250073D01*
X1425460Y249728D01*
X1425512Y249383D01*
X1425718Y249038D01*
G01X1429128Y252598D02*
X1428457Y252752D01*
G01X1428095Y254932D02*
X1428353Y255162D01*
X1428508Y255430D01*
X1428560Y255775D01*
X1428457Y256120D01*
X1428250Y256388D01*
X1427888Y256580D01*
X1427475Y256618D01*
X1427062Y256542D01*
X1426803Y256350D01*
X1426597Y256082D01*
X1426545Y255813D01*
X1426597Y255545D01*
X1426803Y255200D01*
X1425460Y255315D01*
Y256350D01*
G01X1426907Y262282D02*
X1426752Y262435D01*
X1426493Y262550D01*
X1426132Y262627D01*
X1425822Y262550D01*
X1425615Y262397D01*
X1425460Y262128D01*
Y261093D01*
X1428560D01*
Y262358D01*
X1428353Y262627D01*
X1428043Y262780D01*
X1427682Y262857D01*
X1427320Y262780D01*
X1427010Y262550D01*
X1426907Y262282D01*
Y261093D01*
G01X1428560Y264078D02*
X1425460D01*
X1428043Y265075D01*
X1425460Y266072D01*
X1428560D01*
G01X1425718Y269018D02*
X1425563Y268788D01*
X1425460Y268520D01*
Y268213D01*
X1425615Y267868D01*
X1425873Y267600D01*
X1426183Y267408D01*
X1426700Y267255D01*
X1427165Y267217D01*
X1427630Y267293D01*
X1427940Y267408D01*
X1428250Y267638D01*
X1428457Y267907D01*
X1428560Y268175D01*
Y268443D01*
X1428457Y268712D01*
X1428302Y268942D01*
X1428095Y269133D01*
G01X1428147Y273570D02*
X1428405Y273877D01*
X1428560Y274222D01*
Y274528D01*
X1428405Y274835D01*
X1428147Y275065D01*
X1427785Y275180D01*
X1427423Y275103D01*
X1427113Y274912D01*
X1426907Y274567D01*
X1426803Y274107D01*
X1426597Y273838D01*
X1426235Y273723D01*
X1425873Y273800D01*
X1425615Y273992D01*
X1425460Y274260D01*
Y274528D01*
X1425563Y274797D01*
X1425822Y275027D01*
G01X1428560Y278242D02*
Y276708D01*
X1425460D01*
Y278242D01*
G01X1426958Y277628D02*
Y276708D01*
G01X1425460Y280575D02*
X1428560D01*
G01X1425460Y279693D02*
Y281457D01*
G01Y286775D02*
X1428560D01*
G01X1425460Y285893D02*
Y287657D01*
G01X1428560Y289875D02*
X1428508Y289568D01*
X1428302Y289300D01*
X1427992Y289070D01*
X1427630Y288917D01*
X1427217Y288840D01*
X1426803D01*
X1426390Y288917D01*
X1426028Y289070D01*
X1425718Y289300D01*
X1425512Y289568D01*
X1425460Y289875D01*
X1425512Y290182D01*
X1425718Y290450D01*
X1426028Y290680D01*
X1426390Y290833D01*
X1426803Y290910D01*
X1427217D01*
X1427630Y290833D01*
X1427992Y290680D01*
X1428302Y290450D01*
X1428508Y290182D01*
X1428560Y289875D01*
G01Y295270D02*
X1425460D01*
G01Y296880D02*
X1428560D01*
G01X1427010D02*
Y295270D01*
G01X1425460Y298447D02*
Y299903D01*
X1428560Y298447D01*
Y299903D01*
G01X1411190Y233508D02*
X1411500Y233700D01*
X1411707Y233930D01*
X1411810Y234198D01*
X1411707Y234505D01*
X1411500Y234735D01*
X1411190Y234965D01*
X1410777Y235042D01*
X1408710D01*
G01X1411810Y237375D02*
X1411758Y237643D01*
X1411603Y237950D01*
X1411345Y238142D01*
X1410983Y238218D01*
X1410622Y238142D01*
X1410312Y237912D01*
X1410157Y237567D01*
Y237183D01*
X1410053Y236953D01*
X1409795Y236762D01*
X1409433Y236685D01*
X1409072Y236800D01*
X1408813Y237068D01*
X1408710Y237375D01*
X1408813Y237682D01*
X1409072Y237950D01*
X1409433Y238065D01*
X1409795Y237988D01*
X1410053Y237797D01*
X1410157Y237567D01*
Y237183D01*
X1410312Y236838D01*
X1410622Y236608D01*
X1410983Y236532D01*
X1411345Y236608D01*
X1411603Y236800D01*
X1411758Y237107D01*
X1411810Y237375D01*
G01X1410260Y240705D02*
Y241472D01*
X1411190D01*
X1411500Y241242D01*
X1411707Y240973D01*
X1411810Y240590D01*
X1411707Y240207D01*
X1411500Y239938D01*
X1411190Y239708D01*
X1410828Y239555D01*
X1410415Y239478D01*
X1410053D01*
X1409743Y239555D01*
X1409382Y239708D01*
X1409072Y239938D01*
X1408865Y240168D01*
X1408710Y240475D01*
Y240743D01*
X1408813Y241050D01*
X1409020Y241280D01*
G01X1409227Y242847D02*
X1408917Y243077D01*
X1408762Y243345D01*
X1408710Y243652D01*
X1408813Y244035D01*
X1409072Y244303D01*
X1409382Y244380D01*
X1409692Y244342D01*
X1409950Y244188D01*
X1410467Y243422D01*
X1410828Y243077D01*
X1411345Y242847D01*
X1411810Y242770D01*
Y244380D01*
G01X1413160Y300000D02*
Y232825D01*
X1424160D01*
G01D02*
X1430160D01*
Y258725D01*
X1413160D01*
G01X1424160Y232825D02*
Y301825D01*
X1421000D01*
G01X1430160Y281656D02*
Y258725D01*
G01X1454945Y259386D02*
Y261886D01*
X1455986D01*
X1456320Y261761D01*
X1456528Y261594D01*
X1456611Y261261D01*
X1456528Y260928D01*
X1456278Y260719D01*
X1455986Y260594D01*
X1454945D01*
G01X1455986D02*
X1456611Y259386D01*
G01X1458795D02*
X1458878Y259928D01*
X1459003Y260386D01*
X1459170Y260803D01*
X1459378Y261261D01*
X1459711Y261886D01*
X1458045D01*
G01X1462811Y259386D02*
X1461145D01*
Y261886D01*
X1462811D01*
G01X1462145Y260678D02*
X1461145D01*
G01X1464286Y260428D02*
X1464578Y260719D01*
X1464828Y260886D01*
X1465161Y260969D01*
X1465453Y260886D01*
X1465661Y260719D01*
X1465828Y260469D01*
X1465870Y260178D01*
X1465828Y259928D01*
X1465661Y259678D01*
X1465411Y259469D01*
X1465120Y259386D01*
X1464786Y259469D01*
X1464495Y259719D01*
X1464328Y260094D01*
X1464286Y260511D01*
X1464370Y261053D01*
X1464495Y261344D01*
X1464703Y261636D01*
X1464995Y261844D01*
X1465286Y261886D01*
X1465578Y261803D01*
X1465786Y261594D01*
G01X1440837Y246855D02*
Y249355D01*
X1441878D01*
X1442212Y249230D01*
X1442420Y249063D01*
X1442503Y248730D01*
X1442420Y248397D01*
X1442170Y248188D01*
X1441878Y248063D01*
X1440837D01*
G01X1441878D02*
X1442503Y246855D01*
G01X1444687D02*
X1444770Y247397D01*
X1444895Y247855D01*
X1445062Y248272D01*
X1445270Y248730D01*
X1445603Y249355D01*
X1443937D01*
G01X1448703Y246855D02*
X1447037D01*
Y249355D01*
X1448703D01*
G01X1448037Y248147D02*
X1447037D01*
G01X1450053Y247230D02*
X1450303Y247022D01*
X1450595Y246897D01*
X1450970Y246855D01*
X1451345Y246938D01*
X1451637Y247105D01*
X1451845Y247397D01*
X1451887Y247730D01*
X1451803Y248063D01*
X1451595Y248272D01*
X1451303Y248438D01*
X1451012Y248480D01*
X1450720Y248438D01*
X1450345Y248272D01*
X1450470Y249355D01*
X1451595D01*
G01X1437269Y260872D02*
X1438227Y263972D01*
X1439185Y260872D01*
G01X1438840Y261957D02*
X1437614D01*
G01X1441327Y260872D02*
Y263972D01*
X1440867Y263352D01*
G01Y260872D02*
X1441787D01*
G01X1443699Y262164D02*
X1443967Y262525D01*
X1444197Y262732D01*
X1444504Y262835D01*
X1444772Y262732D01*
X1444964Y262525D01*
X1445117Y262215D01*
X1445155Y261854D01*
X1445117Y261544D01*
X1444964Y261234D01*
X1444734Y260975D01*
X1444465Y260872D01*
X1444159Y260975D01*
X1443890Y261285D01*
X1443737Y261750D01*
X1443699Y262267D01*
X1443775Y262939D01*
X1443890Y263300D01*
X1444082Y263662D01*
X1444350Y263920D01*
X1444619Y263972D01*
X1444887Y263869D01*
X1445079Y263610D01*
G01X1436137Y274778D02*
X1437929D01*
X1438304Y274945D01*
X1438554Y275278D01*
X1438637Y275695D01*
X1438554Y276112D01*
X1438304Y276445D01*
X1437929Y276612D01*
X1436137D01*
G01X1438637Y278795D02*
X1438595Y279087D01*
X1438470Y279420D01*
X1438262Y279628D01*
X1437970Y279712D01*
X1437679Y279628D01*
X1437429Y279378D01*
X1437304Y279003D01*
Y278587D01*
X1437220Y278337D01*
X1437012Y278128D01*
X1436720Y278045D01*
X1436429Y278170D01*
X1436220Y278462D01*
X1436137Y278795D01*
X1436220Y279128D01*
X1436429Y279420D01*
X1436720Y279545D01*
X1437012Y279462D01*
X1437220Y279253D01*
X1437304Y279003D01*
Y278587D01*
X1437429Y278212D01*
X1437679Y277962D01*
X1437970Y277878D01*
X1438262Y277962D01*
X1438470Y278170D01*
X1438595Y278503D01*
X1438637Y278795D01*
G01Y280978D02*
X1436137D01*
Y281812D01*
X1436262Y282145D01*
X1436429Y282395D01*
X1436679Y282603D01*
X1436970Y282770D01*
X1437387Y282812D01*
X1437804Y282770D01*
X1438095Y282603D01*
X1438345Y282395D01*
X1438512Y282145D01*
X1438637Y281812D01*
Y280978D01*
G01Y284912D02*
X1438095Y284995D01*
X1437637Y285120D01*
X1437220Y285287D01*
X1436762Y285495D01*
X1436137Y285828D01*
Y284162D01*
G01X1495059Y264941D02*
X1439941D01*
Y320059D01*
X1495059D01*
Y264941D01*
G01X1424160Y301825D02*
X1430160D01*
Y289771D01*
G01X1417500Y301825D02*
X1415500D01*
G01X1437022Y288409D02*
X1434522D01*
Y289450D01*
X1434647Y289784D01*
X1434814Y289992D01*
X1435147Y290075D01*
X1435480Y289992D01*
X1435689Y289742D01*
X1435814Y289450D01*
Y288409D01*
G01Y289450D02*
X1437022Y290075D01*
G01Y292259D02*
X1436480Y292342D01*
X1436022Y292467D01*
X1435605Y292634D01*
X1435147Y292842D01*
X1434522Y293175D01*
Y291509D01*
G01X1437022Y294525D02*
X1434522D01*
Y295359D01*
X1434647Y295692D01*
X1434814Y295942D01*
X1435064Y296150D01*
X1435355Y296317D01*
X1435772Y296359D01*
X1436189Y296317D01*
X1436480Y296150D01*
X1436730Y295942D01*
X1436897Y295692D01*
X1437022Y295359D01*
Y294525D01*
G01Y299042D02*
X1434522D01*
X1436314Y297500D01*
Y299584D01*
G01X1434939Y300850D02*
X1434689Y301100D01*
X1434564Y301392D01*
X1434522Y301725D01*
X1434605Y302142D01*
X1434814Y302434D01*
X1435064Y302517D01*
X1435314Y302475D01*
X1435522Y302309D01*
X1435939Y301475D01*
X1436230Y301100D01*
X1436647Y300850D01*
X1437022Y300767D01*
Y302517D01*
G01X1435549Y312909D02*
X1438649D01*
G01X1435549Y312027D02*
Y313791D01*
G01X1438649Y316009D02*
X1435549D01*
X1436169Y315549D01*
G01X1438649D02*
Y316469D01*
G01X1437357Y318381D02*
X1436996Y318649D01*
X1436789Y318879D01*
X1436686Y319186D01*
X1436789Y319454D01*
X1436996Y319646D01*
X1437306Y319799D01*
X1437667Y319837D01*
X1437977Y319799D01*
X1438287Y319646D01*
X1438546Y319416D01*
X1438649Y319147D01*
X1438546Y318841D01*
X1438236Y318572D01*
X1437771Y318419D01*
X1437254Y318381D01*
X1436582Y318457D01*
X1436221Y318572D01*
X1435859Y318764D01*
X1435601Y319032D01*
X1435549Y319301D01*
X1435652Y319569D01*
X1435911Y319761D01*
G01X1464205Y401155D02*
X1461705D01*
Y402196D01*
X1461830Y402530D01*
X1461997Y402738D01*
X1462330Y402821D01*
X1462663Y402738D01*
X1462872Y402488D01*
X1462997Y402196D01*
Y401155D01*
G01Y402196D02*
X1464205Y402821D01*
G01Y405005D02*
X1463663Y405088D01*
X1463205Y405213D01*
X1462788Y405380D01*
X1462330Y405588D01*
X1461705Y405921D01*
Y404255D01*
G01X1461913Y409105D02*
X1461788Y408855D01*
X1461705Y408563D01*
Y408230D01*
X1461830Y407855D01*
X1462038Y407563D01*
X1462288Y407355D01*
X1462705Y407188D01*
X1463080Y407146D01*
X1463455Y407230D01*
X1463705Y407355D01*
X1463955Y407605D01*
X1464122Y407896D01*
X1464205Y408188D01*
Y408480D01*
X1464122Y408771D01*
X1463997Y409021D01*
X1463830Y409230D01*
G01Y410371D02*
X1464038Y410621D01*
X1464163Y410913D01*
X1464205Y411288D01*
X1464122Y411663D01*
X1463955Y411955D01*
X1463663Y412163D01*
X1463330Y412205D01*
X1462997Y412121D01*
X1462788Y411913D01*
X1462622Y411621D01*
X1462580Y411330D01*
X1462622Y411038D01*
X1462788Y410663D01*
X1461705Y410788D01*
Y411913D01*
G01X1432517Y372467D02*
Y374967D01*
X1433558D01*
X1433892Y374842D01*
X1434100Y374675D01*
X1434183Y374342D01*
X1434100Y374009D01*
X1433850Y373800D01*
X1433558Y373675D01*
X1432517D01*
G01X1433558D02*
X1434183Y372467D01*
G01X1436367D02*
X1436450Y373009D01*
X1436575Y373467D01*
X1436742Y373884D01*
X1436950Y374342D01*
X1437283Y374967D01*
X1435617D01*
G01X1440467Y374759D02*
X1440217Y374884D01*
X1439925Y374967D01*
X1439592D01*
X1439217Y374842D01*
X1438925Y374634D01*
X1438717Y374384D01*
X1438550Y373967D01*
X1438508Y373592D01*
X1438592Y373217D01*
X1438717Y372967D01*
X1438967Y372717D01*
X1439258Y372550D01*
X1439550Y372467D01*
X1439842D01*
X1440133Y372550D01*
X1440383Y372675D01*
X1440592Y372842D01*
G01X1442650Y372467D02*
X1442942Y372509D01*
X1443275Y372634D01*
X1443483Y372842D01*
X1443567Y373134D01*
X1443483Y373425D01*
X1443233Y373675D01*
X1442858Y373800D01*
X1442442D01*
X1442192Y373884D01*
X1441983Y374092D01*
X1441900Y374384D01*
X1442025Y374675D01*
X1442317Y374884D01*
X1442650Y374967D01*
X1442983Y374884D01*
X1443275Y374675D01*
X1443400Y374384D01*
X1443317Y374092D01*
X1443108Y373884D01*
X1442858Y373800D01*
X1442442D01*
X1442067Y373675D01*
X1441817Y373425D01*
X1441733Y373134D01*
X1441817Y372842D01*
X1442025Y372634D01*
X1442358Y372509D01*
X1442650Y372467D01*
G01X1439590Y353520D02*
X1437090D01*
Y354561D01*
X1437215Y354895D01*
X1437382Y355103D01*
X1437715Y355186D01*
X1438048Y355103D01*
X1438257Y354853D01*
X1438382Y354561D01*
Y353520D01*
G01Y354561D02*
X1439590Y355186D01*
G01Y357370D02*
X1439048Y357453D01*
X1438590Y357578D01*
X1438173Y357745D01*
X1437715Y357953D01*
X1437090Y358286D01*
Y356620D01*
G01X1437298Y361470D02*
X1437173Y361220D01*
X1437090Y360928D01*
Y360595D01*
X1437215Y360220D01*
X1437423Y359928D01*
X1437673Y359720D01*
X1438090Y359553D01*
X1438465Y359511D01*
X1438840Y359595D01*
X1439090Y359720D01*
X1439340Y359970D01*
X1439507Y360261D01*
X1439590Y360553D01*
Y360845D01*
X1439507Y361136D01*
X1439382Y361386D01*
X1439215Y361595D01*
G01X1437507Y362861D02*
X1437257Y363111D01*
X1437132Y363403D01*
X1437090Y363736D01*
X1437173Y364153D01*
X1437382Y364445D01*
X1437632Y364528D01*
X1437882Y364486D01*
X1438090Y364320D01*
X1438507Y363486D01*
X1438798Y363111D01*
X1439215Y362861D01*
X1439590Y362778D01*
Y364528D01*
G01X1439090Y365836D02*
X1439382Y366086D01*
X1439548Y366420D01*
X1439590Y366795D01*
X1439548Y367128D01*
X1439340Y367461D01*
X1439090Y367670D01*
X1438840Y367711D01*
X1438548Y367628D01*
X1438340Y367336D01*
X1438257Y367045D01*
Y366670D01*
G01Y367045D02*
X1438132Y367295D01*
X1437923Y367503D01*
X1437673Y367586D01*
X1437423Y367503D01*
X1437215Y367295D01*
X1437090Y366920D01*
X1437132Y366545D01*
X1437298Y366170D01*
G01X1461936Y370042D02*
X1459436D01*
Y371083D01*
X1459561Y371417D01*
X1459728Y371625D01*
X1460061Y371708D01*
X1460394Y371625D01*
X1460603Y371375D01*
X1460728Y371083D01*
Y370042D01*
G01Y371083D02*
X1461936Y371708D01*
G01Y373892D02*
X1461394Y373975D01*
X1460936Y374100D01*
X1460519Y374267D01*
X1460061Y374475D01*
X1459436Y374808D01*
Y373142D01*
G01Y375825D02*
X1461936Y376408D01*
X1459436Y377075D01*
X1461936Y377742D01*
X1459436Y378325D01*
G01X1461936Y380175D02*
X1459436D01*
X1459936Y379675D01*
G01X1461936D02*
Y380675D01*
G01X1439100Y383217D02*
X1436600D01*
Y384258D01*
X1436725Y384592D01*
X1436892Y384800D01*
X1437225Y384883D01*
X1437558Y384800D01*
X1437767Y384550D01*
X1437892Y384258D01*
Y383217D01*
G01Y384258D02*
X1439100Y384883D01*
G01Y387067D02*
X1438558Y387150D01*
X1438100Y387275D01*
X1437683Y387442D01*
X1437225Y387650D01*
X1436600Y387983D01*
Y386317D01*
G01Y389000D02*
X1439100Y389583D01*
X1436600Y390250D01*
X1439100Y390917D01*
X1436600Y391500D01*
G01X1438808Y392642D02*
X1439017Y392933D01*
X1439100Y393267D01*
X1439017Y393600D01*
X1438767Y393892D01*
X1438392Y394100D01*
X1438017Y394183D01*
X1437558D01*
X1437183Y394100D01*
X1436850Y393892D01*
X1436683Y393642D01*
X1436600Y393350D01*
X1436683Y393017D01*
X1436850Y392767D01*
X1437100Y392600D01*
X1437433Y392517D01*
X1437725Y392600D01*
X1438017Y392808D01*
X1438183Y393058D01*
X1438225Y393350D01*
X1438142Y393683D01*
X1437933Y393933D01*
X1437558Y394183D01*
G01X1430700Y385417D02*
X1428200D01*
Y386458D01*
X1428325Y386792D01*
X1428492Y387000D01*
X1428825Y387083D01*
X1429158Y387000D01*
X1429367Y386750D01*
X1429492Y386458D01*
Y385417D01*
G01Y386458D02*
X1430700Y387083D01*
G01Y389267D02*
X1430158Y389350D01*
X1429700Y389475D01*
X1429283Y389642D01*
X1428825Y389850D01*
X1428200Y390183D01*
Y388517D01*
G01X1428408Y393367D02*
X1428283Y393117D01*
X1428200Y392825D01*
Y392492D01*
X1428325Y392117D01*
X1428533Y391825D01*
X1428783Y391617D01*
X1429200Y391450D01*
X1429575Y391408D01*
X1429950Y391492D01*
X1430200Y391617D01*
X1430450Y391867D01*
X1430617Y392158D01*
X1430700Y392450D01*
Y392742D01*
X1430617Y393033D01*
X1430492Y393283D01*
X1430325Y393492D01*
G01X1429658Y394758D02*
X1429367Y395050D01*
X1429200Y395300D01*
X1429117Y395633D01*
X1429200Y395925D01*
X1429367Y396133D01*
X1429617Y396300D01*
X1429908Y396342D01*
X1430158Y396300D01*
X1430408Y396133D01*
X1430617Y395883D01*
X1430700Y395592D01*
X1430617Y395258D01*
X1430367Y394967D01*
X1429992Y394800D01*
X1429575Y394758D01*
X1429033Y394842D01*
X1428742Y394967D01*
X1428450Y395175D01*
X1428242Y395467D01*
X1428200Y395758D01*
X1428283Y396050D01*
X1428492Y396258D01*
G01X1426672Y404112D02*
X1426422Y404237D01*
X1426130Y404320D01*
X1425797D01*
X1425422Y404195D01*
X1425130Y403987D01*
X1424922Y403737D01*
X1424755Y403320D01*
X1424713Y402945D01*
X1424797Y402570D01*
X1424922Y402320D01*
X1425172Y402070D01*
X1425463Y401903D01*
X1425755Y401820D01*
X1426047D01*
X1426338Y401903D01*
X1426588Y402028D01*
X1426797Y402195D01*
G01X1428772Y401820D02*
X1428855Y402362D01*
X1428980Y402820D01*
X1429147Y403237D01*
X1429355Y403695D01*
X1429688Y404320D01*
X1428022D01*
G01X1432872Y404112D02*
X1432622Y404237D01*
X1432330Y404320D01*
X1431997D01*
X1431622Y404195D01*
X1431330Y403987D01*
X1431122Y403737D01*
X1430955Y403320D01*
X1430913Y402945D01*
X1430997Y402570D01*
X1431122Y402320D01*
X1431372Y402070D01*
X1431663Y401903D01*
X1431955Y401820D01*
X1432247D01*
X1432538Y401903D01*
X1432788Y402028D01*
X1432997Y402195D01*
G01X1434347Y402112D02*
X1434638Y401903D01*
X1434972Y401820D01*
X1435305Y401903D01*
X1435597Y402153D01*
X1435805Y402528D01*
X1435888Y402903D01*
Y403362D01*
X1435805Y403737D01*
X1435597Y404070D01*
X1435347Y404237D01*
X1435055Y404320D01*
X1434722Y404237D01*
X1434472Y404070D01*
X1434305Y403820D01*
X1434222Y403487D01*
X1434305Y403195D01*
X1434513Y402903D01*
X1434763Y402737D01*
X1435055Y402695D01*
X1435388Y402778D01*
X1435638Y402987D01*
X1435888Y403362D01*
G01X1433590Y353436D02*
X1435382D01*
X1435757Y353603D01*
X1436007Y353936D01*
X1436090Y354353D01*
X1436007Y354770D01*
X1435757Y355103D01*
X1435382Y355270D01*
X1433590D01*
G01X1436090Y357370D02*
X1435548Y357453D01*
X1435090Y357578D01*
X1434673Y357745D01*
X1434215Y357953D01*
X1433590Y358286D01*
Y356620D01*
G01X1436090Y359636D02*
X1433590D01*
Y360470D01*
X1433715Y360803D01*
X1433882Y361053D01*
X1434132Y361261D01*
X1434423Y361428D01*
X1434840Y361470D01*
X1435257Y361428D01*
X1435548Y361261D01*
X1435798Y361053D01*
X1435965Y360803D01*
X1436090Y360470D01*
Y359636D01*
G01Y363653D02*
X1433590D01*
X1434090Y363153D01*
G01X1436090D02*
Y364153D01*
G01X1428508Y370417D02*
X1428383Y370167D01*
X1428300Y369875D01*
Y369542D01*
X1428425Y369167D01*
X1428633Y368875D01*
X1428883Y368667D01*
X1429300Y368500D01*
X1429675Y368458D01*
X1430050Y368542D01*
X1430300Y368667D01*
X1430550Y368917D01*
X1430717Y369208D01*
X1430800Y369500D01*
Y369792D01*
X1430717Y370083D01*
X1430592Y370333D01*
X1430425Y370542D01*
G01X1430800Y372517D02*
X1430258Y372600D01*
X1429800Y372725D01*
X1429383Y372892D01*
X1428925Y373100D01*
X1428300Y373433D01*
Y371767D01*
G01X1428508Y376617D02*
X1428383Y376367D01*
X1428300Y376075D01*
Y375742D01*
X1428425Y375367D01*
X1428633Y375075D01*
X1428883Y374867D01*
X1429300Y374700D01*
X1429675Y374658D01*
X1430050Y374742D01*
X1430300Y374867D01*
X1430550Y375117D01*
X1430717Y375408D01*
X1430800Y375700D01*
Y375992D01*
X1430717Y376283D01*
X1430592Y376533D01*
X1430425Y376742D01*
G01X1430800Y378800D02*
X1428300D01*
X1428800Y378300D01*
G01X1430800D02*
Y379300D01*
G01X1430425Y380983D02*
X1430633Y381233D01*
X1430758Y381525D01*
X1430800Y381900D01*
X1430717Y382275D01*
X1430550Y382567D01*
X1430258Y382775D01*
X1429925Y382817D01*
X1429592Y382733D01*
X1429383Y382525D01*
X1429217Y382233D01*
X1429175Y381942D01*
X1429217Y381650D01*
X1429383Y381275D01*
X1428300Y381400D01*
Y382525D01*
G01X1455926Y394263D02*
X1455801Y394013D01*
X1455718Y393721D01*
Y393388D01*
X1455843Y393013D01*
X1456051Y392721D01*
X1456301Y392513D01*
X1456718Y392346D01*
X1457093Y392304D01*
X1457468Y392388D01*
X1457718Y392513D01*
X1457968Y392763D01*
X1458135Y393054D01*
X1458218Y393346D01*
Y393638D01*
X1458135Y393929D01*
X1458010Y394179D01*
X1457843Y394388D01*
G01X1458218Y396363D02*
X1457676Y396446D01*
X1457218Y396571D01*
X1456801Y396738D01*
X1456343Y396946D01*
X1455718Y397279D01*
Y395613D01*
G01X1455926Y400463D02*
X1455801Y400213D01*
X1455718Y399921D01*
Y399588D01*
X1455843Y399213D01*
X1456051Y398921D01*
X1456301Y398713D01*
X1456718Y398546D01*
X1457093Y398504D01*
X1457468Y398588D01*
X1457718Y398713D01*
X1457968Y398963D01*
X1458135Y399254D01*
X1458218Y399546D01*
Y399838D01*
X1458135Y400129D01*
X1458010Y400379D01*
X1457843Y400588D01*
G01X1458218Y402646D02*
X1455718D01*
X1456218Y402146D01*
G01X1458218D02*
Y403146D01*
G01X1457718Y404829D02*
X1458010Y405079D01*
X1458176Y405413D01*
X1458218Y405788D01*
X1458176Y406121D01*
X1457968Y406454D01*
X1457718Y406663D01*
X1457468Y406704D01*
X1457176Y406621D01*
X1456968Y406329D01*
X1456885Y406038D01*
Y405663D01*
G01Y406038D02*
X1456760Y406288D01*
X1456551Y406496D01*
X1456301Y406579D01*
X1456051Y406496D01*
X1455843Y406288D01*
X1455718Y405913D01*
X1455760Y405538D01*
X1455926Y405163D01*
G01X1430298Y355270D02*
X1430173Y355020D01*
X1430090Y354728D01*
Y354395D01*
X1430215Y354020D01*
X1430423Y353728D01*
X1430673Y353520D01*
X1431090Y353353D01*
X1431465Y353311D01*
X1431840Y353395D01*
X1432090Y353520D01*
X1432340Y353770D01*
X1432507Y354061D01*
X1432590Y354353D01*
Y354645D01*
X1432507Y354936D01*
X1432382Y355186D01*
X1432215Y355395D01*
G01X1432590Y357370D02*
X1432048Y357453D01*
X1431590Y357578D01*
X1431173Y357745D01*
X1430715Y357953D01*
X1430090Y358286D01*
Y356620D01*
G01X1432590Y359636D02*
X1430090D01*
Y360470D01*
X1430215Y360803D01*
X1430382Y361053D01*
X1430632Y361261D01*
X1430923Y361428D01*
X1431340Y361470D01*
X1431757Y361428D01*
X1432048Y361261D01*
X1432298Y361053D01*
X1432465Y360803D01*
X1432590Y360470D01*
Y359636D01*
G01Y363653D02*
X1430090D01*
X1430590Y363153D01*
G01X1432590D02*
Y364153D01*
G01X1426334Y381850D02*
X1425209D01*
X1423834Y381017D01*
G01Y382683D02*
X1425209Y381850D01*
G01X1426334Y384867D02*
X1425792Y384950D01*
X1425334Y385075D01*
X1424917Y385242D01*
X1424459Y385450D01*
X1423834Y385783D01*
Y384117D01*
G01X1424042Y388967D02*
X1423917Y388717D01*
X1423834Y388425D01*
Y388092D01*
X1423959Y387717D01*
X1424167Y387425D01*
X1424417Y387217D01*
X1424834Y387050D01*
X1425209Y387008D01*
X1425584Y387092D01*
X1425834Y387217D01*
X1426084Y387467D01*
X1426251Y387758D01*
X1426334Y388050D01*
Y388342D01*
X1426251Y388633D01*
X1426126Y388883D01*
X1425959Y389092D01*
G01X1424251Y390358D02*
X1424001Y390608D01*
X1423876Y390900D01*
X1423834Y391233D01*
X1423917Y391650D01*
X1424126Y391942D01*
X1424376Y392025D01*
X1424626Y391983D01*
X1424834Y391817D01*
X1425251Y390983D01*
X1425542Y390608D01*
X1425959Y390358D01*
X1426334Y390275D01*
Y392025D01*
G01X1443350Y386300D02*
Y389700D01*
G01X1449650Y386300D02*
Y389700D01*
G01X1406632Y460140D02*
X1407590Y463240D01*
X1408548Y460140D01*
G01X1408203Y461225D02*
X1406977D01*
G01X1409962Y462723D02*
X1410192Y463033D01*
X1410460Y463188D01*
X1410767Y463240D01*
X1411150Y463137D01*
X1411418Y462878D01*
X1411495Y462568D01*
X1411457Y462258D01*
X1411303Y462000D01*
X1410537Y461483D01*
X1410192Y461122D01*
X1409962Y460605D01*
X1409885Y460140D01*
X1411495D01*
G01X1413790Y463240D02*
X1413483Y463137D01*
X1413253Y462878D01*
X1413100Y462568D01*
X1412985Y462155D01*
X1412947Y461690D01*
X1412985Y461225D01*
X1413100Y460812D01*
X1413253Y460502D01*
X1413483Y460243D01*
X1413790Y460140D01*
X1414097Y460243D01*
X1414327Y460502D01*
X1414480Y460812D01*
X1414595Y461225D01*
X1414633Y461690D01*
X1414595Y462155D01*
X1414480Y462568D01*
X1414327Y462878D01*
X1414097Y463137D01*
X1413790Y463240D01*
G01X1426817Y412467D02*
Y414967D01*
X1427858D01*
X1428192Y414842D01*
X1428400Y414675D01*
X1428483Y414342D01*
X1428400Y414009D01*
X1428150Y413800D01*
X1427858Y413675D01*
X1426817D01*
G01X1427858D02*
X1428483Y412467D01*
G01X1430667D02*
X1430750Y413009D01*
X1430875Y413467D01*
X1431042Y413884D01*
X1431250Y414342D01*
X1431583Y414967D01*
X1429917D01*
G01X1434767Y414759D02*
X1434517Y414884D01*
X1434225Y414967D01*
X1433892D01*
X1433517Y414842D01*
X1433225Y414634D01*
X1433017Y414384D01*
X1432850Y413967D01*
X1432808Y413592D01*
X1432892Y413217D01*
X1433017Y412967D01*
X1433267Y412717D01*
X1433558Y412550D01*
X1433850Y412467D01*
X1434142D01*
X1434433Y412550D01*
X1434683Y412675D01*
X1434892Y412842D01*
G01X1436158Y414550D02*
X1436408Y414800D01*
X1436700Y414925D01*
X1437033Y414967D01*
X1437450Y414884D01*
X1437742Y414675D01*
X1437825Y414425D01*
X1437783Y414175D01*
X1437617Y413967D01*
X1436783Y413550D01*
X1436408Y413259D01*
X1436158Y412842D01*
X1436075Y412467D01*
X1437825D01*
G01X1426817Y408567D02*
Y411067D01*
X1427858D01*
X1428192Y410942D01*
X1428400Y410775D01*
X1428483Y410442D01*
X1428400Y410109D01*
X1428150Y409900D01*
X1427858Y409775D01*
X1426817D01*
G01X1427858D02*
X1428483Y408567D01*
G01X1430667D02*
X1430750Y409109D01*
X1430875Y409567D01*
X1431042Y409984D01*
X1431250Y410442D01*
X1431583Y411067D01*
X1429917D01*
G01X1434767Y410859D02*
X1434517Y410984D01*
X1434225Y411067D01*
X1433892D01*
X1433517Y410942D01*
X1433225Y410734D01*
X1433017Y410484D01*
X1432850Y410067D01*
X1432808Y409692D01*
X1432892Y409317D01*
X1433017Y409067D01*
X1433267Y408817D01*
X1433558Y408650D01*
X1433850Y408567D01*
X1434142D01*
X1434433Y408650D01*
X1434683Y408775D01*
X1434892Y408942D01*
G01X1437450Y408567D02*
Y411067D01*
X1435908Y409275D01*
X1437992D01*
G01X1461877Y417513D02*
X1459377D01*
Y418554D01*
X1459502Y418888D01*
X1459669Y419096D01*
X1460002Y419179D01*
X1460335Y419096D01*
X1460544Y418846D01*
X1460669Y418554D01*
Y417513D01*
G01Y418554D02*
X1461877Y419179D01*
G01Y421363D02*
X1461335Y421446D01*
X1460877Y421571D01*
X1460460Y421738D01*
X1460002Y421946D01*
X1459377Y422279D01*
Y420613D01*
G01X1459585Y425463D02*
X1459460Y425213D01*
X1459377Y424921D01*
Y424588D01*
X1459502Y424213D01*
X1459710Y423921D01*
X1459960Y423713D01*
X1460377Y423546D01*
X1460752Y423504D01*
X1461127Y423588D01*
X1461377Y423713D01*
X1461627Y423963D01*
X1461794Y424254D01*
X1461877Y424546D01*
Y424838D01*
X1461794Y425129D01*
X1461669Y425379D01*
X1461502Y425588D01*
G01X1461877Y427646D02*
X1459377D01*
X1459877Y427146D01*
G01X1461877D02*
Y428146D01*
G01X1426077Y422570D02*
X1424952D01*
X1423577Y421737D01*
G01Y423403D02*
X1424952Y422570D01*
G01X1426077Y425587D02*
X1425535Y425670D01*
X1425077Y425795D01*
X1424660Y425962D01*
X1424202Y426170D01*
X1423577Y426503D01*
Y424837D01*
G01X1423785Y429687D02*
X1423660Y429437D01*
X1423577Y429145D01*
Y428812D01*
X1423702Y428437D01*
X1423910Y428145D01*
X1424160Y427937D01*
X1424577Y427770D01*
X1424952Y427728D01*
X1425327Y427812D01*
X1425577Y427937D01*
X1425827Y428187D01*
X1425994Y428478D01*
X1426077Y428770D01*
Y429062D01*
X1425994Y429353D01*
X1425869Y429603D01*
X1425702Y429812D01*
G01X1426077Y431870D02*
X1423577D01*
X1424077Y431370D01*
G01X1426077D02*
Y432370D01*
G01X1428108Y418067D02*
X1427983Y417817D01*
X1427900Y417525D01*
Y417192D01*
X1428025Y416817D01*
X1428233Y416525D01*
X1428483Y416317D01*
X1428900Y416150D01*
X1429275Y416108D01*
X1429650Y416192D01*
X1429900Y416317D01*
X1430150Y416567D01*
X1430317Y416858D01*
X1430400Y417150D01*
Y417442D01*
X1430317Y417733D01*
X1430192Y417983D01*
X1430025Y418192D01*
G01X1430400Y420167D02*
X1429858Y420250D01*
X1429400Y420375D01*
X1428983Y420542D01*
X1428525Y420750D01*
X1427900Y421083D01*
Y419417D01*
G01X1428108Y424267D02*
X1427983Y424017D01*
X1427900Y423725D01*
Y423392D01*
X1428025Y423017D01*
X1428233Y422725D01*
X1428483Y422517D01*
X1428900Y422350D01*
X1429275Y422308D01*
X1429650Y422392D01*
X1429900Y422517D01*
X1430150Y422767D01*
X1430317Y423058D01*
X1430400Y423350D01*
Y423642D01*
X1430317Y423933D01*
X1430192Y424183D01*
X1430025Y424392D01*
G01Y425533D02*
X1430233Y425783D01*
X1430358Y426075D01*
X1430400Y426450D01*
X1430317Y426825D01*
X1430150Y427117D01*
X1429858Y427325D01*
X1429525Y427367D01*
X1429192Y427283D01*
X1428983Y427075D01*
X1428817Y426783D01*
X1428775Y426492D01*
X1428817Y426200D01*
X1428983Y425825D01*
X1427900Y425950D01*
Y427075D01*
G01X1447717Y458042D02*
X1447467Y458167D01*
X1447175Y458250D01*
X1446842D01*
X1446467Y458125D01*
X1446175Y457917D01*
X1445967Y457667D01*
X1445800Y457250D01*
X1445758Y456875D01*
X1445842Y456500D01*
X1445967Y456250D01*
X1446217Y456000D01*
X1446508Y455833D01*
X1446800Y455750D01*
X1447092D01*
X1447383Y455833D01*
X1447633Y455958D01*
X1447842Y456125D01*
G01X1449817Y455750D02*
X1449900Y456292D01*
X1450025Y456750D01*
X1450192Y457167D01*
X1450400Y457625D01*
X1450733Y458250D01*
X1449067D01*
G01X1453333Y457083D02*
X1453500Y457208D01*
X1453625Y457417D01*
X1453708Y457708D01*
X1453625Y457958D01*
X1453458Y458125D01*
X1453167Y458250D01*
X1452042D01*
Y455750D01*
X1453417D01*
X1453708Y455917D01*
X1453875Y456167D01*
X1453958Y456458D01*
X1453875Y456750D01*
X1453625Y457000D01*
X1453333Y457083D01*
X1452042D01*
G01X1455308Y457833D02*
X1455558Y458083D01*
X1455850Y458208D01*
X1456183Y458250D01*
X1456600Y458167D01*
X1456892Y457958D01*
X1456975Y457708D01*
X1456933Y457458D01*
X1456767Y457250D01*
X1455933Y456833D01*
X1455558Y456542D01*
X1455308Y456125D01*
X1455225Y455750D01*
X1456975D01*
G01X1459117D02*
X1459200Y456292D01*
X1459325Y456750D01*
X1459492Y457167D01*
X1459700Y457625D01*
X1460033Y458250D01*
X1458367D01*
G01X1415443Y445678D02*
X1415193Y445803D01*
X1414901Y445886D01*
X1414568D01*
X1414193Y445761D01*
X1413901Y445553D01*
X1413693Y445303D01*
X1413526Y444886D01*
X1413484Y444511D01*
X1413568Y444136D01*
X1413693Y443886D01*
X1413943Y443636D01*
X1414234Y443469D01*
X1414526Y443386D01*
X1414818D01*
X1415109Y443469D01*
X1415359Y443594D01*
X1415568Y443761D01*
G01X1417543Y443386D02*
X1417626Y443928D01*
X1417751Y444386D01*
X1417918Y444803D01*
X1418126Y445261D01*
X1418459Y445886D01*
X1416793D01*
G01X1421059Y444719D02*
X1421226Y444844D01*
X1421351Y445053D01*
X1421434Y445344D01*
X1421351Y445594D01*
X1421184Y445761D01*
X1420893Y445886D01*
X1419768D01*
Y443386D01*
X1421143D01*
X1421434Y443553D01*
X1421601Y443803D01*
X1421684Y444094D01*
X1421601Y444386D01*
X1421351Y444636D01*
X1421059Y444719D01*
X1419768D01*
G01X1423034Y445469D02*
X1423284Y445719D01*
X1423576Y445844D01*
X1423909Y445886D01*
X1424326Y445803D01*
X1424618Y445594D01*
X1424701Y445344D01*
X1424659Y445094D01*
X1424493Y444886D01*
X1423659Y444469D01*
X1423284Y444178D01*
X1423034Y443761D01*
X1422951Y443386D01*
X1424701D01*
G01X1426926D02*
X1427218Y443428D01*
X1427551Y443553D01*
X1427759Y443761D01*
X1427843Y444053D01*
X1427759Y444344D01*
X1427509Y444594D01*
X1427134Y444719D01*
X1426718D01*
X1426468Y444803D01*
X1426259Y445011D01*
X1426176Y445303D01*
X1426301Y445594D01*
X1426593Y445803D01*
X1426926Y445886D01*
X1427259Y445803D01*
X1427551Y445594D01*
X1427676Y445303D01*
X1427593Y445011D01*
X1427384Y444803D01*
X1427134Y444719D01*
X1426718D01*
X1426343Y444594D01*
X1426093Y444344D01*
X1426009Y444053D01*
X1426093Y443761D01*
X1426301Y443553D01*
X1426634Y443428D01*
X1426926Y443386D01*
G01X1457917Y441392D02*
X1457667Y441517D01*
X1457375Y441600D01*
X1457042D01*
X1456667Y441475D01*
X1456375Y441267D01*
X1456167Y441017D01*
X1456000Y440600D01*
X1455958Y440225D01*
X1456042Y439850D01*
X1456167Y439600D01*
X1456417Y439350D01*
X1456708Y439183D01*
X1457000Y439100D01*
X1457292D01*
X1457583Y439183D01*
X1457833Y439308D01*
X1458042Y439475D01*
G01X1460017Y439100D02*
X1460100Y439642D01*
X1460225Y440100D01*
X1460392Y440517D01*
X1460600Y440975D01*
X1460933Y441600D01*
X1459267D01*
G01X1464117Y441392D02*
X1463867Y441517D01*
X1463575Y441600D01*
X1463242D01*
X1462867Y441475D01*
X1462575Y441267D01*
X1462367Y441017D01*
X1462200Y440600D01*
X1462158Y440225D01*
X1462242Y439850D01*
X1462367Y439600D01*
X1462617Y439350D01*
X1462908Y439183D01*
X1463200Y439100D01*
X1463492D01*
X1463783Y439183D01*
X1464033Y439308D01*
X1464242Y439475D01*
G01X1465508Y441183D02*
X1465758Y441433D01*
X1466050Y441558D01*
X1466383Y441600D01*
X1466800Y441517D01*
X1467092Y441308D01*
X1467175Y441058D01*
X1467133Y440808D01*
X1466967Y440600D01*
X1466133Y440183D01*
X1465758Y439892D01*
X1465508Y439475D01*
X1465425Y439100D01*
X1467175D01*
G01X1457717Y445492D02*
X1457467Y445617D01*
X1457175Y445700D01*
X1456842D01*
X1456467Y445575D01*
X1456175Y445367D01*
X1455967Y445117D01*
X1455800Y444700D01*
X1455758Y444325D01*
X1455842Y443950D01*
X1455967Y443700D01*
X1456217Y443450D01*
X1456508Y443283D01*
X1456800Y443200D01*
X1457092D01*
X1457383Y443283D01*
X1457633Y443408D01*
X1457842Y443575D01*
G01X1459817Y443200D02*
X1459900Y443742D01*
X1460025Y444200D01*
X1460192Y444617D01*
X1460400Y445075D01*
X1460733Y445700D01*
X1459067D01*
G01X1463333Y444533D02*
X1463500Y444658D01*
X1463625Y444867D01*
X1463708Y445158D01*
X1463625Y445408D01*
X1463458Y445575D01*
X1463167Y445700D01*
X1462042D01*
Y443200D01*
X1463417D01*
X1463708Y443367D01*
X1463875Y443617D01*
X1463958Y443908D01*
X1463875Y444200D01*
X1463625Y444450D01*
X1463333Y444533D01*
X1462042D01*
G01X1465308Y445283D02*
X1465558Y445533D01*
X1465850Y445658D01*
X1466183Y445700D01*
X1466600Y445617D01*
X1466892Y445408D01*
X1466975Y445158D01*
X1466933Y444908D01*
X1466767Y444700D01*
X1465933Y444283D01*
X1465558Y443992D01*
X1465308Y443575D01*
X1465225Y443200D01*
X1466975D01*
G01X1468492Y443492D02*
X1468783Y443283D01*
X1469117Y443200D01*
X1469450Y443283D01*
X1469742Y443533D01*
X1469950Y443908D01*
X1470033Y444283D01*
Y444742D01*
X1469950Y445117D01*
X1469742Y445450D01*
X1469492Y445617D01*
X1469200Y445700D01*
X1468867Y445617D01*
X1468617Y445450D01*
X1468450Y445200D01*
X1468367Y444867D01*
X1468450Y444575D01*
X1468658Y444283D01*
X1468908Y444117D01*
X1469200Y444075D01*
X1469533Y444158D01*
X1469783Y444367D01*
X1470033Y444742D01*
G01X1416517Y441892D02*
X1416267Y442017D01*
X1415975Y442100D01*
X1415642D01*
X1415267Y441975D01*
X1414975Y441767D01*
X1414767Y441517D01*
X1414600Y441100D01*
X1414558Y440725D01*
X1414642Y440350D01*
X1414767Y440100D01*
X1415017Y439850D01*
X1415308Y439683D01*
X1415600Y439600D01*
X1415892D01*
X1416183Y439683D01*
X1416433Y439808D01*
X1416642Y439975D01*
G01X1418617Y439600D02*
X1418700Y440142D01*
X1418825Y440600D01*
X1418992Y441017D01*
X1419200Y441475D01*
X1419533Y442100D01*
X1417867D01*
G01X1422717Y441892D02*
X1422467Y442017D01*
X1422175Y442100D01*
X1421842D01*
X1421467Y441975D01*
X1421175Y441767D01*
X1420967Y441517D01*
X1420800Y441100D01*
X1420758Y440725D01*
X1420842Y440350D01*
X1420967Y440100D01*
X1421217Y439850D01*
X1421508Y439683D01*
X1421800Y439600D01*
X1422092D01*
X1422383Y439683D01*
X1422633Y439808D01*
X1422842Y439975D01*
G01X1424900Y439600D02*
Y442100D01*
X1424400Y441600D01*
G01Y439600D02*
X1425400D01*
G01X1417321Y451831D02*
X1417071Y451956D01*
X1416779Y452039D01*
X1416446D01*
X1416071Y451914D01*
X1415779Y451706D01*
X1415571Y451456D01*
X1415404Y451039D01*
X1415362Y450664D01*
X1415446Y450289D01*
X1415571Y450039D01*
X1415821Y449789D01*
X1416112Y449622D01*
X1416404Y449539D01*
X1416696D01*
X1416987Y449622D01*
X1417237Y449747D01*
X1417446Y449914D01*
G01X1419421Y449539D02*
X1419504Y450081D01*
X1419629Y450539D01*
X1419796Y450956D01*
X1420004Y451414D01*
X1420337Y452039D01*
X1418671D01*
G01X1422937Y450872D02*
X1423104Y450997D01*
X1423229Y451206D01*
X1423312Y451497D01*
X1423229Y451747D01*
X1423062Y451914D01*
X1422771Y452039D01*
X1421646D01*
Y449539D01*
X1423021D01*
X1423312Y449706D01*
X1423479Y449956D01*
X1423562Y450247D01*
X1423479Y450539D01*
X1423229Y450789D01*
X1422937Y450872D01*
X1421646D01*
G01X1424912Y451622D02*
X1425162Y451872D01*
X1425454Y451997D01*
X1425787Y452039D01*
X1426204Y451956D01*
X1426496Y451747D01*
X1426579Y451497D01*
X1426537Y451247D01*
X1426371Y451039D01*
X1425537Y450622D01*
X1425162Y450331D01*
X1424912Y449914D01*
X1424829Y449539D01*
X1426579D01*
G01X1428012Y450581D02*
X1428304Y450872D01*
X1428554Y451039D01*
X1428887Y451122D01*
X1429179Y451039D01*
X1429387Y450872D01*
X1429554Y450622D01*
X1429596Y450331D01*
X1429554Y450081D01*
X1429387Y449831D01*
X1429137Y449622D01*
X1428846Y449539D01*
X1428512Y449622D01*
X1428221Y449872D01*
X1428054Y450247D01*
X1428012Y450664D01*
X1428096Y451206D01*
X1428221Y451497D01*
X1428429Y451789D01*
X1428721Y451997D01*
X1429012Y452039D01*
X1429304Y451956D01*
X1429512Y451747D01*
G01X1416811Y457199D02*
X1416561Y457324D01*
X1416269Y457407D01*
X1415936D01*
X1415561Y457282D01*
X1415269Y457074D01*
X1415061Y456824D01*
X1414894Y456407D01*
X1414852Y456032D01*
X1414936Y455657D01*
X1415061Y455407D01*
X1415311Y455157D01*
X1415602Y454990D01*
X1415894Y454907D01*
X1416186D01*
X1416477Y454990D01*
X1416727Y455115D01*
X1416936Y455282D01*
G01X1418911Y454907D02*
X1418994Y455449D01*
X1419119Y455907D01*
X1419286Y456324D01*
X1419494Y456782D01*
X1419827Y457407D01*
X1418161D01*
G01X1422427Y456240D02*
X1422594Y456365D01*
X1422719Y456574D01*
X1422802Y456865D01*
X1422719Y457115D01*
X1422552Y457282D01*
X1422261Y457407D01*
X1421136D01*
Y454907D01*
X1422511D01*
X1422802Y455074D01*
X1422969Y455324D01*
X1423052Y455615D01*
X1422969Y455907D01*
X1422719Y456157D01*
X1422427Y456240D01*
X1421136D01*
G01X1424402Y456990D02*
X1424652Y457240D01*
X1424944Y457365D01*
X1425277Y457407D01*
X1425694Y457324D01*
X1425986Y457115D01*
X1426069Y456865D01*
X1426027Y456615D01*
X1425861Y456407D01*
X1425027Y455990D01*
X1424652Y455699D01*
X1424402Y455282D01*
X1424319Y454907D01*
X1426069D01*
G01X1427377Y455282D02*
X1427627Y455074D01*
X1427919Y454949D01*
X1428294Y454907D01*
X1428669Y454990D01*
X1428961Y455157D01*
X1429169Y455449D01*
X1429211Y455782D01*
X1429127Y456115D01*
X1428919Y456324D01*
X1428627Y456490D01*
X1428336Y456532D01*
X1428044Y456490D01*
X1427669Y456324D01*
X1427794Y457407D01*
X1428919D01*
G01X1457917Y437892D02*
X1457667Y438017D01*
X1457375Y438100D01*
X1457042D01*
X1456667Y437975D01*
X1456375Y437767D01*
X1456167Y437517D01*
X1456000Y437100D01*
X1455958Y436725D01*
X1456042Y436350D01*
X1456167Y436100D01*
X1456417Y435850D01*
X1456708Y435683D01*
X1457000Y435600D01*
X1457292D01*
X1457583Y435683D01*
X1457833Y435808D01*
X1458042Y435975D01*
G01X1460017Y435600D02*
X1460100Y436142D01*
X1460225Y436600D01*
X1460392Y437017D01*
X1460600Y437475D01*
X1460933Y438100D01*
X1459267D01*
G01X1464117Y437892D02*
X1463867Y438017D01*
X1463575Y438100D01*
X1463242D01*
X1462867Y437975D01*
X1462575Y437767D01*
X1462367Y437517D01*
X1462200Y437100D01*
X1462158Y436725D01*
X1462242Y436350D01*
X1462367Y436100D01*
X1462617Y435850D01*
X1462908Y435683D01*
X1463200Y435600D01*
X1463492D01*
X1463783Y435683D01*
X1464033Y435808D01*
X1464242Y435975D01*
G01X1465383Y436100D02*
X1465633Y435808D01*
X1465967Y435642D01*
X1466342Y435600D01*
X1466675Y435642D01*
X1467008Y435850D01*
X1467217Y436100D01*
X1467258Y436350D01*
X1467175Y436642D01*
X1466883Y436850D01*
X1466592Y436933D01*
X1466217D01*
G01X1466592D02*
X1466842Y437058D01*
X1467050Y437267D01*
X1467133Y437517D01*
X1467050Y437767D01*
X1466842Y437975D01*
X1466467Y438100D01*
X1466092Y438058D01*
X1465717Y437892D01*
G01X1427908Y431367D02*
X1427783Y431117D01*
X1427700Y430825D01*
Y430492D01*
X1427825Y430117D01*
X1428033Y429825D01*
X1428283Y429617D01*
X1428700Y429450D01*
X1429075Y429408D01*
X1429450Y429492D01*
X1429700Y429617D01*
X1429950Y429867D01*
X1430117Y430158D01*
X1430200Y430450D01*
Y430742D01*
X1430117Y431033D01*
X1429992Y431283D01*
X1429825Y431492D01*
G01X1430200Y433467D02*
X1429658Y433550D01*
X1429200Y433675D01*
X1428783Y433842D01*
X1428325Y434050D01*
X1427700Y434383D01*
Y432717D01*
G01X1427908Y437567D02*
X1427783Y437317D01*
X1427700Y437025D01*
Y436692D01*
X1427825Y436317D01*
X1428033Y436025D01*
X1428283Y435817D01*
X1428700Y435650D01*
X1429075Y435608D01*
X1429450Y435692D01*
X1429700Y435817D01*
X1429950Y436067D01*
X1430117Y436358D01*
X1430200Y436650D01*
Y436942D01*
X1430117Y437233D01*
X1429992Y437483D01*
X1429825Y437692D01*
G01X1430200Y440250D02*
X1427700D01*
X1429492Y438708D01*
Y440792D01*
G01X1443760Y501450D02*
Y489720D01*
X1459890D01*
G01X1441040Y527470D02*
X1442540Y525970D01*
X1439540D01*
X1441040Y527470D01*
G01D02*
Y520130D01*
X1431680D01*
Y501450D01*
X1443760D01*
G01X1417140Y476000D02*
Y469230D01*
X1441360D01*
Y467860D01*
X1464290D01*
Y489720D01*
X1462570D01*
G01X1417140Y481700D02*
Y478800D01*
G01Y493100D02*
Y485100D01*
G01X1431680Y501450D02*
X1417140D01*
Y496500D01*
G01X1461118Y470707D02*
X1460993Y470457D01*
X1460910Y470165D01*
Y469832D01*
X1461035Y469457D01*
X1461243Y469165D01*
X1461493Y468957D01*
X1461910Y468790D01*
X1462285Y468748D01*
X1462660Y468832D01*
X1462910Y468957D01*
X1463160Y469207D01*
X1463327Y469498D01*
X1463410Y469790D01*
Y470082D01*
X1463327Y470373D01*
X1463202Y470623D01*
X1463035Y470832D01*
G01X1463410Y472807D02*
X1462868Y472890D01*
X1462410Y473015D01*
X1461993Y473182D01*
X1461535Y473390D01*
X1460910Y473723D01*
Y472057D01*
G01X1463410Y474948D02*
X1460910Y475990D01*
X1463410Y477032D01*
G01X1462535Y476657D02*
Y475323D01*
G01X1462910Y478173D02*
X1463202Y478423D01*
X1463368Y478757D01*
X1463410Y479132D01*
X1463368Y479465D01*
X1463160Y479798D01*
X1462910Y480007D01*
X1462660Y480048D01*
X1462368Y479965D01*
X1462160Y479673D01*
X1462077Y479382D01*
Y479007D01*
G01Y479382D02*
X1461952Y479632D01*
X1461743Y479840D01*
X1461493Y479923D01*
X1461243Y479840D01*
X1461035Y479632D01*
X1460910Y479257D01*
X1460952Y478882D01*
X1461118Y478507D01*
G01X1462910Y481273D02*
X1463202Y481523D01*
X1463368Y481857D01*
X1463410Y482232D01*
X1463368Y482565D01*
X1463160Y482898D01*
X1462910Y483107D01*
X1462660Y483148D01*
X1462368Y483065D01*
X1462160Y482773D01*
X1462077Y482482D01*
Y482107D01*
G01Y482482D02*
X1461952Y482732D01*
X1461743Y482940D01*
X1461493Y483023D01*
X1461243Y482940D01*
X1461035Y482732D01*
X1460910Y482357D01*
X1460952Y481982D01*
X1461118Y481607D01*
G01X1457618Y470707D02*
X1457493Y470457D01*
X1457410Y470165D01*
Y469832D01*
X1457535Y469457D01*
X1457743Y469165D01*
X1457993Y468957D01*
X1458410Y468790D01*
X1458785Y468748D01*
X1459160Y468832D01*
X1459410Y468957D01*
X1459660Y469207D01*
X1459827Y469498D01*
X1459910Y469790D01*
Y470082D01*
X1459827Y470373D01*
X1459702Y470623D01*
X1459535Y470832D01*
G01X1459910Y472807D02*
X1459368Y472890D01*
X1458910Y473015D01*
X1458493Y473182D01*
X1458035Y473390D01*
X1457410Y473723D01*
Y472057D01*
G01X1459910Y474948D02*
X1457410Y475990D01*
X1459910Y477032D01*
G01X1459035Y476657D02*
Y475323D01*
G01X1459410Y478173D02*
X1459702Y478423D01*
X1459868Y478757D01*
X1459910Y479132D01*
X1459868Y479465D01*
X1459660Y479798D01*
X1459410Y480007D01*
X1459160Y480048D01*
X1458868Y479965D01*
X1458660Y479673D01*
X1458577Y479382D01*
Y479007D01*
G01Y479382D02*
X1458452Y479632D01*
X1458243Y479840D01*
X1457993Y479923D01*
X1457743Y479840D01*
X1457535Y479632D01*
X1457410Y479257D01*
X1457452Y478882D01*
X1457618Y478507D01*
G01X1457827Y481398D02*
X1457577Y481648D01*
X1457452Y481940D01*
X1457410Y482273D01*
X1457493Y482690D01*
X1457702Y482982D01*
X1457952Y483065D01*
X1458202Y483023D01*
X1458410Y482857D01*
X1458827Y482023D01*
X1459118Y481648D01*
X1459535Y481398D01*
X1459910Y481315D01*
Y483065D01*
G01X1454917Y491100D02*
Y493600D01*
X1455958D01*
X1456292Y493475D01*
X1456500Y493308D01*
X1456583Y492975D01*
X1456500Y492642D01*
X1456250Y492433D01*
X1455958Y492308D01*
X1454917D01*
G01X1455958D02*
X1456583Y491100D01*
G01X1458767D02*
X1458850Y491642D01*
X1458975Y492100D01*
X1459142Y492517D01*
X1459350Y492975D01*
X1459683Y493600D01*
X1458017D01*
G01X1462283Y492433D02*
X1462450Y492558D01*
X1462575Y492767D01*
X1462658Y493058D01*
X1462575Y493308D01*
X1462408Y493475D01*
X1462117Y493600D01*
X1460992D01*
Y491100D01*
X1462367D01*
X1462658Y491267D01*
X1462825Y491517D01*
X1462908Y491808D01*
X1462825Y492100D01*
X1462575Y492350D01*
X1462283Y492433D01*
X1460992D01*
G01X1465050Y491100D02*
X1465342Y491142D01*
X1465675Y491267D01*
X1465883Y491475D01*
X1465967Y491767D01*
X1465883Y492058D01*
X1465633Y492308D01*
X1465258Y492433D01*
X1464842D01*
X1464592Y492517D01*
X1464383Y492725D01*
X1464300Y493017D01*
X1464425Y493308D01*
X1464717Y493517D01*
X1465050Y493600D01*
X1465383Y493517D01*
X1465675Y493308D01*
X1465800Y493017D01*
X1465717Y492725D01*
X1465508Y492517D01*
X1465258Y492433D01*
X1464842D01*
X1464467Y492308D01*
X1464217Y492058D01*
X1464133Y491767D01*
X1464217Y491475D01*
X1464425Y491267D01*
X1464758Y491142D01*
X1465050Y491100D01*
G01X1452910Y468957D02*
X1450410D01*
Y469998D01*
X1450535Y470332D01*
X1450702Y470540D01*
X1451035Y470623D01*
X1451368Y470540D01*
X1451577Y470290D01*
X1451702Y469998D01*
Y468957D01*
G01Y469998D02*
X1452910Y470623D01*
G01Y472807D02*
X1452368Y472890D01*
X1451910Y473015D01*
X1451493Y473182D01*
X1451035Y473390D01*
X1450410Y473723D01*
Y472057D01*
G01X1452910Y474948D02*
X1450410Y475990D01*
X1452910Y477032D01*
G01X1452035Y476657D02*
Y475323D01*
G01X1452910Y479090D02*
X1450410D01*
X1450910Y478590D01*
G01X1452910D02*
Y479590D01*
G01X1452618Y481482D02*
X1452827Y481773D01*
X1452910Y482107D01*
X1452827Y482440D01*
X1452577Y482732D01*
X1452202Y482940D01*
X1451827Y483023D01*
X1451368D01*
X1450993Y482940D01*
X1450660Y482732D01*
X1450493Y482482D01*
X1450410Y482190D01*
X1450493Y481857D01*
X1450660Y481607D01*
X1450910Y481440D01*
X1451243Y481357D01*
X1451535Y481440D01*
X1451827Y481648D01*
X1451993Y481898D01*
X1452035Y482190D01*
X1451952Y482523D01*
X1451743Y482773D01*
X1451368Y483023D01*
G01X1456410Y468957D02*
X1453910D01*
Y469998D01*
X1454035Y470332D01*
X1454202Y470540D01*
X1454535Y470623D01*
X1454868Y470540D01*
X1455077Y470290D01*
X1455202Y469998D01*
Y468957D01*
G01Y469998D02*
X1456410Y470623D01*
G01Y472807D02*
X1455868Y472890D01*
X1455410Y473015D01*
X1454993Y473182D01*
X1454535Y473390D01*
X1453910Y473723D01*
Y472057D01*
G01X1456410Y474948D02*
X1453910Y475990D01*
X1456410Y477032D01*
G01X1455535Y476657D02*
Y475323D01*
G01X1456410Y479090D02*
X1453910D01*
X1454410Y478590D01*
G01X1456410D02*
Y479590D01*
G01Y482690D02*
X1453910D01*
X1455702Y481148D01*
Y483232D01*
G01X1454917Y494600D02*
Y497100D01*
X1455958D01*
X1456292Y496975D01*
X1456500Y496808D01*
X1456583Y496475D01*
X1456500Y496142D01*
X1456250Y495933D01*
X1455958Y495808D01*
X1454917D01*
G01X1455958D02*
X1456583Y494600D01*
G01X1458767D02*
X1458850Y495142D01*
X1458975Y495600D01*
X1459142Y496017D01*
X1459350Y496475D01*
X1459683Y497100D01*
X1458017D01*
G01X1462283Y495933D02*
X1462450Y496058D01*
X1462575Y496267D01*
X1462658Y496558D01*
X1462575Y496808D01*
X1462408Y496975D01*
X1462117Y497100D01*
X1460992D01*
Y494600D01*
X1462367D01*
X1462658Y494767D01*
X1462825Y495017D01*
X1462908Y495308D01*
X1462825Y495600D01*
X1462575Y495850D01*
X1462283Y495933D01*
X1460992D01*
G01X1464967Y494600D02*
X1465050Y495142D01*
X1465175Y495600D01*
X1465342Y496017D01*
X1465550Y496475D01*
X1465883Y497100D01*
X1464217D01*
G01X1454917Y498100D02*
Y500600D01*
X1455958D01*
X1456292Y500475D01*
X1456500Y500308D01*
X1456583Y499975D01*
X1456500Y499642D01*
X1456250Y499433D01*
X1455958Y499308D01*
X1454917D01*
G01X1455958D02*
X1456583Y498100D01*
G01X1458767D02*
X1458850Y498642D01*
X1458975Y499100D01*
X1459142Y499517D01*
X1459350Y499975D01*
X1459683Y500600D01*
X1458017D01*
G01X1462283Y499433D02*
X1462450Y499558D01*
X1462575Y499767D01*
X1462658Y500058D01*
X1462575Y500308D01*
X1462408Y500475D01*
X1462117Y500600D01*
X1460992D01*
Y498100D01*
X1462367D01*
X1462658Y498267D01*
X1462825Y498517D01*
X1462908Y498808D01*
X1462825Y499100D01*
X1462575Y499350D01*
X1462283Y499433D01*
X1460992D01*
G01X1464258Y499142D02*
X1464550Y499433D01*
X1464800Y499600D01*
X1465133Y499683D01*
X1465425Y499600D01*
X1465633Y499433D01*
X1465800Y499183D01*
X1465842Y498892D01*
X1465800Y498642D01*
X1465633Y498392D01*
X1465383Y498183D01*
X1465092Y498100D01*
X1464758Y498183D01*
X1464467Y498433D01*
X1464300Y498808D01*
X1464258Y499225D01*
X1464342Y499767D01*
X1464467Y500058D01*
X1464675Y500350D01*
X1464967Y500558D01*
X1465258Y500600D01*
X1465550Y500517D01*
X1465758Y500308D01*
G01X1422990Y503927D02*
X1420490D01*
Y504968D01*
X1420615Y505302D01*
X1420782Y505510D01*
X1421115Y505593D01*
X1421448Y505510D01*
X1421657Y505260D01*
X1421782Y504968D01*
Y503927D01*
G01Y504968D02*
X1422990Y505593D01*
G01Y507777D02*
X1422448Y507860D01*
X1421990Y507985D01*
X1421573Y508152D01*
X1421115Y508360D01*
X1420490Y508693D01*
Y507027D01*
G01X1421657Y511293D02*
X1421532Y511460D01*
X1421323Y511585D01*
X1421032Y511668D01*
X1420782Y511585D01*
X1420615Y511418D01*
X1420490Y511127D01*
Y510002D01*
X1422990D01*
Y511377D01*
X1422823Y511668D01*
X1422573Y511835D01*
X1422282Y511918D01*
X1421990Y511835D01*
X1421740Y511585D01*
X1421657Y511293D01*
Y510002D01*
G01X1422615Y513143D02*
X1422823Y513393D01*
X1422948Y513685D01*
X1422990Y514060D01*
X1422907Y514435D01*
X1422740Y514727D01*
X1422448Y514935D01*
X1422115Y514977D01*
X1421782Y514893D01*
X1421573Y514685D01*
X1421407Y514393D01*
X1421365Y514102D01*
X1421407Y513810D01*
X1421573Y513435D01*
X1420490Y513560D01*
Y514685D01*
G01X1426490Y503927D02*
X1423990D01*
Y504968D01*
X1424115Y505302D01*
X1424282Y505510D01*
X1424615Y505593D01*
X1424948Y505510D01*
X1425157Y505260D01*
X1425282Y504968D01*
Y503927D01*
G01Y504968D02*
X1426490Y505593D01*
G01Y507777D02*
X1425948Y507860D01*
X1425490Y507985D01*
X1425073Y508152D01*
X1424615Y508360D01*
X1423990Y508693D01*
Y507027D01*
G01X1425157Y511293D02*
X1425032Y511460D01*
X1424823Y511585D01*
X1424532Y511668D01*
X1424282Y511585D01*
X1424115Y511418D01*
X1423990Y511127D01*
Y510002D01*
X1426490D01*
Y511377D01*
X1426323Y511668D01*
X1426073Y511835D01*
X1425782Y511918D01*
X1425490Y511835D01*
X1425240Y511585D01*
X1425157Y511293D01*
Y510002D01*
G01X1426490Y514560D02*
X1423990D01*
X1425782Y513018D01*
Y515102D01*
G01X1429990Y503927D02*
X1427490D01*
Y504968D01*
X1427615Y505302D01*
X1427782Y505510D01*
X1428115Y505593D01*
X1428448Y505510D01*
X1428657Y505260D01*
X1428782Y504968D01*
Y503927D01*
G01Y504968D02*
X1429990Y505593D01*
G01Y507777D02*
X1429448Y507860D01*
X1428990Y507985D01*
X1428573Y508152D01*
X1428115Y508360D01*
X1427490Y508693D01*
Y507027D01*
G01X1428657Y511293D02*
X1428532Y511460D01*
X1428323Y511585D01*
X1428032Y511668D01*
X1427782Y511585D01*
X1427615Y511418D01*
X1427490Y511127D01*
Y510002D01*
X1429990D01*
Y511377D01*
X1429823Y511668D01*
X1429573Y511835D01*
X1429282Y511918D01*
X1428990Y511835D01*
X1428740Y511585D01*
X1428657Y511293D01*
Y510002D01*
G01X1429990Y514060D02*
X1427490D01*
X1427990Y513560D01*
G01X1429990D02*
Y514560D01*
G01X1420237Y481890D02*
Y484390D01*
X1421278D01*
X1421612Y484265D01*
X1421820Y484098D01*
X1421903Y483765D01*
X1421820Y483432D01*
X1421570Y483223D01*
X1421278Y483098D01*
X1420237D01*
G01X1421278D02*
X1421903Y481890D01*
G01X1424087D02*
X1424170Y482432D01*
X1424295Y482890D01*
X1424462Y483307D01*
X1424670Y483765D01*
X1425003Y484390D01*
X1423337D01*
G01X1426228Y481890D02*
X1427270Y484390D01*
X1428312Y481890D01*
G01X1427937Y482765D02*
X1426603D01*
G01X1430370Y481890D02*
Y484390D01*
X1429870Y483890D01*
G01Y481890D02*
X1430870D01*
G01X1432678Y483973D02*
X1432928Y484223D01*
X1433220Y484348D01*
X1433553Y484390D01*
X1433970Y484307D01*
X1434262Y484098D01*
X1434345Y483848D01*
X1434303Y483598D01*
X1434137Y483390D01*
X1433303Y482973D01*
X1432928Y482682D01*
X1432678Y482265D01*
X1432595Y481890D01*
X1434345D01*
G01X1445910Y468957D02*
X1443410D01*
Y469998D01*
X1443535Y470332D01*
X1443702Y470540D01*
X1444035Y470623D01*
X1444368Y470540D01*
X1444577Y470290D01*
X1444702Y469998D01*
Y468957D01*
G01Y469998D02*
X1445910Y470623D01*
G01Y472807D02*
X1445368Y472890D01*
X1444910Y473015D01*
X1444493Y473182D01*
X1444035Y473390D01*
X1443410Y473723D01*
Y472057D01*
G01X1445910Y474948D02*
X1443410Y475990D01*
X1445910Y477032D01*
G01X1445035Y476657D02*
Y475323D01*
G01X1445910Y479090D02*
X1443410D01*
X1443910Y478590D01*
G01X1445910D02*
Y479590D01*
G01Y482190D02*
X1445868Y482482D01*
X1445743Y482815D01*
X1445535Y483023D01*
X1445243Y483107D01*
X1444952Y483023D01*
X1444702Y482773D01*
X1444577Y482398D01*
Y481982D01*
X1444493Y481732D01*
X1444285Y481523D01*
X1443993Y481440D01*
X1443702Y481565D01*
X1443493Y481857D01*
X1443410Y482190D01*
X1443493Y482523D01*
X1443702Y482815D01*
X1443993Y482940D01*
X1444285Y482857D01*
X1444493Y482648D01*
X1444577Y482398D01*
Y481982D01*
X1444702Y481607D01*
X1444952Y481357D01*
X1445243Y481273D01*
X1445535Y481357D01*
X1445743Y481565D01*
X1445868Y481898D01*
X1445910Y482190D01*
G01X1449410Y468957D02*
X1446910D01*
Y469998D01*
X1447035Y470332D01*
X1447202Y470540D01*
X1447535Y470623D01*
X1447868Y470540D01*
X1448077Y470290D01*
X1448202Y469998D01*
Y468957D01*
G01Y469998D02*
X1449410Y470623D01*
G01Y472807D02*
X1448868Y472890D01*
X1448410Y473015D01*
X1447993Y473182D01*
X1447535Y473390D01*
X1446910Y473723D01*
Y472057D01*
G01X1449410Y474948D02*
X1446910Y475990D01*
X1449410Y477032D01*
G01X1448535Y476657D02*
Y475323D01*
G01X1449410Y479090D02*
X1446910D01*
X1447410Y478590D01*
G01X1449410D02*
Y479590D01*
G01X1448910Y481273D02*
X1449202Y481523D01*
X1449368Y481857D01*
X1449410Y482232D01*
X1449368Y482565D01*
X1449160Y482898D01*
X1448910Y483107D01*
X1448660Y483148D01*
X1448368Y483065D01*
X1448160Y482773D01*
X1448077Y482482D01*
Y482107D01*
G01Y482482D02*
X1447952Y482732D01*
X1447743Y482940D01*
X1447493Y483023D01*
X1447243Y482940D01*
X1447035Y482732D01*
X1446910Y482357D01*
X1446952Y481982D01*
X1447118Y481607D01*
G01X1420578Y490613D02*
Y493113D01*
X1421619D01*
X1421953Y492988D01*
X1422161Y492821D01*
X1422244Y492488D01*
X1422161Y492155D01*
X1421911Y491946D01*
X1421619Y491821D01*
X1420578D01*
G01X1421619D02*
X1422244Y490613D01*
G01X1424511D02*
Y493113D01*
X1424011Y492613D01*
G01Y490613D02*
X1425011D01*
G01X1426819Y492696D02*
X1427069Y492946D01*
X1427361Y493071D01*
X1427694Y493113D01*
X1428111Y493030D01*
X1428403Y492821D01*
X1428486Y492571D01*
X1428444Y492321D01*
X1428278Y492113D01*
X1427444Y491696D01*
X1427069Y491405D01*
X1426819Y490988D01*
X1426736Y490613D01*
X1428486D01*
G01X1429461Y493113D02*
X1430044Y490613D01*
X1430711Y493113D01*
X1431378Y490613D01*
X1431961Y493113D01*
G01X1432894Y491113D02*
X1433144Y490821D01*
X1433478Y490655D01*
X1433853Y490613D01*
X1434186Y490655D01*
X1434519Y490863D01*
X1434728Y491113D01*
X1434769Y491363D01*
X1434686Y491655D01*
X1434394Y491863D01*
X1434103Y491946D01*
X1433728D01*
G01X1434103D02*
X1434353Y492071D01*
X1434561Y492280D01*
X1434644Y492530D01*
X1434561Y492780D01*
X1434353Y492988D01*
X1433978Y493113D01*
X1433603Y493071D01*
X1433228Y492905D01*
G01X1436911Y493113D02*
X1436578Y493030D01*
X1436328Y492821D01*
X1436161Y492571D01*
X1436036Y492238D01*
X1435994Y491863D01*
X1436036Y491488D01*
X1436161Y491155D01*
X1436328Y490905D01*
X1436578Y490696D01*
X1436911Y490613D01*
X1437244Y490696D01*
X1437494Y490905D01*
X1437661Y491155D01*
X1437786Y491488D01*
X1437828Y491863D01*
X1437786Y492238D01*
X1437661Y492571D01*
X1437494Y492821D01*
X1437244Y493030D01*
X1436911Y493113D01*
G01X1420047Y474220D02*
Y476720D01*
X1421088D01*
X1421422Y476595D01*
X1421630Y476428D01*
X1421713Y476095D01*
X1421630Y475762D01*
X1421380Y475553D01*
X1421088Y475428D01*
X1420047D01*
G01X1421088D02*
X1421713Y474220D01*
G01X1423980D02*
Y476720D01*
X1423480Y476220D01*
G01Y474220D02*
X1424480D01*
G01X1426288Y476303D02*
X1426538Y476553D01*
X1426830Y476678D01*
X1427163Y476720D01*
X1427580Y476637D01*
X1427872Y476428D01*
X1427955Y476178D01*
X1427913Y475928D01*
X1427747Y475720D01*
X1426913Y475303D01*
X1426538Y475012D01*
X1426288Y474595D01*
X1426205Y474220D01*
X1427955D01*
G01X1428930Y476720D02*
X1429513Y474220D01*
X1430180Y476720D01*
X1430847Y474220D01*
X1431430Y476720D01*
G01X1432488Y476303D02*
X1432738Y476553D01*
X1433030Y476678D01*
X1433363Y476720D01*
X1433780Y476637D01*
X1434072Y476428D01*
X1434155Y476178D01*
X1434113Y475928D01*
X1433947Y475720D01*
X1433113Y475303D01*
X1432738Y475012D01*
X1432488Y474595D01*
X1432405Y474220D01*
X1434155D01*
G01X1435672Y474512D02*
X1435963Y474303D01*
X1436297Y474220D01*
X1436630Y474303D01*
X1436922Y474553D01*
X1437130Y474928D01*
X1437213Y475303D01*
Y475762D01*
X1437130Y476137D01*
X1436922Y476470D01*
X1436672Y476637D01*
X1436380Y476720D01*
X1436047Y476637D01*
X1435797Y476470D01*
X1435630Y476220D01*
X1435547Y475887D01*
X1435630Y475595D01*
X1435838Y475303D01*
X1436088Y475137D01*
X1436380Y475095D01*
X1436713Y475178D01*
X1436963Y475387D01*
X1437213Y475762D01*
G01X1440770Y471647D02*
X1438270D01*
Y472688D01*
X1438395Y473022D01*
X1438562Y473230D01*
X1438895Y473313D01*
X1439228Y473230D01*
X1439437Y472980D01*
X1439562Y472688D01*
Y471647D01*
G01Y472688D02*
X1440770Y473313D01*
G01Y475497D02*
X1440228Y475580D01*
X1439770Y475705D01*
X1439353Y475872D01*
X1438895Y476080D01*
X1438270Y476413D01*
Y474747D01*
G01X1440770Y477638D02*
X1438270Y478680D01*
X1440770Y479722D01*
G01X1439895Y479347D02*
Y478013D01*
G01X1440478Y481072D02*
X1440687Y481363D01*
X1440770Y481697D01*
X1440687Y482030D01*
X1440437Y482322D01*
X1440062Y482530D01*
X1439687Y482613D01*
X1439228D01*
X1438853Y482530D01*
X1438520Y482322D01*
X1438353Y482072D01*
X1438270Y481780D01*
X1438353Y481447D01*
X1438520Y481197D01*
X1438770Y481030D01*
X1439103Y480947D01*
X1439395Y481030D01*
X1439687Y481238D01*
X1439853Y481488D01*
X1439895Y481780D01*
X1439812Y482113D01*
X1439603Y482363D01*
X1439228Y482613D01*
G01X1431506Y498121D02*
Y500621D01*
X1432547D01*
X1432881Y500496D01*
X1433089Y500329D01*
X1433172Y499996D01*
X1433089Y499663D01*
X1432839Y499454D01*
X1432547Y499329D01*
X1431506D01*
G01X1432547D02*
X1433172Y498121D01*
G01X1435356D02*
X1435439Y498663D01*
X1435564Y499121D01*
X1435731Y499538D01*
X1435939Y499996D01*
X1436272Y500621D01*
X1434606D01*
G01X1437497Y498121D02*
X1438539Y500621D01*
X1439581Y498121D01*
G01X1439206Y498996D02*
X1437872D01*
G01X1441556Y498121D02*
X1441639Y498663D01*
X1441764Y499121D01*
X1441931Y499538D01*
X1442139Y499996D01*
X1442472Y500621D01*
X1440806D01*
G01X1420237Y478390D02*
Y480890D01*
X1421278D01*
X1421612Y480765D01*
X1421820Y480598D01*
X1421903Y480265D01*
X1421820Y479932D01*
X1421570Y479723D01*
X1421278Y479598D01*
X1420237D01*
G01X1421278D02*
X1421903Y478390D01*
G01X1424087D02*
X1424170Y478932D01*
X1424295Y479390D01*
X1424462Y479807D01*
X1424670Y480265D01*
X1425003Y480890D01*
X1423337D01*
G01X1426228Y478390D02*
X1427270Y480890D01*
X1428312Y478390D01*
G01X1427937Y479265D02*
X1426603D01*
G01X1430370Y478390D02*
Y480890D01*
X1429870Y480390D01*
G01Y478390D02*
X1430870D01*
G01X1433387D02*
X1433470Y478932D01*
X1433595Y479390D01*
X1433762Y479807D01*
X1433970Y480265D01*
X1434303Y480890D01*
X1432637D01*
G01X1420578Y487113D02*
Y489613D01*
X1421619D01*
X1421953Y489488D01*
X1422161Y489321D01*
X1422244Y488988D01*
X1422161Y488655D01*
X1421911Y488446D01*
X1421619Y488321D01*
X1420578D01*
G01X1421619D02*
X1422244Y487113D01*
G01X1424428D02*
X1424511Y487655D01*
X1424636Y488113D01*
X1424803Y488530D01*
X1425011Y488988D01*
X1425344Y489613D01*
X1423678D01*
G01X1426569Y487113D02*
X1427611Y489613D01*
X1428653Y487113D01*
G01X1428278Y487988D02*
X1426944D01*
G01X1430711Y487113D02*
Y489613D01*
X1430211Y489113D01*
G01Y487113D02*
X1431211D01*
G01X1433811D02*
Y489613D01*
X1433311Y489113D01*
G01Y487113D02*
X1434311D01*
G01X1420097Y470240D02*
Y472740D01*
X1421138D01*
X1421472Y472615D01*
X1421680Y472448D01*
X1421763Y472115D01*
X1421680Y471782D01*
X1421430Y471573D01*
X1421138Y471448D01*
X1420097D01*
G01X1421138D02*
X1421763Y470240D01*
G01X1424030D02*
Y472740D01*
X1423530Y472240D01*
G01Y470240D02*
X1424530D01*
G01X1426338Y472323D02*
X1426588Y472573D01*
X1426880Y472698D01*
X1427213Y472740D01*
X1427630Y472657D01*
X1427922Y472448D01*
X1428005Y472198D01*
X1427963Y471948D01*
X1427797Y471740D01*
X1426963Y471323D01*
X1426588Y471032D01*
X1426338Y470615D01*
X1426255Y470240D01*
X1428005D01*
G01X1428980Y472740D02*
X1429563Y470240D01*
X1430230Y472740D01*
X1430897Y470240D01*
X1431480Y472740D01*
G01X1432538Y472323D02*
X1432788Y472573D01*
X1433080Y472698D01*
X1433413Y472740D01*
X1433830Y472657D01*
X1434122Y472448D01*
X1434205Y472198D01*
X1434163Y471948D01*
X1433997Y471740D01*
X1433163Y471323D01*
X1432788Y471032D01*
X1432538Y470615D01*
X1432455Y470240D01*
X1434205D01*
G01X1436430D02*
X1436722Y470282D01*
X1437055Y470407D01*
X1437263Y470615D01*
X1437347Y470907D01*
X1437263Y471198D01*
X1437013Y471448D01*
X1436638Y471573D01*
X1436222D01*
X1435972Y471657D01*
X1435763Y471865D01*
X1435680Y472157D01*
X1435805Y472448D01*
X1436097Y472657D01*
X1436430Y472740D01*
X1436763Y472657D01*
X1437055Y472448D01*
X1437180Y472157D01*
X1437097Y471865D01*
X1436888Y471657D01*
X1436638Y471573D01*
X1436222D01*
X1435847Y471448D01*
X1435597Y471198D01*
X1435513Y470907D01*
X1435597Y470615D01*
X1435805Y470407D01*
X1436138Y470282D01*
X1436430Y470240D01*
G01X1406639Y512318D02*
X1404139D01*
Y513359D01*
X1404264Y513693D01*
X1404431Y513901D01*
X1404764Y513984D01*
X1405097Y513901D01*
X1405306Y513651D01*
X1405431Y513359D01*
Y512318D01*
G01Y513359D02*
X1406639Y513984D01*
G01X1406139Y515334D02*
X1406431Y515584D01*
X1406597Y515918D01*
X1406639Y516293D01*
X1406597Y516626D01*
X1406389Y516959D01*
X1406139Y517168D01*
X1405889Y517209D01*
X1405597Y517126D01*
X1405389Y516834D01*
X1405306Y516543D01*
Y516168D01*
G01Y516543D02*
X1405181Y516793D01*
X1404972Y517001D01*
X1404722Y517084D01*
X1404472Y517001D01*
X1404264Y516793D01*
X1404139Y516418D01*
X1404181Y516043D01*
X1404347Y515668D01*
G01X1406639Y518268D02*
X1404139D01*
X1406222Y519351D01*
X1404139Y520434D01*
X1406639D01*
G01Y522451D02*
X1404139D01*
X1404639Y521951D01*
G01X1406639D02*
Y522951D01*
G01X1450130Y497324D02*
X1450005Y497074D01*
X1449922Y496782D01*
Y496449D01*
X1450047Y496074D01*
X1450255Y495782D01*
X1450505Y495574D01*
X1450922Y495407D01*
X1451297Y495365D01*
X1451672Y495449D01*
X1451922Y495574D01*
X1452172Y495824D01*
X1452339Y496115D01*
X1452422Y496407D01*
Y496699D01*
X1452339Y496990D01*
X1452214Y497240D01*
X1452047Y497449D01*
G01X1452422Y499424D02*
X1451880Y499507D01*
X1451422Y499632D01*
X1451005Y499799D01*
X1450547Y500007D01*
X1449922Y500340D01*
Y498674D01*
G01X1451089Y502940D02*
X1450964Y503107D01*
X1450755Y503232D01*
X1450464Y503315D01*
X1450214Y503232D01*
X1450047Y503065D01*
X1449922Y502774D01*
Y501649D01*
X1452422D01*
Y503024D01*
X1452255Y503315D01*
X1452005Y503482D01*
X1451714Y503565D01*
X1451422Y503482D01*
X1451172Y503232D01*
X1451089Y502940D01*
Y501649D01*
G01X1450339Y504915D02*
X1450089Y505165D01*
X1449964Y505457D01*
X1449922Y505790D01*
X1450005Y506207D01*
X1450214Y506499D01*
X1450464Y506582D01*
X1450714Y506540D01*
X1450922Y506374D01*
X1451339Y505540D01*
X1451630Y505165D01*
X1452047Y504915D01*
X1452422Y504832D01*
Y506582D01*
G01X1450339Y508015D02*
X1450089Y508265D01*
X1449964Y508557D01*
X1449922Y508890D01*
X1450005Y509307D01*
X1450214Y509599D01*
X1450464Y509682D01*
X1450714Y509640D01*
X1450922Y509474D01*
X1451339Y508640D01*
X1451630Y508265D01*
X1452047Y508015D01*
X1452422Y507932D01*
Y509682D01*
G01X1446455Y494991D02*
X1446330Y494741D01*
X1446247Y494449D01*
Y494116D01*
X1446372Y493741D01*
X1446580Y493449D01*
X1446830Y493241D01*
X1447247Y493074D01*
X1447622Y493032D01*
X1447997Y493116D01*
X1448247Y493241D01*
X1448497Y493491D01*
X1448664Y493782D01*
X1448747Y494074D01*
Y494366D01*
X1448664Y494657D01*
X1448539Y494907D01*
X1448372Y495116D01*
G01X1448747Y497091D02*
X1448205Y497174D01*
X1447747Y497299D01*
X1447330Y497466D01*
X1446872Y497674D01*
X1446247Y498007D01*
Y496341D01*
G01X1447414Y500607D02*
X1447289Y500774D01*
X1447080Y500899D01*
X1446789Y500982D01*
X1446539Y500899D01*
X1446372Y500732D01*
X1446247Y500441D01*
Y499316D01*
X1448747D01*
Y500691D01*
X1448580Y500982D01*
X1448330Y501149D01*
X1448039Y501232D01*
X1447747Y501149D01*
X1447497Y500899D01*
X1447414Y500607D01*
Y499316D01*
G01X1446664Y502582D02*
X1446414Y502832D01*
X1446289Y503124D01*
X1446247Y503457D01*
X1446330Y503874D01*
X1446539Y504166D01*
X1446789Y504249D01*
X1447039Y504207D01*
X1447247Y504041D01*
X1447664Y503207D01*
X1447955Y502832D01*
X1448372Y502582D01*
X1448747Y502499D01*
Y504249D01*
G01Y506474D02*
X1446247D01*
X1446747Y505974D01*
G01X1448747D02*
Y506974D01*
G01X1417198Y505677D02*
X1417073Y505427D01*
X1416990Y505135D01*
Y504802D01*
X1417115Y504427D01*
X1417323Y504135D01*
X1417573Y503927D01*
X1417990Y503760D01*
X1418365Y503718D01*
X1418740Y503802D01*
X1418990Y503927D01*
X1419240Y504177D01*
X1419407Y504468D01*
X1419490Y504760D01*
Y505052D01*
X1419407Y505343D01*
X1419282Y505593D01*
X1419115Y505802D01*
G01X1419490Y507777D02*
X1418948Y507860D01*
X1418490Y507985D01*
X1418073Y508152D01*
X1417615Y508360D01*
X1416990Y508693D01*
Y507027D01*
G01X1418157Y511293D02*
X1418032Y511460D01*
X1417823Y511585D01*
X1417532Y511668D01*
X1417282Y511585D01*
X1417115Y511418D01*
X1416990Y511127D01*
Y510002D01*
X1419490D01*
Y511377D01*
X1419323Y511668D01*
X1419073Y511835D01*
X1418782Y511918D01*
X1418490Y511835D01*
X1418240Y511585D01*
X1418157Y511293D01*
Y510002D01*
G01X1418990Y513143D02*
X1419282Y513393D01*
X1419448Y513727D01*
X1419490Y514102D01*
X1419448Y514435D01*
X1419240Y514768D01*
X1418990Y514977D01*
X1418740Y515018D01*
X1418448Y514935D01*
X1418240Y514643D01*
X1418157Y514352D01*
Y513977D01*
G01Y514352D02*
X1418032Y514602D01*
X1417823Y514810D01*
X1417573Y514893D01*
X1417323Y514810D01*
X1417115Y514602D01*
X1416990Y514227D01*
X1417032Y513852D01*
X1417198Y513477D01*
G01X1422004Y497051D02*
X1421754Y497176D01*
X1421462Y497259D01*
X1421129D01*
X1420754Y497134D01*
X1420462Y496926D01*
X1420254Y496676D01*
X1420087Y496259D01*
X1420045Y495884D01*
X1420129Y495509D01*
X1420254Y495259D01*
X1420504Y495009D01*
X1420795Y494842D01*
X1421087Y494759D01*
X1421379D01*
X1421670Y494842D01*
X1421920Y494967D01*
X1422129Y495134D01*
G01X1424104Y494759D02*
X1424187Y495301D01*
X1424312Y495759D01*
X1424479Y496176D01*
X1424687Y496634D01*
X1425020Y497259D01*
X1423354D01*
G01X1426245Y494759D02*
X1427287Y497259D01*
X1428329Y494759D01*
G01X1427954Y495634D02*
X1426620D01*
G01X1429595Y496842D02*
X1429845Y497092D01*
X1430137Y497217D01*
X1430470Y497259D01*
X1430887Y497176D01*
X1431179Y496967D01*
X1431262Y496717D01*
X1431220Y496467D01*
X1431054Y496259D01*
X1430220Y495842D01*
X1429845Y495551D01*
X1429595Y495134D01*
X1429512Y494759D01*
X1431262D01*
G01X1433487D02*
X1433779Y494801D01*
X1434112Y494926D01*
X1434320Y495134D01*
X1434404Y495426D01*
X1434320Y495717D01*
X1434070Y495967D01*
X1433695Y496092D01*
X1433279D01*
X1433029Y496176D01*
X1432820Y496384D01*
X1432737Y496676D01*
X1432862Y496967D01*
X1433154Y497176D01*
X1433487Y497259D01*
X1433820Y497176D01*
X1434112Y496967D01*
X1434237Y496676D01*
X1434154Y496384D01*
X1433945Y496176D01*
X1433695Y496092D01*
X1433279D01*
X1432904Y495967D01*
X1432654Y495717D01*
X1432570Y495426D01*
X1432654Y495134D01*
X1432862Y494926D01*
X1433195Y494801D01*
X1433487Y494759D01*
G01X1404266Y497491D02*
X1404141Y497241D01*
X1404058Y496949D01*
Y496616D01*
X1404183Y496241D01*
X1404391Y495949D01*
X1404641Y495741D01*
X1405058Y495574D01*
X1405433Y495532D01*
X1405808Y495616D01*
X1406058Y495741D01*
X1406308Y495991D01*
X1406475Y496282D01*
X1406558Y496574D01*
Y496866D01*
X1406475Y497157D01*
X1406350Y497407D01*
X1406183Y497616D01*
G01X1406558Y499591D02*
X1406016Y499674D01*
X1405558Y499799D01*
X1405141Y499966D01*
X1404683Y500174D01*
X1404058Y500507D01*
Y498841D01*
G01X1405225Y503107D02*
X1405100Y503274D01*
X1404891Y503399D01*
X1404600Y503482D01*
X1404350Y503399D01*
X1404183Y503232D01*
X1404058Y502941D01*
Y501816D01*
X1406558D01*
Y503191D01*
X1406391Y503482D01*
X1406141Y503649D01*
X1405850Y503732D01*
X1405558Y503649D01*
X1405308Y503399D01*
X1405225Y503107D01*
Y501816D01*
G01X1406558Y505874D02*
X1404058D01*
X1404558Y505374D01*
G01X1406558D02*
Y506374D01*
G01X1412147Y507168D02*
X1412022Y506918D01*
X1411939Y506626D01*
Y506293D01*
X1412064Y505918D01*
X1412272Y505626D01*
X1412522Y505418D01*
X1412939Y505251D01*
X1413314Y505209D01*
X1413689Y505293D01*
X1413939Y505418D01*
X1414189Y505668D01*
X1414356Y505959D01*
X1414439Y506251D01*
Y506543D01*
X1414356Y506834D01*
X1414231Y507084D01*
X1414064Y507293D01*
G01X1414439Y509268D02*
X1413897Y509351D01*
X1413439Y509476D01*
X1413022Y509643D01*
X1412564Y509851D01*
X1411939Y510184D01*
Y508518D01*
G01X1414439Y511409D02*
X1411939Y512451D01*
X1414439Y513493D01*
G01X1413564Y513118D02*
Y511784D01*
G01X1413939Y514634D02*
X1414231Y514884D01*
X1414397Y515218D01*
X1414439Y515593D01*
X1414397Y515926D01*
X1414189Y516259D01*
X1413939Y516468D01*
X1413689Y516509D01*
X1413397Y516426D01*
X1413189Y516134D01*
X1413106Y515843D01*
Y515468D01*
G01Y515843D02*
X1412981Y516093D01*
X1412772Y516301D01*
X1412522Y516384D01*
X1412272Y516301D01*
X1412064Y516093D01*
X1411939Y515718D01*
X1411981Y515343D01*
X1412147Y514968D01*
G01X1414439Y518651D02*
X1414397Y518943D01*
X1414272Y519276D01*
X1414064Y519484D01*
X1413772Y519568D01*
X1413481Y519484D01*
X1413231Y519234D01*
X1413106Y518859D01*
Y518443D01*
X1413022Y518193D01*
X1412814Y517984D01*
X1412522Y517901D01*
X1412231Y518026D01*
X1412022Y518318D01*
X1411939Y518651D01*
X1412022Y518984D01*
X1412231Y519276D01*
X1412522Y519401D01*
X1412814Y519318D01*
X1413022Y519109D01*
X1413106Y518859D01*
Y518443D01*
X1413231Y518068D01*
X1413481Y517818D01*
X1413772Y517734D01*
X1414064Y517818D01*
X1414272Y518026D01*
X1414397Y518359D01*
X1414439Y518651D01*
G01X1407766Y497491D02*
X1407641Y497241D01*
X1407558Y496949D01*
Y496616D01*
X1407683Y496241D01*
X1407891Y495949D01*
X1408141Y495741D01*
X1408558Y495574D01*
X1408933Y495532D01*
X1409308Y495616D01*
X1409558Y495741D01*
X1409808Y495991D01*
X1409975Y496282D01*
X1410058Y496574D01*
Y496866D01*
X1409975Y497157D01*
X1409850Y497407D01*
X1409683Y497616D01*
G01X1410058Y499591D02*
X1409516Y499674D01*
X1409058Y499799D01*
X1408641Y499966D01*
X1408183Y500174D01*
X1407558Y500507D01*
Y498841D01*
G01X1408725Y503107D02*
X1408600Y503274D01*
X1408391Y503399D01*
X1408100Y503482D01*
X1407850Y503399D01*
X1407683Y503232D01*
X1407558Y502941D01*
Y501816D01*
X1410058D01*
Y503191D01*
X1409891Y503482D01*
X1409641Y503649D01*
X1409350Y503732D01*
X1409058Y503649D01*
X1408808Y503399D01*
X1408725Y503107D01*
Y501816D01*
G01X1407975Y505082D02*
X1407725Y505332D01*
X1407600Y505624D01*
X1407558Y505957D01*
X1407641Y506374D01*
X1407850Y506666D01*
X1408100Y506749D01*
X1408350Y506707D01*
X1408558Y506541D01*
X1408975Y505707D01*
X1409266Y505332D01*
X1409683Y505082D01*
X1410058Y504999D01*
Y506749D01*
G01X1408447Y510868D02*
X1408322Y510618D01*
X1408239Y510326D01*
Y509993D01*
X1408364Y509618D01*
X1408572Y509326D01*
X1408822Y509118D01*
X1409239Y508951D01*
X1409614Y508909D01*
X1409989Y508993D01*
X1410239Y509118D01*
X1410489Y509368D01*
X1410656Y509659D01*
X1410739Y509951D01*
Y510243D01*
X1410656Y510534D01*
X1410531Y510784D01*
X1410364Y510993D01*
G01X1410739Y512968D02*
X1410197Y513051D01*
X1409739Y513176D01*
X1409322Y513343D01*
X1408864Y513551D01*
X1408239Y513884D01*
Y512218D01*
G01X1410739Y515109D02*
X1408239Y516151D01*
X1410739Y517193D01*
G01X1409864Y516818D02*
Y515484D01*
G01X1410239Y518334D02*
X1410531Y518584D01*
X1410697Y518918D01*
X1410739Y519293D01*
X1410697Y519626D01*
X1410489Y519959D01*
X1410239Y520168D01*
X1409989Y520209D01*
X1409697Y520126D01*
X1409489Y519834D01*
X1409406Y519543D01*
Y519168D01*
G01Y519543D02*
X1409281Y519793D01*
X1409072Y520001D01*
X1408822Y520084D01*
X1408572Y520001D01*
X1408364Y519793D01*
X1408239Y519418D01*
X1408281Y519043D01*
X1408447Y518668D01*
G01X1410739Y522268D02*
X1410197Y522351D01*
X1409739Y522476D01*
X1409322Y522643D01*
X1408864Y522851D01*
X1408239Y523184D01*
Y521518D01*
G01X1417693Y516177D02*
X1416027D01*
Y518677D01*
X1417693D01*
G01X1417027Y517469D02*
X1416027D01*
G01X1419043Y518677D02*
Y516885D01*
X1419210Y516510D01*
X1419543Y516260D01*
X1419960Y516177D01*
X1420377Y516260D01*
X1420710Y516510D01*
X1420877Y516885D01*
Y518677D01*
G01X1422977Y516177D02*
X1423060Y516719D01*
X1423185Y517177D01*
X1423352Y517594D01*
X1423560Y518052D01*
X1423893Y518677D01*
X1422227D01*
G01X1425118Y516177D02*
X1426160Y518677D01*
X1427202Y516177D01*
G01X1426827Y517052D02*
X1425493D01*
G01X1428343Y516552D02*
X1428593Y516344D01*
X1428885Y516219D01*
X1429260Y516177D01*
X1429635Y516260D01*
X1429927Y516427D01*
X1430135Y516719D01*
X1430177Y517052D01*
X1430093Y517385D01*
X1429885Y517594D01*
X1429593Y517760D01*
X1429302Y517802D01*
X1429010Y517760D01*
X1428635Y517594D01*
X1428760Y518677D01*
X1429885D01*
G01X1448296Y544040D02*
X1473200D01*
G01X1430710Y551313D02*
Y560490D01*
X1431200D01*
G01X1439800Y544040D02*
X1443800D01*
G01X1436442Y560366D02*
X1438742D01*
Y553400D01*
G01X1479770Y540200D02*
Y529300D01*
X1434040D01*
Y533410D01*
X1430710D01*
Y548087D01*
G01X1438742Y549300D02*
Y546576D01*
G01X1430597Y564520D02*
Y567020D01*
X1431638D01*
X1431972Y566895D01*
X1432180Y566728D01*
X1432263Y566395D01*
X1432180Y566062D01*
X1431930Y565853D01*
X1431638Y565728D01*
X1430597D01*
G01X1431638D02*
X1432263Y564520D01*
G01X1433738D02*
Y567020D01*
X1435322D01*
G01X1434738Y565812D02*
X1433738D01*
G01X1437630Y564520D02*
Y567020D01*
X1437130Y566520D01*
G01Y564520D02*
X1438130D01*
G01X1440647D02*
X1440730Y565062D01*
X1440855Y565520D01*
X1441022Y565937D01*
X1441230Y566395D01*
X1441563Y567020D01*
X1439897D01*
G01X1417427Y564790D02*
Y567290D01*
X1418468D01*
X1418802Y567165D01*
X1419010Y566998D01*
X1419093Y566665D01*
X1419010Y566332D01*
X1418760Y566123D01*
X1418468Y565998D01*
X1417427D01*
G01X1418468D02*
X1419093Y564790D01*
G01X1420568D02*
Y567290D01*
X1422152D01*
G01X1421568Y566082D02*
X1420568D01*
G01X1424460Y564790D02*
Y567290D01*
X1423960Y566790D01*
G01Y564790D02*
X1424960D01*
G01X1427560D02*
X1427852Y564832D01*
X1428185Y564957D01*
X1428393Y565165D01*
X1428477Y565457D01*
X1428393Y565748D01*
X1428143Y565998D01*
X1427768Y566123D01*
X1427352D01*
X1427102Y566207D01*
X1426893Y566415D01*
X1426810Y566707D01*
X1426935Y566998D01*
X1427227Y567207D01*
X1427560Y567290D01*
X1427893Y567207D01*
X1428185Y566998D01*
X1428310Y566707D01*
X1428227Y566415D01*
X1428018Y566207D01*
X1427768Y566123D01*
X1427352D01*
X1426977Y565998D01*
X1426727Y565748D01*
X1426643Y565457D01*
X1426727Y565165D01*
X1426935Y564957D01*
X1427268Y564832D01*
X1427560Y564790D01*
G01X1465542Y563767D02*
X1465417Y563517D01*
X1465334Y563225D01*
Y562892D01*
X1465459Y562517D01*
X1465667Y562225D01*
X1465917Y562017D01*
X1466334Y561850D01*
X1466709Y561808D01*
X1467084Y561892D01*
X1467334Y562017D01*
X1467584Y562267D01*
X1467751Y562558D01*
X1467834Y562850D01*
Y563142D01*
X1467751Y563433D01*
X1467626Y563683D01*
X1467459Y563892D01*
G01X1465334Y565950D02*
X1467834D01*
G01X1465334Y564992D02*
Y566908D01*
G01X1466792Y568258D02*
X1466501Y568550D01*
X1466334Y568800D01*
X1466251Y569133D01*
X1466334Y569425D01*
X1466501Y569633D01*
X1466751Y569800D01*
X1467042Y569842D01*
X1467292Y569800D01*
X1467542Y569633D01*
X1467751Y569383D01*
X1467834Y569092D01*
X1467751Y568758D01*
X1467501Y568467D01*
X1467126Y568300D01*
X1466709Y568258D01*
X1466167Y568342D01*
X1465876Y568467D01*
X1465584Y568675D01*
X1465376Y568967D01*
X1465334Y569258D01*
X1465417Y569550D01*
X1465626Y569758D01*
G01X1467459Y571233D02*
X1467667Y571483D01*
X1467792Y571775D01*
X1467834Y572150D01*
X1467751Y572525D01*
X1467584Y572817D01*
X1467292Y573025D01*
X1466959Y573067D01*
X1466626Y572983D01*
X1466417Y572775D01*
X1466251Y572483D01*
X1466209Y572192D01*
X1466251Y571900D01*
X1466417Y571525D01*
X1465334Y571650D01*
Y572775D01*
G01X1456417Y548458D02*
X1456167Y548583D01*
X1455875Y548666D01*
X1455542D01*
X1455167Y548541D01*
X1454875Y548333D01*
X1454667Y548083D01*
X1454500Y547666D01*
X1454458Y547291D01*
X1454542Y546916D01*
X1454667Y546666D01*
X1454917Y546416D01*
X1455208Y546249D01*
X1455500Y546166D01*
X1455792D01*
X1456083Y546249D01*
X1456333Y546374D01*
X1456542Y546541D01*
G01X1458517Y546166D02*
X1458600Y546708D01*
X1458725Y547166D01*
X1458892Y547583D01*
X1459100Y548041D01*
X1459433Y548666D01*
X1457767D01*
G01X1460658Y546166D02*
X1461700Y548666D01*
X1462742Y546166D01*
G01X1462367Y547041D02*
X1461033D01*
G01X1464008Y548249D02*
X1464258Y548499D01*
X1464550Y548624D01*
X1464883Y548666D01*
X1465300Y548583D01*
X1465592Y548374D01*
X1465675Y548124D01*
X1465633Y547874D01*
X1465467Y547666D01*
X1464633Y547249D01*
X1464258Y546958D01*
X1464008Y546541D01*
X1463925Y546166D01*
X1465675D01*
G01X1467817D02*
X1467900Y546708D01*
X1468025Y547166D01*
X1468192Y547583D01*
X1468400Y548041D01*
X1468733Y548666D01*
X1467067D01*
G01X1460900Y549736D02*
X1464691D01*
Y562532D01*
X1460900D01*
G01X1448300Y549736D02*
X1444738D01*
Y562532D01*
X1448300D01*
G01X1445600Y585100D02*
X1448298D01*
G01X1463600D02*
X1460905D01*
G01X1463600D02*
Y562528D01*
G01X1445600Y585100D02*
Y562525D01*
G01X1436383Y590365D02*
Y568365D01*
X1418683D01*
Y590365D01*
X1436383D01*
G01X1405530Y533916D02*
X1404521D01*
Y535098D01*
G01X1424599Y534988D02*
Y533916D01*
G01X1423353Y553994D02*
X1424599D01*
Y552812D01*
G01X1404521Y552796D02*
Y553994D01*
X1405669D01*
G01X1424599Y533916D02*
X1423486D01*
G01X1409800Y588080D02*
X1414000D01*
X1416600Y585480D01*
Y566380D01*
X1409800D01*
G01X1463695Y608806D02*
X1463663D01*
Y610067D01*
X1467704D01*
G01X1433308Y625550D02*
X1578985D01*
Y611924D01*
G01X1439999Y607642D02*
X1461723D01*
G01X1452767Y605159D02*
X1452517Y605284D01*
X1452225Y605367D01*
X1451892D01*
X1451517Y605242D01*
X1451225Y605034D01*
X1451017Y604784D01*
X1450850Y604367D01*
X1450808Y603992D01*
X1450892Y603617D01*
X1451017Y603367D01*
X1451267Y603117D01*
X1451558Y602950D01*
X1451850Y602867D01*
X1452142D01*
X1452433Y602950D01*
X1452683Y603075D01*
X1452892Y603242D01*
G01X1454867Y602867D02*
X1454950Y603409D01*
X1455075Y603867D01*
X1455242Y604284D01*
X1455450Y604742D01*
X1455783Y605367D01*
X1454117D01*
G01X1457008Y602867D02*
X1458050Y605367D01*
X1459092Y602867D01*
G01X1458717Y603742D02*
X1457383D01*
G01X1461150Y602867D02*
X1461442Y602909D01*
X1461775Y603034D01*
X1461983Y603242D01*
X1462067Y603534D01*
X1461983Y603825D01*
X1461733Y604075D01*
X1461358Y604200D01*
X1460942D01*
X1460692Y604284D01*
X1460483Y604492D01*
X1460400Y604784D01*
X1460525Y605075D01*
X1460817Y605284D01*
X1461150Y605367D01*
X1461483Y605284D01*
X1461775Y605075D01*
X1461900Y604784D01*
X1461817Y604492D01*
X1461608Y604284D01*
X1461358Y604200D01*
X1460942D01*
X1460567Y604075D01*
X1460317Y603825D01*
X1460233Y603534D01*
X1460317Y603242D01*
X1460525Y603034D01*
X1460858Y602909D01*
X1461150Y602867D01*
G01X1436200Y604666D02*
Y602166D01*
G01X1435242Y604666D02*
X1437158D01*
G01X1438425Y602166D02*
Y604666D01*
G01X1440175D02*
Y602166D01*
G01Y603416D02*
X1438425D01*
G01X1442317Y602166D02*
X1442400Y602708D01*
X1442525Y603166D01*
X1442692Y603583D01*
X1442900Y604041D01*
X1443233Y604666D01*
X1441567D01*
G01X1444458Y602166D02*
X1445500Y604666D01*
X1446542Y602166D01*
G01X1446167Y603041D02*
X1444833D01*
G01X1448600Y602166D02*
Y604666D01*
X1448100Y604166D01*
G01Y602166D02*
X1449100D01*
G01X1452717Y591267D02*
Y593767D01*
X1453758D01*
X1454092Y593642D01*
X1454300Y593475D01*
X1454383Y593142D01*
X1454300Y592809D01*
X1454050Y592600D01*
X1453758Y592475D01*
X1452717D01*
G01X1453758D02*
X1454383Y591267D01*
G01X1456650Y593767D02*
Y591267D01*
G01X1455692Y593767D02*
X1457608D01*
G01X1460250Y591267D02*
Y593767D01*
X1458708Y591975D01*
X1460792D01*
G01X1461933Y591767D02*
X1462183Y591475D01*
X1462517Y591309D01*
X1462892Y591267D01*
X1463225Y591309D01*
X1463558Y591517D01*
X1463767Y591767D01*
X1463808Y592017D01*
X1463725Y592309D01*
X1463433Y592517D01*
X1463142Y592600D01*
X1462767D01*
G01X1463142D02*
X1463392Y592725D01*
X1463600Y592934D01*
X1463683Y593184D01*
X1463600Y593434D01*
X1463392Y593642D01*
X1463017Y593767D01*
X1462642Y593725D01*
X1462267Y593559D01*
G01X1439867Y592159D02*
X1439617Y592284D01*
X1439325Y592367D01*
X1438992D01*
X1438617Y592242D01*
X1438325Y592034D01*
X1438117Y591784D01*
X1437950Y591367D01*
X1437908Y590992D01*
X1437992Y590617D01*
X1438117Y590367D01*
X1438367Y590117D01*
X1438658Y589950D01*
X1438950Y589867D01*
X1439242D01*
X1439533Y589950D01*
X1439783Y590075D01*
X1439992Y590242D01*
G01X1441967Y589867D02*
X1442050Y590409D01*
X1442175Y590867D01*
X1442342Y591284D01*
X1442550Y591742D01*
X1442883Y592367D01*
X1441217D01*
G01X1443900D02*
X1444483Y589867D01*
X1445150Y592367D01*
X1445817Y589867D01*
X1446400Y592367D01*
G01X1447333Y590242D02*
X1447583Y590034D01*
X1447875Y589909D01*
X1448250Y589867D01*
X1448625Y589950D01*
X1448917Y590117D01*
X1449125Y590409D01*
X1449167Y590742D01*
X1449083Y591075D01*
X1448875Y591284D01*
X1448583Y591450D01*
X1448292Y591492D01*
X1448000Y591450D01*
X1447625Y591284D01*
X1447750Y592367D01*
X1448875D01*
G01X1436067Y598859D02*
X1435817Y598984D01*
X1435525Y599067D01*
X1435192D01*
X1434817Y598942D01*
X1434525Y598734D01*
X1434317Y598484D01*
X1434150Y598067D01*
X1434108Y597692D01*
X1434192Y597317D01*
X1434317Y597067D01*
X1434567Y596817D01*
X1434858Y596650D01*
X1435150Y596567D01*
X1435442D01*
X1435733Y596650D01*
X1435983Y596775D01*
X1436192Y596942D01*
G01X1437458Y598650D02*
X1437708Y598900D01*
X1438000Y599025D01*
X1438333Y599067D01*
X1438750Y598984D01*
X1439042Y598775D01*
X1439125Y598525D01*
X1439083Y598275D01*
X1438917Y598067D01*
X1438083Y597650D01*
X1437708Y597359D01*
X1437458Y596942D01*
X1437375Y596567D01*
X1439125D01*
G01X1440558Y598650D02*
X1440808Y598900D01*
X1441100Y599025D01*
X1441433Y599067D01*
X1441850Y598984D01*
X1442142Y598775D01*
X1442225Y598525D01*
X1442183Y598275D01*
X1442017Y598067D01*
X1441183Y597650D01*
X1440808Y597359D01*
X1440558Y596942D01*
X1440475Y596567D01*
X1442225D01*
G01X1443200Y599067D02*
X1443783Y596567D01*
X1444450Y599067D01*
X1445117Y596567D01*
X1445700Y599067D01*
G01X1446758Y598650D02*
X1447008Y598900D01*
X1447300Y599025D01*
X1447633Y599067D01*
X1448050Y598984D01*
X1448342Y598775D01*
X1448425Y598525D01*
X1448383Y598275D01*
X1448217Y598067D01*
X1447383Y597650D01*
X1447008Y597359D01*
X1446758Y596942D01*
X1446675Y596567D01*
X1448425D01*
G01X1449858Y598650D02*
X1450108Y598900D01*
X1450400Y599025D01*
X1450733Y599067D01*
X1451150Y598984D01*
X1451442Y598775D01*
X1451525Y598525D01*
X1451483Y598275D01*
X1451317Y598067D01*
X1450483Y597650D01*
X1450108Y597359D01*
X1449858Y596942D01*
X1449775Y596567D01*
X1451525D01*
G01X1423277Y594050D02*
Y591550D01*
X1424943D01*
G01X1427127D02*
X1427210Y592092D01*
X1427335Y592550D01*
X1427502Y592967D01*
X1427710Y593425D01*
X1428043Y594050D01*
X1426377D01*
G01X1429268Y591550D02*
X1430310Y594050D01*
X1431352Y591550D01*
G01X1430977Y592425D02*
X1429643D01*
G01X1432493Y591925D02*
X1432743Y591717D01*
X1433035Y591592D01*
X1433410Y591550D01*
X1433785Y591633D01*
X1434077Y591800D01*
X1434285Y592092D01*
X1434327Y592425D01*
X1434243Y592758D01*
X1434035Y592967D01*
X1433743Y593133D01*
X1433452Y593175D01*
X1433160Y593133D01*
X1432785Y592967D01*
X1432910Y594050D01*
X1434035D01*
G01X1411657Y593792D02*
X1411407Y593917D01*
X1411115Y594000D01*
X1410782D01*
X1410407Y593875D01*
X1410115Y593667D01*
X1409907Y593417D01*
X1409740Y593000D01*
X1409698Y592625D01*
X1409782Y592250D01*
X1409907Y592000D01*
X1410157Y591750D01*
X1410448Y591583D01*
X1410740Y591500D01*
X1411032D01*
X1411323Y591583D01*
X1411573Y591708D01*
X1411782Y591875D01*
G01X1413757Y591500D02*
X1413840Y592042D01*
X1413965Y592500D01*
X1414132Y592917D01*
X1414340Y593375D01*
X1414673Y594000D01*
X1413007D01*
G01X1415690D02*
X1416273Y591500D01*
X1416940Y594000D01*
X1417607Y591500D01*
X1418190Y594000D01*
G01X1419248Y593583D02*
X1419498Y593833D01*
X1419790Y593958D01*
X1420123Y594000D01*
X1420540Y593917D01*
X1420832Y593708D01*
X1420915Y593458D01*
X1420873Y593208D01*
X1420707Y593000D01*
X1419873Y592583D01*
X1419498Y592292D01*
X1419248Y591875D01*
X1419165Y591500D01*
X1420915D01*
G01X1520420Y-54580D02*
Y-57580D01*
X1522420D01*
G01X1525020D02*
Y-54580D01*
X1524420Y-55180D01*
G01Y-57580D02*
X1525620D01*
G01X1531220Y-54580D02*
Y-57580D01*
X1533220D01*
G01X1535820D02*
Y-54580D01*
X1535220Y-55180D01*
G01Y-57580D02*
X1536420D01*
G01X1539420Y-54580D02*
X1539020Y-54680D01*
X1538720Y-54930D01*
X1538520Y-55230D01*
X1538370Y-55630D01*
X1538320Y-56080D01*
X1538370Y-56530D01*
X1538520Y-56930D01*
X1538720Y-57230D01*
X1539020Y-57480D01*
X1539420Y-57580D01*
X1539820Y-57480D01*
X1540120Y-57230D01*
X1540320Y-56930D01*
X1540470Y-56530D01*
X1540520Y-56080D01*
X1540470Y-55630D01*
X1540320Y-55230D01*
X1540120Y-54930D01*
X1539820Y-54680D01*
X1539420Y-54580D01*
G01X1545620D02*
Y-57580D01*
X1547620D01*
G01X1550220D02*
Y-54580D01*
X1549620Y-55180D01*
G01Y-57580D02*
X1550820D01*
G01X1552870Y-55080D02*
X1553170Y-54780D01*
X1553520Y-54630D01*
X1553920Y-54580D01*
X1554420Y-54680D01*
X1554770Y-54930D01*
X1554870Y-55230D01*
X1554820Y-55530D01*
X1554620Y-55780D01*
X1553620Y-56280D01*
X1553170Y-56630D01*
X1552870Y-57130D01*
X1552770Y-57580D01*
X1554870D01*
G01X1560020Y-54580D02*
Y-57580D01*
X1562020D01*
G01X1564620D02*
Y-54580D01*
X1564020Y-55180D01*
G01Y-57580D02*
X1565220D01*
G01X1568820D02*
Y-54580D01*
X1566970Y-56730D01*
X1569470D01*
G01X1570320Y-58580D02*
X1573320D01*
G01X1575420Y-57580D02*
Y-54580D01*
X1574820Y-55180D01*
G01Y-57580D02*
X1576020D01*
G01X1579020Y-54580D02*
X1578620Y-54680D01*
X1578320Y-54930D01*
X1578120Y-55230D01*
X1577970Y-55630D01*
X1577920Y-56080D01*
X1577970Y-56530D01*
X1578120Y-56930D01*
X1578320Y-57230D01*
X1578620Y-57480D01*
X1579020Y-57580D01*
X1579420Y-57480D01*
X1579720Y-57230D01*
X1579920Y-56930D01*
X1580070Y-56530D01*
X1580120Y-56080D01*
X1580070Y-55630D01*
X1579920Y-55230D01*
X1579720Y-54930D01*
X1579420Y-54680D01*
X1579020Y-54580D01*
G01X1582620D02*
X1582220Y-54680D01*
X1581920Y-54930D01*
X1581720Y-55230D01*
X1581570Y-55630D01*
X1581520Y-56080D01*
X1581570Y-56530D01*
X1581720Y-56930D01*
X1581920Y-57230D01*
X1582220Y-57480D01*
X1582620Y-57580D01*
X1583020Y-57480D01*
X1583320Y-57230D01*
X1583520Y-56930D01*
X1583670Y-56530D01*
X1583720Y-56080D01*
X1583670Y-55630D01*
X1583520Y-55230D01*
X1583320Y-54930D01*
X1583020Y-54680D01*
X1582620Y-54580D01*
G01X1586220Y-57580D02*
X1585820Y-57530D01*
X1585470Y-57330D01*
X1585170Y-57030D01*
X1584970Y-56680D01*
X1584870Y-56280D01*
Y-55880D01*
X1584970Y-55480D01*
X1585170Y-55130D01*
X1585470Y-54830D01*
X1585820Y-54630D01*
X1586220Y-54580D01*
X1586620Y-54630D01*
X1586970Y-54830D01*
X1587270Y-55130D01*
X1587470Y-55480D01*
X1587570Y-55880D01*
Y-56280D01*
X1587470Y-56680D01*
X1587270Y-57030D01*
X1586970Y-57330D01*
X1586620Y-57530D01*
X1586220Y-57580D01*
G01X1588970D02*
Y-54580D01*
G01Y-56030D02*
X1589220Y-55780D01*
X1589470Y-55630D01*
X1589870Y-55580D01*
X1590170Y-55630D01*
X1590520Y-55830D01*
X1590670Y-56130D01*
Y-57580D01*
G01X1591920D02*
Y-55580D01*
G01Y-56130D02*
X1592070Y-55880D01*
X1592320Y-55680D01*
X1592670Y-55580D01*
X1593020Y-55680D01*
X1593270Y-55880D01*
X1593420Y-56130D01*
Y-57580D01*
G01Y-56130D02*
X1593570Y-55880D01*
X1593820Y-55680D01*
X1594170Y-55580D01*
X1594520Y-55680D01*
X1594770Y-55880D01*
X1594920Y-56180D01*
Y-57580D01*
G01X1595520Y-58580D02*
X1598520D01*
G01X1599520Y-57580D02*
Y-54580D01*
X1600520D01*
X1600920Y-54730D01*
X1601220Y-54930D01*
X1601470Y-55230D01*
X1601670Y-55580D01*
X1601720Y-56080D01*
X1601670Y-56580D01*
X1601470Y-56930D01*
X1601220Y-57230D01*
X1600920Y-57430D01*
X1600520Y-57580D01*
X1599520D01*
G01X1506333Y-5000D02*
Y2000D01*
X1509533D01*
X1510600Y1650D01*
X1511400Y833D01*
X1511667Y-100D01*
X1511400Y-1033D01*
X1510733Y-1733D01*
X1509533Y-2084D01*
X1506333D01*
G01X1527200Y4900D02*
X1505000D01*
Y-8700D01*
X1579320D01*
Y-8027D01*
G01X1521917Y7000D02*
X1522125Y6750D01*
X1522375Y6583D01*
X1522667Y6500D01*
X1523000Y6583D01*
X1523250Y6750D01*
X1523500Y7000D01*
X1523583Y7333D01*
Y9000D01*
G01X1525850Y6500D02*
X1526142Y6542D01*
X1526475Y6667D01*
X1526683Y6875D01*
X1526767Y7167D01*
X1526683Y7458D01*
X1526433Y7708D01*
X1526058Y7833D01*
X1525642D01*
X1525392Y7917D01*
X1525183Y8125D01*
X1525100Y8417D01*
X1525225Y8708D01*
X1525517Y8917D01*
X1525850Y9000D01*
X1526183Y8917D01*
X1526475Y8708D01*
X1526600Y8417D01*
X1526517Y8125D01*
X1526308Y7917D01*
X1526058Y7833D01*
X1525642D01*
X1525267Y7708D01*
X1525017Y7458D01*
X1524933Y7167D01*
X1525017Y6875D01*
X1525225Y6667D01*
X1525558Y6542D01*
X1525850Y6500D01*
G01X1529200Y7750D02*
X1530033D01*
Y7000D01*
X1529783Y6750D01*
X1529492Y6583D01*
X1529075Y6500D01*
X1528658Y6583D01*
X1528367Y6750D01*
X1528117Y7000D01*
X1527950Y7292D01*
X1527867Y7625D01*
Y7917D01*
X1527950Y8167D01*
X1528117Y8458D01*
X1528367Y8708D01*
X1528617Y8875D01*
X1528950Y9000D01*
X1529242D01*
X1529575Y8917D01*
X1529825Y8750D01*
G01X1532050Y6500D02*
Y9000D01*
X1531550Y8500D01*
G01Y6500D02*
X1532550D01*
G01X1886280Y37905D02*
Y10031D01*
X1522186D01*
Y37905D01*
X1886280D01*
G01X1497417Y6200D02*
X1497625Y5950D01*
X1497875Y5783D01*
X1498167Y5700D01*
X1498500Y5783D01*
X1498750Y5950D01*
X1499000Y6200D01*
X1499083Y6533D01*
Y8200D01*
G01X1501267Y5700D02*
X1501350Y6242D01*
X1501475Y6700D01*
X1501642Y7117D01*
X1501850Y7575D01*
X1502183Y8200D01*
X1500517D01*
G01X1504700Y6950D02*
X1505533D01*
Y6200D01*
X1505283Y5950D01*
X1504992Y5783D01*
X1504575Y5700D01*
X1504158Y5783D01*
X1503867Y5950D01*
X1503617Y6200D01*
X1503450Y6492D01*
X1503367Y6825D01*
Y7117D01*
X1503450Y7367D01*
X1503617Y7658D01*
X1503867Y7908D01*
X1504117Y8075D01*
X1504450Y8200D01*
X1504742D01*
X1505075Y8117D01*
X1505325Y7950D01*
G01X1506758Y7783D02*
X1507008Y8033D01*
X1507300Y8158D01*
X1507633Y8200D01*
X1508050Y8117D01*
X1508342Y7908D01*
X1508425Y7658D01*
X1508383Y7408D01*
X1508217Y7200D01*
X1507383Y6783D01*
X1507008Y6492D01*
X1506758Y6075D01*
X1506675Y5700D01*
X1508425D01*
G01X1500000Y-20100D02*
Y-9900D01*
X1580000D01*
Y-20100D01*
X1500000D01*
G01X1492540Y980D02*
Y4080D01*
X1492080Y3460D01*
G01Y980D02*
X1493000D01*
G01X1494912Y3563D02*
X1495142Y3873D01*
X1495410Y4028D01*
X1495717Y4080D01*
X1496100Y3977D01*
X1496368Y3718D01*
X1496445Y3408D01*
X1496407Y3098D01*
X1496253Y2840D01*
X1495487Y2323D01*
X1495142Y1962D01*
X1494912Y1445D01*
X1494835Y980D01*
X1496445D01*
G01X1498350Y-4680D02*
Y-1580D01*
X1497890Y-2200D01*
G01Y-4680D02*
X1498810D01*
G01X1501450D02*
Y-1580D01*
X1500990Y-2200D01*
G01Y-4680D02*
X1501910D01*
G01X1496500Y-19800D02*
Y-19799D01*
G01Y-200D02*
Y-201D01*
G01X1504345Y70113D02*
X1504652Y69855D01*
X1504997Y69700D01*
X1505303D01*
X1505610Y69855D01*
X1505840Y70113D01*
X1505955Y70475D01*
X1505878Y70837D01*
X1505687Y71147D01*
X1505342Y71353D01*
X1504882Y71457D01*
X1504613Y71663D01*
X1504498Y72025D01*
X1504575Y72387D01*
X1504767Y72645D01*
X1505035Y72800D01*
X1505303D01*
X1505572Y72697D01*
X1505802Y72438D01*
G01X1507292Y69700D02*
X1508250Y72800D01*
X1509208Y69700D01*
G01X1508863Y70785D02*
X1507637D01*
G01X1511350Y72800D02*
Y69700D01*
G01X1510468Y72800D02*
X1512232D01*
G01X1513492Y69700D02*
X1514450Y72800D01*
X1515408Y69700D01*
G01X1515063Y70785D02*
X1513837D01*
G01X1517358Y68667D02*
X1516975Y69183D01*
X1516783Y69700D01*
Y71767D01*
X1516975Y72283D01*
X1517358Y72800D01*
G01X1520650D02*
X1520343Y72697D01*
X1520113Y72438D01*
X1519960Y72128D01*
X1519845Y71715D01*
X1519807Y71250D01*
X1519845Y70785D01*
X1519960Y70372D01*
X1520113Y70062D01*
X1520343Y69803D01*
X1520650Y69700D01*
X1520957Y69803D01*
X1521187Y70062D01*
X1521340Y70372D01*
X1521455Y70785D01*
X1521493Y71250D01*
X1521455Y71715D01*
X1521340Y72128D01*
X1521187Y72438D01*
X1520957Y72697D01*
X1520650Y72800D01*
G01X1523942Y68667D02*
X1524325Y69183D01*
X1524517Y69700D01*
Y71767D01*
X1524325Y72283D01*
X1523942Y72800D01*
G01X1489297Y47439D02*
X1489172Y47189D01*
X1489089Y46897D01*
Y46564D01*
X1489214Y46189D01*
X1489422Y45897D01*
X1489672Y45689D01*
X1490089Y45522D01*
X1490464Y45480D01*
X1490839Y45564D01*
X1491089Y45689D01*
X1491339Y45939D01*
X1491506Y46230D01*
X1491589Y46522D01*
Y46814D01*
X1491506Y47105D01*
X1491381Y47355D01*
X1491214Y47564D01*
G01X1491589Y49539D02*
X1491047Y49622D01*
X1490589Y49747D01*
X1490172Y49914D01*
X1489714Y50122D01*
X1489089Y50455D01*
Y48789D01*
G01X1490339Y52972D02*
Y53805D01*
X1491089D01*
X1491339Y53555D01*
X1491506Y53264D01*
X1491589Y52847D01*
X1491506Y52430D01*
X1491339Y52139D01*
X1491089Y51889D01*
X1490797Y51722D01*
X1490464Y51639D01*
X1490172D01*
X1489922Y51722D01*
X1489631Y51889D01*
X1489381Y52139D01*
X1489214Y52389D01*
X1489089Y52722D01*
Y53014D01*
X1489172Y53347D01*
X1489339Y53597D01*
G01X1491589Y55822D02*
X1489089D01*
X1489589Y55322D01*
G01X1491589D02*
Y56322D01*
G01Y58922D02*
X1491547Y59214D01*
X1491422Y59547D01*
X1491214Y59755D01*
X1490922Y59839D01*
X1490631Y59755D01*
X1490381Y59505D01*
X1490256Y59130D01*
Y58714D01*
X1490172Y58464D01*
X1489964Y58255D01*
X1489672Y58172D01*
X1489381Y58297D01*
X1489172Y58589D01*
X1489089Y58922D01*
X1489172Y59255D01*
X1489381Y59547D01*
X1489672Y59672D01*
X1489964Y59589D01*
X1490172Y59380D01*
X1490256Y59130D01*
Y58714D01*
X1490381Y58339D01*
X1490631Y58089D01*
X1490922Y58005D01*
X1491214Y58089D01*
X1491422Y58297D01*
X1491547Y58630D01*
X1491589Y58922D01*
G01X1492797Y47439D02*
X1492672Y47189D01*
X1492589Y46897D01*
Y46564D01*
X1492714Y46189D01*
X1492922Y45897D01*
X1493172Y45689D01*
X1493589Y45522D01*
X1493964Y45480D01*
X1494339Y45564D01*
X1494589Y45689D01*
X1494839Y45939D01*
X1495006Y46230D01*
X1495089Y46522D01*
Y46814D01*
X1495006Y47105D01*
X1494881Y47355D01*
X1494714Y47564D01*
G01X1495089Y49539D02*
X1494547Y49622D01*
X1494089Y49747D01*
X1493672Y49914D01*
X1493214Y50122D01*
X1492589Y50455D01*
Y48789D01*
G01X1493839Y52972D02*
Y53805D01*
X1494589D01*
X1494839Y53555D01*
X1495006Y53264D01*
X1495089Y52847D01*
X1495006Y52430D01*
X1494839Y52139D01*
X1494589Y51889D01*
X1494297Y51722D01*
X1493964Y51639D01*
X1493672D01*
X1493422Y51722D01*
X1493131Y51889D01*
X1492881Y52139D01*
X1492714Y52389D01*
X1492589Y52722D01*
Y53014D01*
X1492672Y53347D01*
X1492839Y53597D01*
G01X1493006Y55030D02*
X1492756Y55280D01*
X1492631Y55572D01*
X1492589Y55905D01*
X1492672Y56322D01*
X1492881Y56614D01*
X1493131Y56697D01*
X1493381Y56655D01*
X1493589Y56489D01*
X1494006Y55655D01*
X1494297Y55280D01*
X1494714Y55030D01*
X1495089Y54947D01*
Y56697D01*
G01X1492589Y58922D02*
X1492672Y58589D01*
X1492881Y58339D01*
X1493131Y58172D01*
X1493464Y58047D01*
X1493839Y58005D01*
X1494214Y58047D01*
X1494547Y58172D01*
X1494797Y58339D01*
X1495006Y58589D01*
X1495089Y58922D01*
X1495006Y59255D01*
X1494797Y59505D01*
X1494547Y59672D01*
X1494214Y59797D01*
X1493839Y59839D01*
X1493464Y59797D01*
X1493131Y59672D01*
X1492881Y59505D01*
X1492672Y59255D01*
X1492589Y58922D01*
G01X1496297Y47439D02*
X1496172Y47189D01*
X1496089Y46897D01*
Y46564D01*
X1496214Y46189D01*
X1496422Y45897D01*
X1496672Y45689D01*
X1497089Y45522D01*
X1497464Y45480D01*
X1497839Y45564D01*
X1498089Y45689D01*
X1498339Y45939D01*
X1498506Y46230D01*
X1498589Y46522D01*
Y46814D01*
X1498506Y47105D01*
X1498381Y47355D01*
X1498214Y47564D01*
G01X1498589Y49539D02*
X1498047Y49622D01*
X1497589Y49747D01*
X1497172Y49914D01*
X1496714Y50122D01*
X1496089Y50455D01*
Y48789D01*
G01X1497339Y52972D02*
Y53805D01*
X1498089D01*
X1498339Y53555D01*
X1498506Y53264D01*
X1498589Y52847D01*
X1498506Y52430D01*
X1498339Y52139D01*
X1498089Y51889D01*
X1497797Y51722D01*
X1497464Y51639D01*
X1497172D01*
X1496922Y51722D01*
X1496631Y51889D01*
X1496381Y52139D01*
X1496214Y52389D01*
X1496089Y52722D01*
Y53014D01*
X1496172Y53347D01*
X1496339Y53597D01*
G01X1498589Y55822D02*
X1496089D01*
X1496589Y55322D01*
G01X1498589D02*
Y56322D01*
G01X1498297Y58214D02*
X1498506Y58505D01*
X1498589Y58839D01*
X1498506Y59172D01*
X1498256Y59464D01*
X1497881Y59672D01*
X1497506Y59755D01*
X1497047D01*
X1496672Y59672D01*
X1496339Y59464D01*
X1496172Y59214D01*
X1496089Y58922D01*
X1496172Y58589D01*
X1496339Y58339D01*
X1496589Y58172D01*
X1496922Y58089D01*
X1497214Y58172D01*
X1497506Y58380D01*
X1497672Y58630D01*
X1497714Y58922D01*
X1497631Y59255D01*
X1497422Y59505D01*
X1497047Y59755D01*
G01X1482297Y47439D02*
X1482172Y47189D01*
X1482089Y46897D01*
Y46564D01*
X1482214Y46189D01*
X1482422Y45897D01*
X1482672Y45689D01*
X1483089Y45522D01*
X1483464Y45480D01*
X1483839Y45564D01*
X1484089Y45689D01*
X1484339Y45939D01*
X1484506Y46230D01*
X1484589Y46522D01*
Y46814D01*
X1484506Y47105D01*
X1484381Y47355D01*
X1484214Y47564D01*
G01X1484589Y49539D02*
X1484047Y49622D01*
X1483589Y49747D01*
X1483172Y49914D01*
X1482714Y50122D01*
X1482089Y50455D01*
Y48789D01*
G01X1483339Y52972D02*
Y53805D01*
X1484089D01*
X1484339Y53555D01*
X1484506Y53264D01*
X1484589Y52847D01*
X1484506Y52430D01*
X1484339Y52139D01*
X1484089Y51889D01*
X1483797Y51722D01*
X1483464Y51639D01*
X1483172D01*
X1482922Y51722D01*
X1482631Y51889D01*
X1482381Y52139D01*
X1482214Y52389D01*
X1482089Y52722D01*
Y53014D01*
X1482172Y53347D01*
X1482339Y53597D01*
G01X1484589Y55822D02*
X1482089D01*
X1482589Y55322D01*
G01X1484589D02*
Y56322D01*
G01X1483547Y58130D02*
X1483256Y58422D01*
X1483089Y58672D01*
X1483006Y59005D01*
X1483089Y59297D01*
X1483256Y59505D01*
X1483506Y59672D01*
X1483797Y59714D01*
X1484047Y59672D01*
X1484297Y59505D01*
X1484506Y59255D01*
X1484589Y58964D01*
X1484506Y58630D01*
X1484256Y58339D01*
X1483881Y58172D01*
X1483464Y58130D01*
X1482922Y58214D01*
X1482631Y58339D01*
X1482339Y58547D01*
X1482131Y58839D01*
X1482089Y59130D01*
X1482172Y59422D01*
X1482381Y59630D01*
G01X1478797Y47439D02*
X1478672Y47189D01*
X1478589Y46897D01*
Y46564D01*
X1478714Y46189D01*
X1478922Y45897D01*
X1479172Y45689D01*
X1479589Y45522D01*
X1479964Y45480D01*
X1480339Y45564D01*
X1480589Y45689D01*
X1480839Y45939D01*
X1481006Y46230D01*
X1481089Y46522D01*
Y46814D01*
X1481006Y47105D01*
X1480881Y47355D01*
X1480714Y47564D01*
G01X1481089Y49539D02*
X1480547Y49622D01*
X1480089Y49747D01*
X1479672Y49914D01*
X1479214Y50122D01*
X1478589Y50455D01*
Y48789D01*
G01X1479839Y52972D02*
Y53805D01*
X1480589D01*
X1480839Y53555D01*
X1481006Y53264D01*
X1481089Y52847D01*
X1481006Y52430D01*
X1480839Y52139D01*
X1480589Y51889D01*
X1480297Y51722D01*
X1479964Y51639D01*
X1479672D01*
X1479422Y51722D01*
X1479131Y51889D01*
X1478881Y52139D01*
X1478714Y52389D01*
X1478589Y52722D01*
Y53014D01*
X1478672Y53347D01*
X1478839Y53597D01*
G01X1481089Y55822D02*
X1478589D01*
X1479089Y55322D01*
G01X1481089D02*
Y56322D01*
G01X1480714Y58005D02*
X1480922Y58255D01*
X1481047Y58547D01*
X1481089Y58922D01*
X1481006Y59297D01*
X1480839Y59589D01*
X1480547Y59797D01*
X1480214Y59839D01*
X1479881Y59755D01*
X1479672Y59547D01*
X1479506Y59255D01*
X1479464Y58964D01*
X1479506Y58672D01*
X1479672Y58297D01*
X1478589Y58422D01*
Y59547D01*
G01X1485797Y47439D02*
X1485672Y47189D01*
X1485589Y46897D01*
Y46564D01*
X1485714Y46189D01*
X1485922Y45897D01*
X1486172Y45689D01*
X1486589Y45522D01*
X1486964Y45480D01*
X1487339Y45564D01*
X1487589Y45689D01*
X1487839Y45939D01*
X1488006Y46230D01*
X1488089Y46522D01*
Y46814D01*
X1488006Y47105D01*
X1487881Y47355D01*
X1487714Y47564D01*
G01X1488089Y49539D02*
X1487547Y49622D01*
X1487089Y49747D01*
X1486672Y49914D01*
X1486214Y50122D01*
X1485589Y50455D01*
Y48789D01*
G01X1486839Y52972D02*
Y53805D01*
X1487589D01*
X1487839Y53555D01*
X1488006Y53264D01*
X1488089Y52847D01*
X1488006Y52430D01*
X1487839Y52139D01*
X1487589Y51889D01*
X1487297Y51722D01*
X1486964Y51639D01*
X1486672D01*
X1486422Y51722D01*
X1486131Y51889D01*
X1485881Y52139D01*
X1485714Y52389D01*
X1485589Y52722D01*
Y53014D01*
X1485672Y53347D01*
X1485839Y53597D01*
G01X1488089Y55822D02*
X1485589D01*
X1486089Y55322D01*
G01X1488089D02*
Y56322D01*
G01Y58839D02*
X1487547Y58922D01*
X1487089Y59047D01*
X1486672Y59214D01*
X1486214Y59422D01*
X1485589Y59755D01*
Y58089D01*
G01X1493800Y70433D02*
X1495592D01*
X1495967Y70600D01*
X1496217Y70933D01*
X1496300Y71350D01*
X1496217Y71767D01*
X1495967Y72100D01*
X1495592Y72267D01*
X1493800D01*
G01X1496300Y73492D02*
X1493800D01*
X1496300Y75408D01*
X1493800D01*
G01X1496300Y77550D02*
X1496258Y77842D01*
X1496133Y78175D01*
X1495925Y78383D01*
X1495633Y78467D01*
X1495342Y78383D01*
X1495092Y78133D01*
X1494967Y77758D01*
Y77342D01*
X1494883Y77092D01*
X1494675Y76883D01*
X1494383Y76800D01*
X1494092Y76925D01*
X1493883Y77217D01*
X1493800Y77550D01*
X1493883Y77883D01*
X1494092Y78175D01*
X1494383Y78300D01*
X1494675Y78217D01*
X1494883Y78008D01*
X1494967Y77758D01*
Y77342D01*
X1495092Y76967D01*
X1495342Y76717D01*
X1495633Y76633D01*
X1495925Y76717D01*
X1496133Y76925D01*
X1496258Y77258D01*
X1496300Y77550D01*
G01Y79858D02*
X1493800D01*
Y81442D01*
G01X1495008Y80858D02*
Y79858D01*
G01X1494217Y82958D02*
X1493967Y83208D01*
X1493842Y83500D01*
X1493800Y83833D01*
X1493883Y84250D01*
X1494092Y84542D01*
X1494342Y84625D01*
X1494592Y84583D01*
X1494800Y84417D01*
X1495217Y83583D01*
X1495508Y83208D01*
X1495925Y82958D01*
X1496300Y82875D01*
Y84625D01*
G01X1540844Y76061D02*
X1503044D01*
Y164261D01*
X1540844D01*
Y76061D01*
G01X1499434Y149967D02*
X1496934D01*
Y151008D01*
X1497059Y151342D01*
X1497226Y151550D01*
X1497559Y151633D01*
X1497892Y151550D01*
X1498101Y151300D01*
X1498226Y151008D01*
Y149967D01*
G01Y151008D02*
X1499434Y151633D01*
G01Y153900D02*
X1499392Y154192D01*
X1499267Y154525D01*
X1499059Y154733D01*
X1498767Y154817D01*
X1498476Y154733D01*
X1498226Y154483D01*
X1498101Y154108D01*
Y153692D01*
X1498017Y153442D01*
X1497809Y153233D01*
X1497517Y153150D01*
X1497226Y153275D01*
X1497017Y153567D01*
X1496934Y153900D01*
X1497017Y154233D01*
X1497226Y154525D01*
X1497517Y154650D01*
X1497809Y154567D01*
X1498017Y154358D01*
X1498101Y154108D01*
Y153692D01*
X1498226Y153317D01*
X1498476Y153067D01*
X1498767Y152983D01*
X1499059Y153067D01*
X1499267Y153275D01*
X1499392Y153608D01*
X1499434Y153900D01*
G01Y156208D02*
X1496934D01*
Y157792D01*
G01X1498142Y157208D02*
Y156208D01*
G01X1498934Y159183D02*
X1499226Y159433D01*
X1499392Y159767D01*
X1499434Y160142D01*
X1499392Y160475D01*
X1499184Y160808D01*
X1498934Y161017D01*
X1498684Y161058D01*
X1498392Y160975D01*
X1498184Y160683D01*
X1498101Y160392D01*
Y160017D01*
G01Y160392D02*
X1497976Y160642D01*
X1497767Y160850D01*
X1497517Y160933D01*
X1497267Y160850D01*
X1497059Y160642D01*
X1496934Y160267D01*
X1496976Y159892D01*
X1497142Y159517D01*
G01X1499434Y163700D02*
X1496934D01*
X1498726Y162158D01*
Y164242D01*
G01X1495334Y147367D02*
X1492834D01*
Y148408D01*
X1492959Y148742D01*
X1493126Y148950D01*
X1493459Y149033D01*
X1493792Y148950D01*
X1494001Y148700D01*
X1494126Y148408D01*
Y147367D01*
G01Y148408D02*
X1495334Y149033D01*
G01Y151300D02*
X1495292Y151592D01*
X1495167Y151925D01*
X1494959Y152133D01*
X1494667Y152217D01*
X1494376Y152133D01*
X1494126Y151883D01*
X1494001Y151508D01*
Y151092D01*
X1493917Y150842D01*
X1493709Y150633D01*
X1493417Y150550D01*
X1493126Y150675D01*
X1492917Y150967D01*
X1492834Y151300D01*
X1492917Y151633D01*
X1493126Y151925D01*
X1493417Y152050D01*
X1493709Y151967D01*
X1493917Y151758D01*
X1494001Y151508D01*
Y151092D01*
X1494126Y150717D01*
X1494376Y150467D01*
X1494667Y150383D01*
X1494959Y150467D01*
X1495167Y150675D01*
X1495292Y151008D01*
X1495334Y151300D01*
G01Y153608D02*
X1492834D01*
Y155192D01*
G01X1494042Y154608D02*
Y153608D01*
G01X1494834Y156583D02*
X1495126Y156833D01*
X1495292Y157167D01*
X1495334Y157542D01*
X1495292Y157875D01*
X1495084Y158208D01*
X1494834Y158417D01*
X1494584Y158458D01*
X1494292Y158375D01*
X1494084Y158083D01*
X1494001Y157792D01*
Y157417D01*
G01Y157792D02*
X1493876Y158042D01*
X1493667Y158250D01*
X1493417Y158333D01*
X1493167Y158250D01*
X1492959Y158042D01*
X1492834Y157667D01*
X1492876Y157292D01*
X1493042Y156917D01*
G01X1494959Y159683D02*
X1495167Y159933D01*
X1495292Y160225D01*
X1495334Y160600D01*
X1495251Y160975D01*
X1495084Y161267D01*
X1494792Y161475D01*
X1494459Y161517D01*
X1494126Y161433D01*
X1493917Y161225D01*
X1493751Y160933D01*
X1493709Y160642D01*
X1493751Y160350D01*
X1493917Y159975D01*
X1492834Y160100D01*
Y161225D01*
G01X1483264Y133185D02*
X1483523Y133454D01*
X1483626Y133760D01*
X1483523Y134067D01*
X1483213Y134335D01*
X1482748Y134527D01*
X1482283Y134604D01*
X1481714D01*
X1481249Y134527D01*
X1480836Y134335D01*
X1480629Y134105D01*
X1480526Y133837D01*
X1480629Y133530D01*
X1480836Y133300D01*
X1481146Y133147D01*
X1481559Y133070D01*
X1481921Y133147D01*
X1482283Y133339D01*
X1482489Y133569D01*
X1482541Y133837D01*
X1482438Y134144D01*
X1482179Y134374D01*
X1481714Y134604D01*
G01X1493687Y173059D02*
X1493840Y173214D01*
X1493955Y173473D01*
X1494032Y173834D01*
X1493955Y174144D01*
X1493802Y174351D01*
X1493533Y174506D01*
X1492498D01*
Y171406D01*
X1493763D01*
X1494032Y171613D01*
X1494185Y171923D01*
X1494262Y172284D01*
X1494185Y172646D01*
X1493955Y172956D01*
X1493687Y173059D01*
X1492498D01*
G01X1495483Y171406D02*
Y174506D01*
X1496480Y171923D01*
X1497477Y174506D01*
Y171406D01*
G01X1500423Y174248D02*
X1500193Y174403D01*
X1499925Y174506D01*
X1499618D01*
X1499273Y174351D01*
X1499005Y174093D01*
X1498813Y173783D01*
X1498660Y173266D01*
X1498622Y172801D01*
X1498698Y172336D01*
X1498813Y172026D01*
X1499043Y171716D01*
X1499312Y171509D01*
X1499580Y171406D01*
X1499848D01*
X1500117Y171509D01*
X1500347Y171664D01*
X1500538Y171871D01*
G01X1505052Y171406D02*
Y174506D01*
X1506508D01*
G01X1505972Y173008D02*
X1505052D01*
G01X1508113Y174506D02*
Y171406D01*
X1509647D01*
G01X1511022D02*
X1511980Y174506D01*
X1512938Y171406D01*
G01X1512593Y172491D02*
X1511367D01*
G01X1514275Y171819D02*
X1514582Y171561D01*
X1514927Y171406D01*
X1515233D01*
X1515540Y171561D01*
X1515770Y171819D01*
X1515885Y172181D01*
X1515808Y172543D01*
X1515617Y172853D01*
X1515272Y173059D01*
X1514812Y173163D01*
X1514543Y173369D01*
X1514428Y173731D01*
X1514505Y174093D01*
X1514697Y174351D01*
X1514965Y174506D01*
X1515233D01*
X1515502Y174403D01*
X1515732Y174144D01*
G01X1517375Y171406D02*
Y174506D01*
G01X1518985D02*
Y171406D01*
G01Y172956D02*
X1517375D01*
G01X1511634Y181267D02*
X1509134D01*
Y182308D01*
X1509259Y182642D01*
X1509426Y182850D01*
X1509759Y182933D01*
X1510092Y182850D01*
X1510301Y182600D01*
X1510426Y182308D01*
Y181267D01*
G01Y182308D02*
X1511634Y182933D01*
G01Y185117D02*
X1511092Y185200D01*
X1510634Y185325D01*
X1510217Y185492D01*
X1509759Y185700D01*
X1509134Y186033D01*
Y184367D01*
G01X1511634Y187508D02*
X1509134D01*
Y189092D01*
G01X1510342Y188508D02*
Y187508D01*
G01X1509551Y190608D02*
X1509301Y190858D01*
X1509176Y191150D01*
X1509134Y191483D01*
X1509217Y191900D01*
X1509426Y192192D01*
X1509676Y192275D01*
X1509926Y192233D01*
X1510134Y192067D01*
X1510551Y191233D01*
X1510842Y190858D01*
X1511259Y190608D01*
X1511634Y190525D01*
Y192275D01*
G01X1511342Y193792D02*
X1511551Y194083D01*
X1511634Y194417D01*
X1511551Y194750D01*
X1511301Y195042D01*
X1510926Y195250D01*
X1510551Y195333D01*
X1510092D01*
X1509717Y195250D01*
X1509384Y195042D01*
X1509217Y194792D01*
X1509134Y194500D01*
X1509217Y194167D01*
X1509384Y193917D01*
X1509634Y193750D01*
X1509967Y193667D01*
X1510259Y193750D01*
X1510551Y193958D01*
X1510717Y194208D01*
X1510759Y194500D01*
X1510676Y194833D01*
X1510467Y195083D01*
X1510092Y195333D01*
G01X1496817Y182967D02*
Y185467D01*
X1497858D01*
X1498192Y185342D01*
X1498400Y185175D01*
X1498483Y184842D01*
X1498400Y184509D01*
X1498150Y184300D01*
X1497858Y184175D01*
X1496817D01*
G01X1497858D02*
X1498483Y182967D01*
G01X1500750D02*
X1501042Y183009D01*
X1501375Y183134D01*
X1501583Y183342D01*
X1501667Y183634D01*
X1501583Y183925D01*
X1501333Y184175D01*
X1500958Y184300D01*
X1500542D01*
X1500292Y184384D01*
X1500083Y184592D01*
X1500000Y184884D01*
X1500125Y185175D01*
X1500417Y185384D01*
X1500750Y185467D01*
X1501083Y185384D01*
X1501375Y185175D01*
X1501500Y184884D01*
X1501417Y184592D01*
X1501208Y184384D01*
X1500958Y184300D01*
X1500542D01*
X1500167Y184175D01*
X1499917Y183925D01*
X1499833Y183634D01*
X1499917Y183342D01*
X1500125Y183134D01*
X1500458Y183009D01*
X1500750Y182967D01*
G01X1503058D02*
Y185467D01*
X1504642D01*
G01X1504058Y184259D02*
X1503058D01*
G01X1506950Y182967D02*
X1507242Y183009D01*
X1507575Y183134D01*
X1507783Y183342D01*
X1507867Y183634D01*
X1507783Y183925D01*
X1507533Y184175D01*
X1507158Y184300D01*
X1506742D01*
X1506492Y184384D01*
X1506283Y184592D01*
X1506200Y184884D01*
X1506325Y185175D01*
X1506617Y185384D01*
X1506950Y185467D01*
X1507283Y185384D01*
X1507575Y185175D01*
X1507700Y184884D01*
X1507617Y184592D01*
X1507408Y184384D01*
X1507158Y184300D01*
X1506742D01*
X1506367Y184175D01*
X1506117Y183925D01*
X1506033Y183634D01*
X1506117Y183342D01*
X1506325Y183134D01*
X1506658Y183009D01*
X1506950Y182967D01*
G01X1507480Y190517D02*
X1504980D01*
Y191558D01*
X1505105Y191892D01*
X1505272Y192100D01*
X1505605Y192183D01*
X1505938Y192100D01*
X1506147Y191850D01*
X1506272Y191558D01*
Y190517D01*
G01Y191558D02*
X1507480Y192183D01*
G01Y194367D02*
X1506938Y194450D01*
X1506480Y194575D01*
X1506063Y194742D01*
X1505605Y194950D01*
X1504980Y195283D01*
Y193617D01*
G01X1507480Y196758D02*
X1504980D01*
Y198342D01*
G01X1506188Y197758D02*
Y196758D01*
G01X1506980Y199733D02*
X1507272Y199983D01*
X1507438Y200317D01*
X1507480Y200692D01*
X1507438Y201025D01*
X1507230Y201358D01*
X1506980Y201567D01*
X1506730Y201608D01*
X1506438Y201525D01*
X1506230Y201233D01*
X1506147Y200942D01*
Y200567D01*
G01Y200942D02*
X1506022Y201192D01*
X1505813Y201400D01*
X1505563Y201483D01*
X1505313Y201400D01*
X1505105Y201192D01*
X1504980Y200817D01*
X1505022Y200442D01*
X1505188Y200067D01*
G01X1504980Y203750D02*
X1505063Y203417D01*
X1505272Y203167D01*
X1505522Y203000D01*
X1505855Y202875D01*
X1506230Y202833D01*
X1506605Y202875D01*
X1506938Y203000D01*
X1507188Y203167D01*
X1507397Y203417D01*
X1507480Y203750D01*
X1507397Y204083D01*
X1507188Y204333D01*
X1506938Y204500D01*
X1506605Y204625D01*
X1506230Y204667D01*
X1505855Y204625D01*
X1505522Y204500D01*
X1505272Y204333D01*
X1505063Y204083D01*
X1504980Y203750D01*
G01X1503880Y190517D02*
X1501380D01*
Y191558D01*
X1501505Y191892D01*
X1501672Y192100D01*
X1502005Y192183D01*
X1502338Y192100D01*
X1502547Y191850D01*
X1502672Y191558D01*
Y190517D01*
G01Y191558D02*
X1503880Y192183D01*
G01Y194367D02*
X1503338Y194450D01*
X1502880Y194575D01*
X1502463Y194742D01*
X1502005Y194950D01*
X1501380Y195283D01*
Y193617D01*
G01X1503880Y196758D02*
X1501380D01*
Y198342D01*
G01X1502588Y197758D02*
Y196758D01*
G01X1501797Y199858D02*
X1501547Y200108D01*
X1501422Y200400D01*
X1501380Y200733D01*
X1501463Y201150D01*
X1501672Y201442D01*
X1501922Y201525D01*
X1502172Y201483D01*
X1502380Y201317D01*
X1502797Y200483D01*
X1503088Y200108D01*
X1503505Y199858D01*
X1503880Y199775D01*
Y201525D01*
G01Y203750D02*
X1503838Y204042D01*
X1503713Y204375D01*
X1503505Y204583D01*
X1503213Y204667D01*
X1502922Y204583D01*
X1502672Y204333D01*
X1502547Y203958D01*
Y203542D01*
X1502463Y203292D01*
X1502255Y203083D01*
X1501963Y203000D01*
X1501672Y203125D01*
X1501463Y203417D01*
X1501380Y203750D01*
X1501463Y204083D01*
X1501672Y204375D01*
X1501963Y204500D01*
X1502255Y204417D01*
X1502463Y204208D01*
X1502547Y203958D01*
Y203542D01*
X1502672Y203167D01*
X1502922Y202917D01*
X1503213Y202833D01*
X1503505Y202917D01*
X1503713Y203125D01*
X1503838Y203458D01*
X1503880Y203750D01*
G01X1484046Y219476D02*
X1483796Y219601D01*
X1483504Y219684D01*
X1483171D01*
X1482796Y219559D01*
X1482504Y219351D01*
X1482296Y219101D01*
X1482129Y218684D01*
X1482087Y218309D01*
X1482171Y217934D01*
X1482296Y217684D01*
X1482546Y217434D01*
X1482837Y217267D01*
X1483129Y217184D01*
X1483421D01*
X1483712Y217267D01*
X1483962Y217392D01*
X1484171Y217559D01*
G01X1486229Y217184D02*
X1486521Y217226D01*
X1486854Y217351D01*
X1487062Y217559D01*
X1487146Y217851D01*
X1487062Y218142D01*
X1486812Y218392D01*
X1486437Y218517D01*
X1486021D01*
X1485771Y218601D01*
X1485562Y218809D01*
X1485479Y219101D01*
X1485604Y219392D01*
X1485896Y219601D01*
X1486229Y219684D01*
X1486562Y219601D01*
X1486854Y219392D01*
X1486979Y219101D01*
X1486896Y218809D01*
X1486687Y218601D01*
X1486437Y218517D01*
X1486021D01*
X1485646Y218392D01*
X1485396Y218142D01*
X1485312Y217851D01*
X1485396Y217559D01*
X1485604Y217351D01*
X1485937Y217226D01*
X1486229Y217184D01*
G01X1490162D02*
X1488496D01*
Y219684D01*
X1490162D01*
G01X1489496Y218476D02*
X1488496D01*
G01X1492429Y217184D02*
Y219684D01*
X1491929Y219184D01*
G01Y217184D02*
X1492929D01*
G01X1495529D02*
X1495821Y217226D01*
X1496154Y217351D01*
X1496362Y217559D01*
X1496446Y217851D01*
X1496362Y218142D01*
X1496112Y218392D01*
X1495737Y218517D01*
X1495321D01*
X1495071Y218601D01*
X1494862Y218809D01*
X1494779Y219101D01*
X1494904Y219392D01*
X1495196Y219601D01*
X1495529Y219684D01*
X1495862Y219601D01*
X1496154Y219392D01*
X1496279Y219101D01*
X1496196Y218809D01*
X1495987Y218601D01*
X1495737Y218517D01*
X1495321D01*
X1494946Y218392D01*
X1494696Y218142D01*
X1494612Y217851D01*
X1494696Y217559D01*
X1494904Y217351D01*
X1495237Y217226D01*
X1495529Y217184D01*
G01X1495482Y177990D02*
X1492382D01*
X1493002Y177530D01*
G01X1495482D02*
Y178450D01*
G01X1494190Y180362D02*
X1493829Y180630D01*
X1493622Y180860D01*
X1493519Y181167D01*
X1493622Y181435D01*
X1493829Y181627D01*
X1494139Y181780D01*
X1494500Y181818D01*
X1494810Y181780D01*
X1495120Y181627D01*
X1495379Y181397D01*
X1495482Y181128D01*
X1495379Y180822D01*
X1495069Y180553D01*
X1494604Y180400D01*
X1494087Y180362D01*
X1493415Y180438D01*
X1493054Y180553D01*
X1492692Y180745D01*
X1492434Y181013D01*
X1492382Y181282D01*
X1492485Y181550D01*
X1492744Y181742D01*
G01X1522049Y176290D02*
X1525149D01*
X1524529Y176750D01*
G01X1522049D02*
Y175830D01*
G01X1523341Y173918D02*
X1523702Y173650D01*
X1523909Y173420D01*
X1524012Y173113D01*
X1523909Y172845D01*
X1523702Y172653D01*
X1523392Y172500D01*
X1523031Y172462D01*
X1522721Y172500D01*
X1522411Y172653D01*
X1522152Y172883D01*
X1522049Y173152D01*
X1522152Y173458D01*
X1522462Y173727D01*
X1522927Y173880D01*
X1523444Y173918D01*
X1524116Y173842D01*
X1524477Y173727D01*
X1524839Y173535D01*
X1525097Y173267D01*
X1525149Y172998D01*
X1525046Y172730D01*
X1524787Y172538D01*
G01X1518161Y182946D02*
X1519953D01*
X1520328Y183113D01*
X1520578Y183446D01*
X1520661Y183863D01*
X1520578Y184280D01*
X1520328Y184613D01*
X1519953Y184780D01*
X1518161D01*
G01X1520661Y186880D02*
X1520119Y186963D01*
X1519661Y187088D01*
X1519244Y187255D01*
X1518786Y187463D01*
X1518161Y187796D01*
Y186130D01*
G01X1520661Y189271D02*
X1518161D01*
Y190855D01*
G01X1519369Y190271D02*
Y189271D01*
G01X1520661Y193163D02*
X1518161D01*
X1518661Y192663D01*
G01X1520661D02*
Y193663D01*
G01X1575546Y178322D02*
X1521451D01*
Y228518D01*
X1575546D01*
Y178322D01*
G01X1511232Y167040D02*
X1511440Y166790D01*
X1511690Y166623D01*
X1511982Y166540D01*
X1512315Y166623D01*
X1512565Y166790D01*
X1512815Y167040D01*
X1512898Y167373D01*
Y169040D01*
G01X1515165Y166540D02*
X1515457Y166582D01*
X1515790Y166707D01*
X1515998Y166915D01*
X1516082Y167207D01*
X1515998Y167498D01*
X1515748Y167748D01*
X1515373Y167873D01*
X1514957D01*
X1514707Y167957D01*
X1514498Y168165D01*
X1514415Y168457D01*
X1514540Y168748D01*
X1514832Y168957D01*
X1515165Y169040D01*
X1515498Y168957D01*
X1515790Y168748D01*
X1515915Y168457D01*
X1515832Y168165D01*
X1515623Y167957D01*
X1515373Y167873D01*
X1514957D01*
X1514582Y167748D01*
X1514332Y167498D01*
X1514248Y167207D01*
X1514332Y166915D01*
X1514540Y166707D01*
X1514873Y166582D01*
X1515165Y166540D01*
G01X1517473D02*
Y169040D01*
X1519057D01*
G01X1518473Y167832D02*
X1517473D01*
G01X1521365Y166540D02*
Y169040D01*
X1520865Y168540D01*
G01Y166540D02*
X1521865D01*
G01X1518013Y278410D02*
Y280910D01*
X1519054D01*
X1519388Y280785D01*
X1519596Y280618D01*
X1519679Y280285D01*
X1519596Y279952D01*
X1519346Y279743D01*
X1519054Y279618D01*
X1518013D01*
G01X1519054D02*
X1519679Y278410D01*
G01X1521863D02*
X1521946Y278952D01*
X1522071Y279410D01*
X1522238Y279827D01*
X1522446Y280285D01*
X1522779Y280910D01*
X1521113D01*
G01X1525879Y278410D02*
X1524213D01*
Y280910D01*
X1525879D01*
G01X1525213Y279702D02*
X1524213D01*
G01X1528146Y278410D02*
Y280910D01*
X1527646Y280410D01*
G01Y278410D02*
X1528646D01*
G01X1530329Y278910D02*
X1530579Y278618D01*
X1530913Y278452D01*
X1531288Y278410D01*
X1531621Y278452D01*
X1531954Y278660D01*
X1532163Y278910D01*
X1532204Y279160D01*
X1532121Y279452D01*
X1531829Y279660D01*
X1531538Y279743D01*
X1531163D01*
G01X1531538D02*
X1531788Y279868D01*
X1531996Y280077D01*
X1532079Y280327D01*
X1531996Y280577D01*
X1531788Y280785D01*
X1531413Y280910D01*
X1531038Y280868D01*
X1530663Y280702D01*
G01X1510174Y232653D02*
X1507674D01*
Y233694D01*
X1507799Y234028D01*
X1507966Y234236D01*
X1508299Y234319D01*
X1508632Y234236D01*
X1508841Y233986D01*
X1508966Y233694D01*
Y232653D01*
G01Y233694D02*
X1510174Y234319D01*
G01Y236503D02*
X1509632Y236586D01*
X1509174Y236711D01*
X1508757Y236878D01*
X1508299Y237086D01*
X1507674Y237419D01*
Y235753D01*
G01X1510174Y240519D02*
Y238853D01*
X1507674D01*
Y240519D01*
G01X1508882Y239853D02*
Y238853D01*
G01X1510174Y242786D02*
X1507674D01*
X1508174Y242286D01*
G01X1510174D02*
Y243286D01*
G01X1509132Y245094D02*
X1508841Y245386D01*
X1508674Y245636D01*
X1508591Y245969D01*
X1508674Y246261D01*
X1508841Y246469D01*
X1509091Y246636D01*
X1509382Y246678D01*
X1509632Y246636D01*
X1509882Y246469D01*
X1510091Y246219D01*
X1510174Y245928D01*
X1510091Y245594D01*
X1509841Y245303D01*
X1509466Y245136D01*
X1509049Y245094D01*
X1508507Y245178D01*
X1508216Y245303D01*
X1507924Y245511D01*
X1507716Y245803D01*
X1507674Y246094D01*
X1507757Y246386D01*
X1507966Y246594D01*
G01X1506375Y232728D02*
X1503875D01*
Y233769D01*
X1504000Y234103D01*
X1504167Y234311D01*
X1504500Y234394D01*
X1504833Y234311D01*
X1505042Y234061D01*
X1505167Y233769D01*
Y232728D01*
G01Y233769D02*
X1506375Y234394D01*
G01Y236578D02*
X1505833Y236661D01*
X1505375Y236786D01*
X1504958Y236953D01*
X1504500Y237161D01*
X1503875Y237494D01*
Y235828D01*
G01X1506375Y238969D02*
X1503875D01*
Y240553D01*
G01X1505083Y239969D02*
Y238969D01*
G01X1506375Y242861D02*
X1503875D01*
X1504375Y242361D01*
G01X1506375D02*
Y243361D01*
G01X1518237Y235690D02*
Y238190D01*
X1519278D01*
X1519612Y238065D01*
X1519820Y237898D01*
X1519903Y237565D01*
X1519820Y237232D01*
X1519570Y237023D01*
X1519278Y236898D01*
X1518237D01*
G01X1519278D02*
X1519903Y235690D01*
G01X1522170D02*
X1522462Y235732D01*
X1522795Y235857D01*
X1523003Y236065D01*
X1523087Y236357D01*
X1523003Y236648D01*
X1522753Y236898D01*
X1522378Y237023D01*
X1521962D01*
X1521712Y237107D01*
X1521503Y237315D01*
X1521420Y237607D01*
X1521545Y237898D01*
X1521837Y238107D01*
X1522170Y238190D01*
X1522503Y238107D01*
X1522795Y237898D01*
X1522920Y237607D01*
X1522837Y237315D01*
X1522628Y237107D01*
X1522378Y237023D01*
X1521962D01*
X1521587Y236898D01*
X1521337Y236648D01*
X1521253Y236357D01*
X1521337Y236065D01*
X1521545Y235857D01*
X1521878Y235732D01*
X1522170Y235690D01*
G01X1526103D02*
X1524437D01*
Y238190D01*
X1526103D01*
G01X1525437Y236982D02*
X1524437D01*
G01X1527453Y236190D02*
X1527703Y235898D01*
X1528037Y235732D01*
X1528412Y235690D01*
X1528745Y235732D01*
X1529078Y235940D01*
X1529287Y236190D01*
X1529328Y236440D01*
X1529245Y236732D01*
X1528953Y236940D01*
X1528662Y237023D01*
X1528287D01*
G01X1528662D02*
X1528912Y237148D01*
X1529120Y237357D01*
X1529203Y237607D01*
X1529120Y237857D01*
X1528912Y238065D01*
X1528537Y238190D01*
X1528162Y238148D01*
X1527787Y237982D01*
G01X1530762Y235982D02*
X1531053Y235773D01*
X1531387Y235690D01*
X1531720Y235773D01*
X1532012Y236023D01*
X1532220Y236398D01*
X1532303Y236773D01*
Y237232D01*
X1532220Y237607D01*
X1532012Y237940D01*
X1531762Y238107D01*
X1531470Y238190D01*
X1531137Y238107D01*
X1530887Y237940D01*
X1530720Y237690D01*
X1530637Y237357D01*
X1530720Y237065D01*
X1530928Y236773D01*
X1531178Y236607D01*
X1531470Y236565D01*
X1531803Y236648D01*
X1532053Y236857D01*
X1532303Y237232D01*
G01X1503240Y271100D02*
X1500740D01*
Y272141D01*
X1500865Y272475D01*
X1501032Y272683D01*
X1501365Y272766D01*
X1501698Y272683D01*
X1501907Y272433D01*
X1502032Y272141D01*
Y271100D01*
G01Y272141D02*
X1503240Y272766D01*
G01X1501157Y274241D02*
X1500907Y274491D01*
X1500782Y274783D01*
X1500740Y275116D01*
X1500823Y275533D01*
X1501032Y275825D01*
X1501282Y275908D01*
X1501532Y275866D01*
X1501740Y275700D01*
X1502157Y274866D01*
X1502448Y274491D01*
X1502865Y274241D01*
X1503240Y274158D01*
Y275908D01*
G01X1500740Y278133D02*
X1503240D01*
G01X1500740Y277175D02*
Y279091D01*
G01X1502740Y280316D02*
X1503032Y280566D01*
X1503198Y280900D01*
X1503240Y281275D01*
X1503198Y281608D01*
X1502990Y281941D01*
X1502740Y282150D01*
X1502490Y282191D01*
X1502198Y282108D01*
X1501990Y281816D01*
X1501907Y281525D01*
Y281150D01*
G01Y281525D02*
X1501782Y281775D01*
X1501573Y281983D01*
X1501323Y282066D01*
X1501073Y281983D01*
X1500865Y281775D01*
X1500740Y281400D01*
X1500782Y281025D01*
X1500948Y280650D01*
G01X1503240Y284250D02*
X1502698Y284333D01*
X1502240Y284458D01*
X1501823Y284625D01*
X1501365Y284833D01*
X1500740Y285166D01*
Y283500D01*
G01X1507113Y270695D02*
X1504613D01*
Y271736D01*
X1504738Y272070D01*
X1504905Y272278D01*
X1505238Y272361D01*
X1505571Y272278D01*
X1505780Y272028D01*
X1505905Y271736D01*
Y270695D01*
G01Y271736D02*
X1507113Y272361D01*
G01X1505030Y273836D02*
X1504780Y274086D01*
X1504655Y274378D01*
X1504613Y274711D01*
X1504696Y275128D01*
X1504905Y275420D01*
X1505155Y275503D01*
X1505405Y275461D01*
X1505613Y275295D01*
X1506030Y274461D01*
X1506321Y274086D01*
X1506738Y273836D01*
X1507113Y273753D01*
Y275503D01*
G01X1504613Y277728D02*
X1507113D01*
G01X1504613Y276770D02*
Y278686D01*
G01X1507113Y281328D02*
X1504613D01*
X1506405Y279786D01*
Y281870D01*
G01X1506613Y283011D02*
X1506905Y283261D01*
X1507071Y283595D01*
X1507113Y283970D01*
X1507071Y284303D01*
X1506863Y284636D01*
X1506613Y284845D01*
X1506363Y284886D01*
X1506071Y284803D01*
X1505863Y284511D01*
X1505780Y284220D01*
Y283845D01*
G01Y284220D02*
X1505655Y284470D01*
X1505446Y284678D01*
X1505196Y284761D01*
X1504946Y284678D01*
X1504738Y284470D01*
X1504613Y284095D01*
X1504655Y283720D01*
X1504821Y283345D01*
G01X1496067Y226100D02*
Y228600D01*
X1497108D01*
X1497442Y228475D01*
X1497650Y228308D01*
X1497733Y227975D01*
X1497650Y227642D01*
X1497400Y227433D01*
X1497108Y227308D01*
X1496067D01*
G01X1497108D02*
X1497733Y226100D01*
G01X1499917D02*
X1500000Y226642D01*
X1500125Y227100D01*
X1500292Y227517D01*
X1500500Y227975D01*
X1500833Y228600D01*
X1499167D01*
G01X1502308Y226100D02*
Y228600D01*
X1503892D01*
G01X1503308Y227392D02*
X1502308D01*
G01X1505283Y226600D02*
X1505533Y226308D01*
X1505867Y226142D01*
X1506242Y226100D01*
X1506575Y226142D01*
X1506908Y226350D01*
X1507117Y226600D01*
X1507158Y226850D01*
X1507075Y227142D01*
X1506783Y227350D01*
X1506492Y227433D01*
X1506117D01*
G01X1506492D02*
X1506742Y227558D01*
X1506950Y227767D01*
X1507033Y228017D01*
X1506950Y228267D01*
X1506742Y228475D01*
X1506367Y228600D01*
X1505992Y228558D01*
X1505617Y228392D01*
G01X1509217Y226100D02*
X1509300Y226642D01*
X1509425Y227100D01*
X1509592Y227517D01*
X1509800Y227975D01*
X1510133Y228600D01*
X1508467D01*
G01X1499320Y239677D02*
X1496820D01*
Y240718D01*
X1496945Y241052D01*
X1497112Y241260D01*
X1497445Y241343D01*
X1497778Y241260D01*
X1497987Y241010D01*
X1498112Y240718D01*
Y239677D01*
G01Y240718D02*
X1499320Y241343D01*
G01Y243527D02*
X1498778Y243610D01*
X1498320Y243735D01*
X1497903Y243902D01*
X1497445Y244110D01*
X1496820Y244443D01*
Y242777D01*
G01X1499320Y247543D02*
Y245877D01*
X1496820D01*
Y247543D01*
G01X1498028Y246877D02*
Y245877D01*
G01X1499320Y249810D02*
X1496820D01*
X1497320Y249310D01*
G01X1499320D02*
Y250310D01*
G01Y252827D02*
X1498778Y252910D01*
X1498320Y253035D01*
X1497903Y253202D01*
X1497445Y253410D01*
X1496820Y253743D01*
Y252077D01*
G01X1522267Y247759D02*
X1522017Y247884D01*
X1521725Y247967D01*
X1521392D01*
X1521017Y247842D01*
X1520725Y247634D01*
X1520517Y247384D01*
X1520350Y246967D01*
X1520308Y246592D01*
X1520392Y246217D01*
X1520517Y245967D01*
X1520767Y245717D01*
X1521058Y245550D01*
X1521350Y245467D01*
X1521642D01*
X1521933Y245550D01*
X1522183Y245675D01*
X1522392Y245842D01*
G01X1524450Y245467D02*
X1524742Y245509D01*
X1525075Y245634D01*
X1525283Y245842D01*
X1525367Y246134D01*
X1525283Y246425D01*
X1525033Y246675D01*
X1524658Y246800D01*
X1524242D01*
X1523992Y246884D01*
X1523783Y247092D01*
X1523700Y247384D01*
X1523825Y247675D01*
X1524117Y247884D01*
X1524450Y247967D01*
X1524783Y247884D01*
X1525075Y247675D01*
X1525200Y247384D01*
X1525117Y247092D01*
X1524908Y246884D01*
X1524658Y246800D01*
X1524242D01*
X1523867Y246675D01*
X1523617Y246425D01*
X1523533Y246134D01*
X1523617Y245842D01*
X1523825Y245634D01*
X1524158Y245509D01*
X1524450Y245467D01*
G01X1528383D02*
X1526717D01*
Y247967D01*
X1528383D01*
G01X1527717Y246759D02*
X1526717D01*
G01X1529858Y246509D02*
X1530150Y246800D01*
X1530400Y246967D01*
X1530733Y247050D01*
X1531025Y246967D01*
X1531233Y246800D01*
X1531400Y246550D01*
X1531442Y246259D01*
X1531400Y246009D01*
X1531233Y245759D01*
X1530983Y245550D01*
X1530692Y245467D01*
X1530358Y245550D01*
X1530067Y245800D01*
X1529900Y246175D01*
X1529858Y246592D01*
X1529942Y247134D01*
X1530067Y247425D01*
X1530275Y247717D01*
X1530567Y247925D01*
X1530858Y247967D01*
X1531150Y247884D01*
X1531358Y247675D01*
G01X1500218Y234615D02*
X1500093Y234365D01*
X1500010Y234073D01*
Y233740D01*
X1500135Y233365D01*
X1500343Y233073D01*
X1500593Y232865D01*
X1501010Y232698D01*
X1501385Y232656D01*
X1501760Y232740D01*
X1502010Y232865D01*
X1502260Y233115D01*
X1502427Y233406D01*
X1502510Y233698D01*
Y233990D01*
X1502427Y234281D01*
X1502302Y234531D01*
X1502135Y234740D01*
G01X1502510Y236715D02*
X1501968Y236798D01*
X1501510Y236923D01*
X1501093Y237090D01*
X1500635Y237298D01*
X1500010Y237631D01*
Y235965D01*
G01X1502510Y240731D02*
Y239065D01*
X1500010D01*
Y240731D01*
G01X1501218Y240065D02*
Y239065D01*
G01X1502510Y242998D02*
X1500010D01*
X1500510Y242498D01*
G01X1502510D02*
Y243498D01*
G01Y246598D02*
X1500010D01*
X1501802Y245056D01*
Y247140D01*
G01X1511437Y235027D02*
X1511312Y234777D01*
X1511229Y234485D01*
Y234152D01*
X1511354Y233777D01*
X1511562Y233485D01*
X1511812Y233277D01*
X1512229Y233110D01*
X1512604Y233068D01*
X1512979Y233152D01*
X1513229Y233277D01*
X1513479Y233527D01*
X1513646Y233818D01*
X1513729Y234110D01*
Y234402D01*
X1513646Y234693D01*
X1513521Y234943D01*
X1513354Y235152D01*
G01X1513729Y237210D02*
X1513687Y237502D01*
X1513562Y237835D01*
X1513354Y238043D01*
X1513062Y238127D01*
X1512771Y238043D01*
X1512521Y237793D01*
X1512396Y237418D01*
Y237002D01*
X1512312Y236752D01*
X1512104Y236543D01*
X1511812Y236460D01*
X1511521Y236585D01*
X1511312Y236877D01*
X1511229Y237210D01*
X1511312Y237543D01*
X1511521Y237835D01*
X1511812Y237960D01*
X1512104Y237877D01*
X1512312Y237668D01*
X1512396Y237418D01*
Y237002D01*
X1512521Y236627D01*
X1512771Y236377D01*
X1513062Y236293D01*
X1513354Y236377D01*
X1513562Y236585D01*
X1513687Y236918D01*
X1513729Y237210D01*
G01Y241143D02*
Y239477D01*
X1511229D01*
Y241143D01*
G01X1512437Y240477D02*
Y239477D01*
G01X1513729Y243410D02*
X1511229D01*
X1511729Y242910D01*
G01X1513729D02*
Y243910D01*
G01X1512687Y245718D02*
X1512396Y246010D01*
X1512229Y246260D01*
X1512146Y246593D01*
X1512229Y246885D01*
X1512396Y247093D01*
X1512646Y247260D01*
X1512937Y247302D01*
X1513187Y247260D01*
X1513437Y247093D01*
X1513646Y246843D01*
X1513729Y246552D01*
X1513646Y246218D01*
X1513396Y245927D01*
X1513021Y245760D01*
X1512604Y245718D01*
X1512062Y245802D01*
X1511771Y245927D01*
X1511479Y246135D01*
X1511271Y246427D01*
X1511229Y246718D01*
X1511312Y247010D01*
X1511521Y247218D01*
G01X1520580Y232888D02*
X1520330Y233013D01*
X1520038Y233096D01*
X1519705D01*
X1519330Y232971D01*
X1519038Y232763D01*
X1518830Y232513D01*
X1518663Y232096D01*
X1518621Y231721D01*
X1518705Y231346D01*
X1518830Y231096D01*
X1519080Y230846D01*
X1519371Y230679D01*
X1519663Y230596D01*
X1519955D01*
X1520246Y230679D01*
X1520496Y230804D01*
X1520705Y230971D01*
G01X1522763Y230596D02*
X1523055Y230638D01*
X1523388Y230763D01*
X1523596Y230971D01*
X1523680Y231263D01*
X1523596Y231554D01*
X1523346Y231804D01*
X1522971Y231929D01*
X1522555D01*
X1522305Y232013D01*
X1522096Y232221D01*
X1522013Y232513D01*
X1522138Y232804D01*
X1522430Y233013D01*
X1522763Y233096D01*
X1523096Y233013D01*
X1523388Y232804D01*
X1523513Y232513D01*
X1523430Y232221D01*
X1523221Y232013D01*
X1522971Y231929D01*
X1522555D01*
X1522180Y231804D01*
X1521930Y231554D01*
X1521846Y231263D01*
X1521930Y230971D01*
X1522138Y230763D01*
X1522471Y230638D01*
X1522763Y230596D01*
G01X1525071D02*
Y233096D01*
X1526655D01*
G01X1526071Y231888D02*
X1525071D01*
G01X1528963Y230596D02*
Y233096D01*
X1528463Y232596D01*
G01Y230596D02*
X1529463D01*
G01X1486734Y233708D02*
X1484234D01*
Y235292D01*
G01X1485442Y234708D02*
Y233708D01*
G01X1485401Y237933D02*
X1485276Y238100D01*
X1485067Y238225D01*
X1484776Y238308D01*
X1484526Y238225D01*
X1484359Y238058D01*
X1484234Y237767D01*
Y236642D01*
X1486734D01*
Y238017D01*
X1486567Y238308D01*
X1486317Y238475D01*
X1486026Y238558D01*
X1485734Y238475D01*
X1485484Y238225D01*
X1485401Y237933D01*
Y236642D01*
G01X1486734Y240617D02*
X1486192Y240700D01*
X1485734Y240825D01*
X1485317Y240992D01*
X1484859Y241200D01*
X1484234Y241533D01*
Y239867D01*
G01X1486734Y244633D02*
Y242967D01*
X1484234D01*
Y244633D01*
G01X1485442Y243967D02*
Y242967D01*
G01X1486734Y246900D02*
X1484234D01*
X1484734Y246400D01*
G01X1486734D02*
Y247400D01*
G01X1515629Y227552D02*
X1515370Y227283D01*
X1515267Y226977D01*
X1515370Y226670D01*
X1515680Y226402D01*
X1516145Y226210D01*
X1516610Y226133D01*
X1517179D01*
X1517644Y226210D01*
X1518057Y226402D01*
X1518264Y226632D01*
X1518367Y226900D01*
X1518264Y227207D01*
X1518057Y227437D01*
X1517747Y227590D01*
X1517334Y227667D01*
X1516972Y227590D01*
X1516610Y227398D01*
X1516404Y227168D01*
X1516352Y226900D01*
X1516455Y226593D01*
X1516714Y226363D01*
X1517179Y226133D01*
G01X1483791Y251682D02*
X1483666Y251432D01*
X1483583Y251140D01*
Y250807D01*
X1483708Y250432D01*
X1483916Y250140D01*
X1484166Y249932D01*
X1484583Y249765D01*
X1484958Y249723D01*
X1485333Y249807D01*
X1485583Y249932D01*
X1485833Y250182D01*
X1486000Y250473D01*
X1486083Y250765D01*
Y251057D01*
X1486000Y251348D01*
X1485875Y251598D01*
X1485708Y251807D01*
G01X1486083Y253782D02*
X1485541Y253865D01*
X1485083Y253990D01*
X1484666Y254157D01*
X1484208Y254365D01*
X1483583Y254698D01*
Y253032D01*
G01X1486083Y257798D02*
Y256132D01*
X1483583D01*
Y257798D01*
G01X1484791Y257132D02*
Y256132D01*
G01X1486083Y260065D02*
X1483583D01*
X1484083Y259565D01*
G01X1486083D02*
Y260565D01*
G01Y263165D02*
X1483583D01*
X1484083Y262665D01*
G01X1486083D02*
Y263665D01*
G01X1516509Y274089D02*
Y269644D01*
G01X1509409Y274092D02*
Y269646D01*
G01X1488542Y236117D02*
X1488417Y235867D01*
X1488334Y235575D01*
Y235242D01*
X1488459Y234867D01*
X1488667Y234575D01*
X1488917Y234367D01*
X1489334Y234200D01*
X1489709Y234158D01*
X1490084Y234242D01*
X1490334Y234367D01*
X1490584Y234617D01*
X1490751Y234908D01*
X1490834Y235200D01*
Y235492D01*
X1490751Y235783D01*
X1490626Y236033D01*
X1490459Y236242D01*
G01X1490834Y238217D02*
X1490292Y238300D01*
X1489834Y238425D01*
X1489417Y238592D01*
X1488959Y238800D01*
X1488334Y239133D01*
Y237467D01*
G01X1490834Y242233D02*
Y240567D01*
X1488334D01*
Y242233D01*
G01X1489542Y241567D02*
Y240567D01*
G01X1490834Y244500D02*
X1488334D01*
X1488834Y244000D01*
G01X1490834D02*
Y245000D01*
G01X1488751Y246808D02*
X1488501Y247058D01*
X1488376Y247350D01*
X1488334Y247683D01*
X1488417Y248100D01*
X1488626Y248392D01*
X1488876Y248475D01*
X1489126Y248433D01*
X1489334Y248267D01*
X1489751Y247433D01*
X1490042Y247058D01*
X1490459Y246808D01*
X1490834Y246725D01*
Y248475D01*
G01X1493620Y236717D02*
X1493495Y236467D01*
X1493412Y236175D01*
Y235842D01*
X1493537Y235467D01*
X1493745Y235175D01*
X1493995Y234967D01*
X1494412Y234800D01*
X1494787Y234758D01*
X1495162Y234842D01*
X1495412Y234967D01*
X1495662Y235217D01*
X1495829Y235508D01*
X1495912Y235800D01*
Y236092D01*
X1495829Y236383D01*
X1495704Y236633D01*
X1495537Y236842D01*
G01X1493829Y238108D02*
X1493579Y238358D01*
X1493454Y238650D01*
X1493412Y238983D01*
X1493495Y239400D01*
X1493704Y239692D01*
X1493954Y239775D01*
X1494204Y239733D01*
X1494412Y239567D01*
X1494829Y238733D01*
X1495120Y238358D01*
X1495537Y238108D01*
X1495912Y238025D01*
Y239775D01*
G01X1493829Y241208D02*
X1493579Y241458D01*
X1493454Y241750D01*
X1493412Y242083D01*
X1493495Y242500D01*
X1493704Y242792D01*
X1493954Y242875D01*
X1494204Y242833D01*
X1494412Y242667D01*
X1494829Y241833D01*
X1495120Y241458D01*
X1495537Y241208D01*
X1495912Y241125D01*
Y242875D01*
G01X1493412Y243850D02*
X1495912Y244433D01*
X1493412Y245100D01*
X1495912Y245767D01*
X1493412Y246350D01*
G01X1495912Y248200D02*
X1495870Y248492D01*
X1495745Y248825D01*
X1495537Y249033D01*
X1495245Y249117D01*
X1494954Y249033D01*
X1494704Y248783D01*
X1494579Y248408D01*
Y247992D01*
X1494495Y247742D01*
X1494287Y247533D01*
X1493995Y247450D01*
X1493704Y247575D01*
X1493495Y247867D01*
X1493412Y248200D01*
X1493495Y248533D01*
X1493704Y248825D01*
X1493995Y248950D01*
X1494287Y248867D01*
X1494495Y248658D01*
X1494579Y248408D01*
Y247992D01*
X1494704Y247617D01*
X1494954Y247367D01*
X1495245Y247283D01*
X1495537Y247367D01*
X1495745Y247575D01*
X1495870Y247908D01*
X1495912Y248200D01*
G01X1487389Y251615D02*
X1487264Y251365D01*
X1487181Y251073D01*
Y250740D01*
X1487306Y250365D01*
X1487514Y250073D01*
X1487764Y249865D01*
X1488181Y249698D01*
X1488556Y249656D01*
X1488931Y249740D01*
X1489181Y249865D01*
X1489431Y250115D01*
X1489598Y250406D01*
X1489681Y250698D01*
Y250990D01*
X1489598Y251281D01*
X1489473Y251531D01*
X1489306Y251740D01*
G01X1489681Y253715D02*
X1489139Y253798D01*
X1488681Y253923D01*
X1488264Y254090D01*
X1487806Y254298D01*
X1487181Y254631D01*
Y252965D01*
G01X1489681Y257731D02*
Y256065D01*
X1487181D01*
Y257731D01*
G01X1488389Y257065D02*
Y256065D01*
G01X1489681Y259998D02*
X1487181D01*
X1487681Y259498D01*
G01X1489681D02*
Y260498D01*
G01X1489181Y262181D02*
X1489473Y262431D01*
X1489639Y262765D01*
X1489681Y263140D01*
X1489639Y263473D01*
X1489431Y263806D01*
X1489181Y264015D01*
X1488931Y264056D01*
X1488639Y263973D01*
X1488431Y263681D01*
X1488348Y263390D01*
Y263015D01*
G01Y263390D02*
X1488223Y263640D01*
X1488014Y263848D01*
X1487764Y263931D01*
X1487514Y263848D01*
X1487306Y263640D01*
X1487181Y263265D01*
X1487223Y262890D01*
X1487389Y262515D01*
G01X1491058Y251617D02*
X1490933Y251367D01*
X1490850Y251075D01*
Y250742D01*
X1490975Y250367D01*
X1491183Y250075D01*
X1491433Y249867D01*
X1491850Y249700D01*
X1492225Y249658D01*
X1492600Y249742D01*
X1492850Y249867D01*
X1493100Y250117D01*
X1493267Y250408D01*
X1493350Y250700D01*
Y250992D01*
X1493267Y251283D01*
X1493142Y251533D01*
X1492975Y251742D01*
G01X1491267Y253008D02*
X1491017Y253258D01*
X1490892Y253550D01*
X1490850Y253883D01*
X1490933Y254300D01*
X1491142Y254592D01*
X1491392Y254675D01*
X1491642Y254633D01*
X1491850Y254467D01*
X1492267Y253633D01*
X1492558Y253258D01*
X1492975Y253008D01*
X1493350Y252925D01*
Y254675D01*
G01X1491267Y256108D02*
X1491017Y256358D01*
X1490892Y256650D01*
X1490850Y256983D01*
X1490933Y257400D01*
X1491142Y257692D01*
X1491392Y257775D01*
X1491642Y257733D01*
X1491850Y257567D01*
X1492267Y256733D01*
X1492558Y256358D01*
X1492975Y256108D01*
X1493350Y256025D01*
Y257775D01*
G01X1490850Y258750D02*
X1493350Y259333D01*
X1490850Y260000D01*
X1493350Y260667D01*
X1490850Y261250D01*
G01X1493058Y262392D02*
X1493267Y262683D01*
X1493350Y263017D01*
X1493267Y263350D01*
X1493017Y263642D01*
X1492642Y263850D01*
X1492267Y263933D01*
X1491808D01*
X1491433Y263850D01*
X1491100Y263642D01*
X1490933Y263392D01*
X1490850Y263100D01*
X1490933Y262767D01*
X1491100Y262517D01*
X1491350Y262350D01*
X1491683Y262267D01*
X1491975Y262350D01*
X1492267Y262558D01*
X1492433Y262808D01*
X1492475Y263100D01*
X1492392Y263433D01*
X1492183Y263683D01*
X1491808Y263933D01*
G01X1519233Y240667D02*
X1517567D01*
Y243167D01*
X1519233D01*
G01X1518567Y241959D02*
X1517567D01*
G01X1520583Y243167D02*
Y241375D01*
X1520750Y241000D01*
X1521083Y240750D01*
X1521500Y240667D01*
X1521917Y240750D01*
X1522250Y241000D01*
X1522417Y241375D01*
Y243167D01*
G01X1524517Y240667D02*
X1524600Y241209D01*
X1524725Y241667D01*
X1524892Y242084D01*
X1525100Y242542D01*
X1525433Y243167D01*
X1523767D01*
G01X1528533Y240667D02*
X1526867D01*
Y243167D01*
X1528533D01*
G01X1527867Y241959D02*
X1526867D01*
G01X1530008Y242750D02*
X1530258Y243000D01*
X1530550Y243125D01*
X1530883Y243167D01*
X1531300Y243084D01*
X1531592Y242875D01*
X1531675Y242625D01*
X1531633Y242375D01*
X1531467Y242167D01*
X1530633Y241750D01*
X1530258Y241459D01*
X1530008Y241042D01*
X1529925Y240667D01*
X1531675D01*
G01X1513467Y332800D02*
Y335300D01*
X1514508D01*
X1514842Y335175D01*
X1515050Y335008D01*
X1515133Y334675D01*
X1515050Y334342D01*
X1514800Y334133D01*
X1514508Y334008D01*
X1513467D01*
G01X1514508D02*
X1515133Y332800D01*
G01X1517317D02*
X1517400Y333342D01*
X1517525Y333800D01*
X1517692Y334217D01*
X1517900Y334675D01*
X1518233Y335300D01*
X1516567D01*
G01X1519583Y332800D02*
Y335300D01*
X1520417D01*
X1520750Y335175D01*
X1521000Y335008D01*
X1521208Y334758D01*
X1521375Y334467D01*
X1521417Y334050D01*
X1521375Y333633D01*
X1521208Y333342D01*
X1521000Y333092D01*
X1520750Y332925D01*
X1520417Y332800D01*
X1519583D01*
G01X1522808Y334883D02*
X1523058Y335133D01*
X1523350Y335258D01*
X1523683Y335300D01*
X1524100Y335217D01*
X1524392Y335008D01*
X1524475Y334758D01*
X1524433Y334508D01*
X1524267Y334300D01*
X1523433Y333883D01*
X1523058Y333592D01*
X1522808Y333175D01*
X1522725Y332800D01*
X1524475D01*
G01X1525908Y333842D02*
X1526200Y334133D01*
X1526450Y334300D01*
X1526783Y334383D01*
X1527075Y334300D01*
X1527283Y334133D01*
X1527450Y333883D01*
X1527492Y333592D01*
X1527450Y333342D01*
X1527283Y333092D01*
X1527033Y332883D01*
X1526742Y332800D01*
X1526408Y332883D01*
X1526117Y333133D01*
X1525950Y333508D01*
X1525908Y333925D01*
X1525992Y334467D01*
X1526117Y334758D01*
X1526325Y335050D01*
X1526617Y335258D01*
X1526908Y335300D01*
X1527200Y335217D01*
X1527408Y335008D01*
G01X1502822Y336444D02*
Y338944D01*
X1503863D01*
X1504197Y338819D01*
X1504405Y338652D01*
X1504488Y338319D01*
X1504405Y337986D01*
X1504155Y337777D01*
X1503863Y337652D01*
X1502822D01*
G01X1503863D02*
X1504488Y336444D01*
G01X1506672D02*
X1506755Y336986D01*
X1506880Y337444D01*
X1507047Y337861D01*
X1507255Y338319D01*
X1507588Y338944D01*
X1505922D01*
G01X1508938Y336444D02*
Y338944D01*
X1509772D01*
X1510105Y338819D01*
X1510355Y338652D01*
X1510563Y338402D01*
X1510730Y338111D01*
X1510772Y337694D01*
X1510730Y337277D01*
X1510563Y336986D01*
X1510355Y336736D01*
X1510105Y336569D01*
X1509772Y336444D01*
X1508938D01*
G01X1512955D02*
Y338944D01*
X1512455Y338444D01*
G01Y336444D02*
X1513455D01*
G01X1515138Y336944D02*
X1515388Y336652D01*
X1515722Y336486D01*
X1516097Y336444D01*
X1516430Y336486D01*
X1516763Y336694D01*
X1516972Y336944D01*
X1517013Y337194D01*
X1516930Y337486D01*
X1516638Y337694D01*
X1516347Y337777D01*
X1515972D01*
G01X1516347D02*
X1516597Y337902D01*
X1516805Y338111D01*
X1516888Y338361D01*
X1516805Y338611D01*
X1516597Y338819D01*
X1516222Y338944D01*
X1515847Y338902D01*
X1515472Y338736D01*
G01X1476792Y325658D02*
X1474292D01*
Y326699D01*
X1474417Y327033D01*
X1474584Y327241D01*
X1474917Y327324D01*
X1475250Y327241D01*
X1475459Y326991D01*
X1475584Y326699D01*
Y325658D01*
G01Y326699D02*
X1476792Y327324D01*
G01X1474709Y328799D02*
X1474459Y329049D01*
X1474334Y329341D01*
X1474292Y329674D01*
X1474375Y330091D01*
X1474584Y330383D01*
X1474834Y330466D01*
X1475084Y330424D01*
X1475292Y330258D01*
X1475709Y329424D01*
X1476000Y329049D01*
X1476417Y328799D01*
X1476792Y328716D01*
Y330466D01*
G01Y331858D02*
X1474292D01*
Y332899D01*
X1474417Y333233D01*
X1474584Y333441D01*
X1474917Y333524D01*
X1475250Y333441D01*
X1475459Y333191D01*
X1475584Y332899D01*
Y331858D01*
G01Y332899D02*
X1476792Y333524D01*
G01Y335791D02*
X1474292D01*
X1474792Y335291D01*
G01X1476792D02*
Y336291D01*
G01Y338891D02*
X1474292D01*
X1474792Y338391D01*
G01X1476792D02*
Y339391D01*
G01X1478231Y324510D02*
Y327010D01*
X1479272D01*
X1479606Y326885D01*
X1479814Y326718D01*
X1479897Y326385D01*
X1479814Y326052D01*
X1479564Y325843D01*
X1479272Y325718D01*
X1478231D01*
G01X1479272D02*
X1479897Y324510D01*
G01X1482081D02*
X1482164Y325052D01*
X1482289Y325510D01*
X1482456Y325927D01*
X1482664Y326385D01*
X1482997Y327010D01*
X1481331D01*
G01X1484347Y324510D02*
Y327010D01*
X1485181D01*
X1485514Y326885D01*
X1485764Y326718D01*
X1485972Y326468D01*
X1486139Y326177D01*
X1486181Y325760D01*
X1486139Y325343D01*
X1485972Y325052D01*
X1485764Y324802D01*
X1485514Y324635D01*
X1485181Y324510D01*
X1484347D01*
G01X1487572Y326593D02*
X1487822Y326843D01*
X1488114Y326968D01*
X1488447Y327010D01*
X1488864Y326927D01*
X1489156Y326718D01*
X1489239Y326468D01*
X1489197Y326218D01*
X1489031Y326010D01*
X1488197Y325593D01*
X1487822Y325302D01*
X1487572Y324885D01*
X1487489Y324510D01*
X1489239D01*
G01X1491464D02*
X1491756Y324552D01*
X1492089Y324677D01*
X1492297Y324885D01*
X1492381Y325177D01*
X1492297Y325468D01*
X1492047Y325718D01*
X1491672Y325843D01*
X1491256D01*
X1491006Y325927D01*
X1490797Y326135D01*
X1490714Y326427D01*
X1490839Y326718D01*
X1491131Y326927D01*
X1491464Y327010D01*
X1491797Y326927D01*
X1492089Y326718D01*
X1492214Y326427D01*
X1492131Y326135D01*
X1491922Y325927D01*
X1491672Y325843D01*
X1491256D01*
X1490881Y325718D01*
X1490631Y325468D01*
X1490547Y325177D01*
X1490631Y324885D01*
X1490839Y324677D01*
X1491172Y324552D01*
X1491464Y324510D01*
G01X1478303Y320953D02*
Y323453D01*
X1479344D01*
X1479678Y323328D01*
X1479886Y323161D01*
X1479969Y322828D01*
X1479886Y322495D01*
X1479636Y322286D01*
X1479344Y322161D01*
X1478303D01*
G01X1479344D02*
X1479969Y320953D01*
G01X1482153D02*
X1482236Y321495D01*
X1482361Y321953D01*
X1482528Y322370D01*
X1482736Y322828D01*
X1483069Y323453D01*
X1481403D01*
G01X1484419Y320953D02*
Y323453D01*
X1485253D01*
X1485586Y323328D01*
X1485836Y323161D01*
X1486044Y322911D01*
X1486211Y322620D01*
X1486253Y322203D01*
X1486211Y321786D01*
X1486044Y321495D01*
X1485836Y321245D01*
X1485586Y321078D01*
X1485253Y320953D01*
X1484419D01*
G01X1487644Y323036D02*
X1487894Y323286D01*
X1488186Y323411D01*
X1488519Y323453D01*
X1488936Y323370D01*
X1489228Y323161D01*
X1489311Y322911D01*
X1489269Y322661D01*
X1489103Y322453D01*
X1488269Y322036D01*
X1487894Y321745D01*
X1487644Y321328D01*
X1487561Y320953D01*
X1489311D01*
G01X1491453D02*
X1491536Y321495D01*
X1491661Y321953D01*
X1491828Y322370D01*
X1492036Y322828D01*
X1492369Y323453D01*
X1490703D01*
G01X1509117Y289100D02*
Y291600D01*
X1510158D01*
X1510492Y291475D01*
X1510700Y291308D01*
X1510783Y290975D01*
X1510700Y290642D01*
X1510450Y290433D01*
X1510158Y290308D01*
X1509117D01*
G01X1510158D02*
X1510783Y289100D01*
G01X1512967D02*
X1513050Y289642D01*
X1513175Y290100D01*
X1513342Y290517D01*
X1513550Y290975D01*
X1513883Y291600D01*
X1512217D01*
G01X1516983Y289100D02*
X1515317D01*
Y291600D01*
X1516983D01*
G01X1516317Y290392D02*
X1515317D01*
G01X1518458Y291183D02*
X1518708Y291433D01*
X1519000Y291558D01*
X1519333Y291600D01*
X1519750Y291517D01*
X1520042Y291308D01*
X1520125Y291058D01*
X1520083Y290808D01*
X1519917Y290600D01*
X1519083Y290183D01*
X1518708Y289892D01*
X1518458Y289475D01*
X1518375Y289100D01*
X1520125D01*
G01X1498653Y297664D02*
X1496153D01*
Y298705D01*
X1496278Y299039D01*
X1496445Y299247D01*
X1496778Y299330D01*
X1497111Y299247D01*
X1497320Y298997D01*
X1497445Y298705D01*
Y297664D01*
G01Y298705D02*
X1498653Y299330D01*
G01X1496570Y300805D02*
X1496320Y301055D01*
X1496195Y301347D01*
X1496153Y301680D01*
X1496236Y302097D01*
X1496445Y302389D01*
X1496695Y302472D01*
X1496945Y302430D01*
X1497153Y302264D01*
X1497570Y301430D01*
X1497861Y301055D01*
X1498278Y300805D01*
X1498653Y300722D01*
Y302472D01*
G01X1496153Y304697D02*
X1498653D01*
G01X1496153Y303739D02*
Y305655D01*
G01X1498653Y308297D02*
X1496153D01*
X1497945Y306755D01*
Y308839D01*
G01X1498653Y311397D02*
X1496153D01*
X1497945Y309855D01*
Y311939D01*
G01X1502509Y297789D02*
X1500009D01*
Y298830D01*
X1500134Y299164D01*
X1500301Y299372D01*
X1500634Y299455D01*
X1500967Y299372D01*
X1501176Y299122D01*
X1501301Y298830D01*
Y297789D01*
G01Y298830D02*
X1502509Y299455D01*
G01X1500426Y300930D02*
X1500176Y301180D01*
X1500051Y301472D01*
X1500009Y301805D01*
X1500092Y302222D01*
X1500301Y302514D01*
X1500551Y302597D01*
X1500801Y302555D01*
X1501009Y302389D01*
X1501426Y301555D01*
X1501717Y301180D01*
X1502134Y300930D01*
X1502509Y300847D01*
Y302597D01*
G01X1500009Y304822D02*
X1502509D01*
G01X1500009Y303864D02*
Y305780D01*
G01X1502509Y308422D02*
X1500009D01*
X1501801Y306880D01*
Y308964D01*
G01X1500009Y311022D02*
X1500092Y310689D01*
X1500301Y310439D01*
X1500551Y310272D01*
X1500884Y310147D01*
X1501259Y310105D01*
X1501634Y310147D01*
X1501967Y310272D01*
X1502217Y310439D01*
X1502426Y310689D01*
X1502509Y311022D01*
X1502426Y311355D01*
X1502217Y311605D01*
X1501967Y311772D01*
X1501634Y311897D01*
X1501259Y311939D01*
X1500884Y311897D01*
X1500551Y311772D01*
X1500301Y311605D01*
X1500092Y311355D01*
X1500009Y311022D01*
G01X1499500Y313517D02*
X1497000D01*
Y314558D01*
X1497125Y314892D01*
X1497292Y315100D01*
X1497625Y315183D01*
X1497958Y315100D01*
X1498167Y314850D01*
X1498292Y314558D01*
Y313517D01*
G01Y314558D02*
X1499500Y315183D01*
G01Y317367D02*
X1498958Y317450D01*
X1498500Y317575D01*
X1498083Y317742D01*
X1497625Y317950D01*
X1497000Y318283D01*
Y316617D01*
G01Y319300D02*
X1499500Y319883D01*
X1497000Y320550D01*
X1499500Y321217D01*
X1497000Y321800D01*
G01X1499500Y323650D02*
X1497000D01*
X1497500Y323150D01*
G01X1499500D02*
Y324150D01*
G01Y327250D02*
X1497000D01*
X1498792Y325708D01*
Y327792D01*
G01X1493183Y335100D02*
Y333308D01*
X1493350Y332933D01*
X1493683Y332683D01*
X1494100Y332600D01*
X1494517Y332683D01*
X1494850Y332933D01*
X1495017Y333308D01*
Y335100D01*
G01X1497200Y332600D02*
Y335100D01*
X1496700Y334600D01*
G01Y332600D02*
X1497700D01*
G01X1500800D02*
Y335100D01*
X1499258Y333308D01*
X1501342D01*
G01X1504233Y332600D02*
X1502567D01*
Y335100D01*
X1504233D01*
G01X1503567Y333892D02*
X1502567D01*
G01X1505583Y333100D02*
X1505833Y332808D01*
X1506167Y332642D01*
X1506542Y332600D01*
X1506875Y332642D01*
X1507208Y332850D01*
X1507417Y333100D01*
X1507458Y333350D01*
X1507375Y333642D01*
X1507083Y333850D01*
X1506792Y333933D01*
X1506417D01*
G01X1506792D02*
X1507042Y334058D01*
X1507250Y334267D01*
X1507333Y334517D01*
X1507250Y334767D01*
X1507042Y334975D01*
X1506667Y335100D01*
X1506292Y335058D01*
X1505917Y334892D01*
G01X1491713Y331290D02*
Y329498D01*
X1491880Y329123D01*
X1492213Y328873D01*
X1492630Y328790D01*
X1493047Y328873D01*
X1493380Y329123D01*
X1493547Y329498D01*
Y331290D01*
G01X1495730Y328790D02*
Y331290D01*
X1495230Y330790D01*
G01Y328790D02*
X1496230D01*
G01X1499330D02*
Y331290D01*
X1497788Y329498D01*
X1499872D01*
G01X1502763Y328790D02*
X1501097D01*
Y331290D01*
X1502763D01*
G01X1502097Y330082D02*
X1501097D01*
G01X1504238Y330873D02*
X1504488Y331123D01*
X1504780Y331248D01*
X1505113Y331290D01*
X1505530Y331207D01*
X1505822Y330998D01*
X1505905Y330748D01*
X1505863Y330498D01*
X1505697Y330290D01*
X1504863Y329873D01*
X1504488Y329582D01*
X1504238Y329165D01*
X1504155Y328790D01*
X1505905D01*
G01X1516933Y287800D02*
Y286008D01*
X1517100Y285633D01*
X1517433Y285383D01*
X1517850Y285300D01*
X1518267Y285383D01*
X1518600Y285633D01*
X1518767Y286008D01*
Y287800D01*
G01X1520867Y285300D02*
X1520950Y285842D01*
X1521075Y286300D01*
X1521242Y286717D01*
X1521450Y287175D01*
X1521783Y287800D01*
X1520117D01*
G01X1523133Y285300D02*
Y287800D01*
X1523967D01*
X1524300Y287675D01*
X1524550Y287508D01*
X1524758Y287258D01*
X1524925Y286967D01*
X1524967Y286550D01*
X1524925Y286133D01*
X1524758Y285842D01*
X1524550Y285592D01*
X1524300Y285425D01*
X1523967Y285300D01*
X1523133D01*
G01X1526358Y287383D02*
X1526608Y287633D01*
X1526900Y287758D01*
X1527233Y287800D01*
X1527650Y287717D01*
X1527942Y287508D01*
X1528025Y287258D01*
X1527983Y287008D01*
X1527817Y286800D01*
X1526983Y286383D01*
X1526608Y286092D01*
X1526358Y285675D01*
X1526275Y285300D01*
X1528025D01*
G01X1527022Y311137D02*
X1538422D01*
Y290797D01*
X1527022D01*
Y311137D01*
G01X1467150Y329800D02*
Y326700D01*
G01X1466268Y329800D02*
X1468032D01*
G01X1470250Y326700D02*
Y329800D01*
X1469790Y329180D01*
G01Y326700D02*
X1470710D01*
G01X1479400Y349300D02*
X1474801D01*
X1474800Y349299D01*
Y341501D01*
X1474801Y341500D01*
X1477600D01*
G01X1481500D02*
X1494500D01*
G01X1501400D02*
X1518300D01*
G01X1524300Y349300D02*
X1519000D01*
G01X1488200D02*
X1482600D01*
G01X1494700D02*
X1491400D01*
G01X1515400D02*
X1497600D01*
G01X1470093Y348554D02*
X1467593D01*
Y349595D01*
X1467718Y349929D01*
X1467885Y350137D01*
X1468218Y350220D01*
X1468551Y350137D01*
X1468760Y349887D01*
X1468885Y349595D01*
Y348554D01*
G01Y349595D02*
X1470093Y350220D01*
G01X1468010Y351695D02*
X1467760Y351945D01*
X1467635Y352237D01*
X1467593Y352570D01*
X1467676Y352987D01*
X1467885Y353279D01*
X1468135Y353362D01*
X1468385Y353320D01*
X1468593Y353154D01*
X1469010Y352320D01*
X1469301Y351945D01*
X1469718Y351695D01*
X1470093Y351612D01*
Y353362D01*
G01Y354754D02*
X1467593D01*
Y355754D01*
X1467718Y356087D01*
X1468010Y356337D01*
X1468343Y356420D01*
X1468676Y356337D01*
X1468926Y356129D01*
X1469051Y355754D01*
Y354754D01*
G01X1468010Y357895D02*
X1467760Y358145D01*
X1467635Y358437D01*
X1467593Y358770D01*
X1467676Y359187D01*
X1467885Y359479D01*
X1468135Y359562D01*
X1468385Y359520D01*
X1468593Y359354D01*
X1469010Y358520D01*
X1469301Y358145D01*
X1469718Y357895D01*
X1470093Y357812D01*
Y359562D01*
G01X1475537Y353100D02*
Y355600D01*
X1476578D01*
X1476912Y355475D01*
X1477120Y355308D01*
X1477203Y354975D01*
X1477120Y354642D01*
X1476870Y354433D01*
X1476578Y354308D01*
X1475537D01*
G01X1476578D02*
X1477203Y353100D01*
G01X1478678Y355183D02*
X1478928Y355433D01*
X1479220Y355558D01*
X1479553Y355600D01*
X1479970Y355517D01*
X1480262Y355308D01*
X1480345Y355058D01*
X1480303Y354808D01*
X1480137Y354600D01*
X1479303Y354183D01*
X1478928Y353892D01*
X1478678Y353475D01*
X1478595Y353100D01*
X1480345D01*
G01X1481653Y353475D02*
X1481903Y353267D01*
X1482195Y353142D01*
X1482570Y353100D01*
X1482945Y353183D01*
X1483237Y353350D01*
X1483445Y353642D01*
X1483487Y353975D01*
X1483403Y354308D01*
X1483195Y354517D01*
X1482903Y354683D01*
X1482612Y354725D01*
X1482320Y354683D01*
X1481945Y354517D01*
X1482070Y355600D01*
X1483195D01*
G01X1484420D02*
X1485003Y353100D01*
X1485670Y355600D01*
X1486337Y353100D01*
X1486920Y355600D01*
G01X1488687Y353100D02*
X1488770Y353642D01*
X1488895Y354100D01*
X1489062Y354517D01*
X1489270Y354975D01*
X1489603Y355600D01*
X1487937D01*
G01X1491078Y355183D02*
X1491328Y355433D01*
X1491620Y355558D01*
X1491953Y355600D01*
X1492370Y355517D01*
X1492662Y355308D01*
X1492745Y355058D01*
X1492703Y354808D01*
X1492537Y354600D01*
X1491703Y354183D01*
X1491328Y353892D01*
X1491078Y353475D01*
X1490995Y353100D01*
X1492745D01*
G01X1520437Y352610D02*
Y355110D01*
X1521478D01*
X1521812Y354985D01*
X1522020Y354818D01*
X1522103Y354485D01*
X1522020Y354152D01*
X1521770Y353943D01*
X1521478Y353818D01*
X1520437D01*
G01X1521478D02*
X1522103Y352610D01*
G01X1524287D02*
X1524370Y353152D01*
X1524495Y353610D01*
X1524662Y354027D01*
X1524870Y354485D01*
X1525203Y355110D01*
X1523537D01*
G01X1526220D02*
X1526803Y352610D01*
X1527470Y355110D01*
X1528137Y352610D01*
X1528720Y355110D01*
G01X1530570Y352610D02*
Y355110D01*
X1530070Y354610D01*
G01Y352610D02*
X1531070D01*
G01X1532753Y352985D02*
X1533003Y352777D01*
X1533295Y352652D01*
X1533670Y352610D01*
X1534045Y352693D01*
X1534337Y352860D01*
X1534545Y353152D01*
X1534587Y353485D01*
X1534503Y353818D01*
X1534295Y354027D01*
X1534003Y354193D01*
X1533712Y354235D01*
X1533420Y354193D01*
X1533045Y354027D01*
X1533170Y355110D01*
X1534295D01*
G01X1471317Y391773D02*
X1468217D01*
X1468837Y391313D01*
G01X1471317D02*
Y392233D01*
G01X1470852Y394030D02*
X1471110Y394260D01*
X1471265Y394528D01*
X1471317Y394873D01*
X1471214Y395218D01*
X1471007Y395486D01*
X1470645Y395678D01*
X1470232Y395716D01*
X1469819Y395640D01*
X1469560Y395448D01*
X1469354Y395180D01*
X1469302Y394911D01*
X1469354Y394643D01*
X1469560Y394298D01*
X1468217Y394413D01*
Y395448D01*
G01X1468734Y399335D02*
X1468424Y399565D01*
X1468269Y399833D01*
X1468217Y400140D01*
X1468320Y400523D01*
X1468579Y400791D01*
X1468889Y400868D01*
X1469199Y400830D01*
X1469457Y400676D01*
X1469974Y399910D01*
X1470335Y399565D01*
X1470852Y399335D01*
X1471317Y399258D01*
Y400868D01*
G01X1468217Y403163D02*
X1468320Y402856D01*
X1468579Y402626D01*
X1468889Y402473D01*
X1469302Y402358D01*
X1469767Y402320D01*
X1470232Y402358D01*
X1470645Y402473D01*
X1470955Y402626D01*
X1471214Y402856D01*
X1471317Y403163D01*
X1471214Y403470D01*
X1470955Y403700D01*
X1470645Y403853D01*
X1470232Y403968D01*
X1469767Y404006D01*
X1469302Y403968D01*
X1468889Y403853D01*
X1468579Y403700D01*
X1468320Y403470D01*
X1468217Y403163D01*
G01X1470935Y369507D02*
X1471193Y369737D01*
X1471348Y370005D01*
X1471400Y370350D01*
X1471297Y370695D01*
X1471090Y370963D01*
X1470728Y371155D01*
X1470315Y371193D01*
X1469902Y371117D01*
X1469643Y370925D01*
X1469437Y370657D01*
X1469385Y370388D01*
X1469437Y370120D01*
X1469643Y369775D01*
X1468300Y369890D01*
Y370925D01*
G01X1471317Y382907D02*
X1468217D01*
X1468837Y382447D01*
G01X1471317D02*
Y383367D01*
G01X1468217Y386007D02*
X1468320Y385700D01*
X1468579Y385470D01*
X1468889Y385317D01*
X1469302Y385202D01*
X1469767Y385164D01*
X1470232Y385202D01*
X1470645Y385317D01*
X1470955Y385470D01*
X1471214Y385700D01*
X1471317Y386007D01*
X1471214Y386314D01*
X1470955Y386544D01*
X1470645Y386697D01*
X1470232Y386812D01*
X1469767Y386850D01*
X1469302Y386812D01*
X1468889Y386697D01*
X1468579Y386544D01*
X1468320Y386314D01*
X1468217Y386007D01*
G01X1472220Y360502D02*
X1469120Y361460D01*
X1472220Y362418D01*
G01X1471135Y362073D02*
Y360847D01*
G01X1473188Y361933D02*
X1473033Y361703D01*
X1472930Y361435D01*
Y361128D01*
X1473085Y360783D01*
X1473343Y360515D01*
X1473653Y360323D01*
X1474170Y360170D01*
X1474635Y360132D01*
X1475100Y360208D01*
X1475410Y360323D01*
X1475720Y360553D01*
X1475927Y360822D01*
X1476030Y361090D01*
Y361358D01*
X1475927Y361627D01*
X1475772Y361857D01*
X1475565Y362048D01*
G01X1488230Y360353D02*
X1491330D01*
Y361887D01*
G01X1486870Y360053D02*
X1487180Y360245D01*
X1487387Y360475D01*
X1487490Y360743D01*
X1487387Y361050D01*
X1487180Y361280D01*
X1486870Y361510D01*
X1486457Y361587D01*
X1484390D01*
G01X1482270Y360930D02*
Y361697D01*
X1483200D01*
X1483510Y361467D01*
X1483717Y361198D01*
X1483820Y360815D01*
X1483717Y360432D01*
X1483510Y360163D01*
X1483200Y359933D01*
X1482838Y359780D01*
X1482425Y359703D01*
X1482063D01*
X1481753Y359780D01*
X1481392Y359933D01*
X1481082Y360163D01*
X1480875Y360393D01*
X1480720Y360700D01*
Y360968D01*
X1480823Y361275D01*
X1481030Y361505D01*
G01X1479940Y361727D02*
Y360193D01*
X1476840D01*
Y361727D01*
G01X1478338Y361113D02*
Y360193D01*
G01X1510327Y358926D02*
X1507227Y359884D01*
X1510327Y360842D01*
G01X1509242Y360497D02*
Y359271D01*
G01X1508674Y363291D02*
X1508519Y363444D01*
X1508260Y363559D01*
X1507899Y363636D01*
X1507589Y363559D01*
X1507382Y363406D01*
X1507227Y363137D01*
Y362102D01*
X1510327D01*
Y363367D01*
X1510120Y363636D01*
X1509810Y363789D01*
X1509449Y363866D01*
X1509087Y363789D01*
X1508777Y363559D01*
X1508674Y363291D01*
Y362102D01*
G01X1506360Y360901D02*
X1504965D01*
X1503260Y360134D01*
G01Y361668D02*
X1504965Y360901D01*
G01X1499873Y360039D02*
X1502973Y360997D01*
X1499873Y361955D01*
G01X1499120Y360263D02*
X1496020D01*
Y361222D01*
X1496175Y361528D01*
X1496382Y361720D01*
X1496795Y361797D01*
X1497208Y361720D01*
X1497467Y361490D01*
X1497622Y361222D01*
Y360263D01*
G01Y361222D02*
X1499120Y361797D01*
G01X1495270Y360078D02*
X1492170D01*
X1495270Y361842D01*
X1492170D01*
G01X1530114Y359023D02*
X1527014Y359981D01*
X1530114Y360939D01*
G01X1529029Y360594D02*
Y359368D01*
G01X1530114Y362199D02*
X1527014D01*
X1530114Y363963D01*
X1527014D01*
G01X1525857Y359072D02*
X1522757Y360030D01*
X1525857Y360988D01*
G01X1524772Y360643D02*
Y359417D01*
G01X1522757Y362363D02*
X1525857D01*
Y363897D01*
G01X1521939Y359023D02*
X1518839Y359981D01*
X1521939Y360939D01*
G01X1520854Y360594D02*
Y359368D01*
G01X1521319Y362314D02*
X1521629Y362506D01*
X1521836Y362736D01*
X1521939Y363004D01*
X1521836Y363311D01*
X1521629Y363541D01*
X1521319Y363771D01*
X1520906Y363848D01*
X1518839D01*
G01X1518650Y358962D02*
X1515550Y359920D01*
X1518650Y360878D01*
G01X1517565Y360533D02*
Y359307D01*
G01X1518650Y362292D02*
X1515550D01*
Y363748D01*
G01X1517048Y363212D02*
Y362292D01*
G01X1514488Y359168D02*
X1511388Y360126D01*
X1514488Y361084D01*
G01X1513403Y360739D02*
Y359513D01*
G01X1514488Y362383D02*
X1511388D01*
Y363149D01*
X1511543Y363456D01*
X1511750Y363686D01*
X1512060Y363878D01*
X1512421Y364031D01*
X1512938Y364069D01*
X1513455Y364031D01*
X1513816Y363878D01*
X1514126Y363686D01*
X1514333Y363456D01*
X1514488Y363149D01*
Y362383D01*
G01X1472382Y365571D02*
Y499429D01*
X1582618D01*
Y365571D01*
X1472382D01*
G01X1471302Y447936D02*
X1468202D01*
X1470424Y446518D01*
Y448434D01*
G01X1470837Y449733D02*
X1471095Y449963D01*
X1471250Y450231D01*
X1471302Y450576D01*
X1471199Y450921D01*
X1470992Y451189D01*
X1470630Y451381D01*
X1470217Y451419D01*
X1469804Y451343D01*
X1469545Y451151D01*
X1469339Y450883D01*
X1469287Y450614D01*
X1469339Y450346D01*
X1469545Y450001D01*
X1468202Y450116D01*
Y451151D01*
G01X1470837Y454923D02*
X1471095Y455153D01*
X1471250Y455421D01*
X1471302Y455766D01*
X1471199Y456111D01*
X1470992Y456379D01*
X1470630Y456571D01*
X1470217Y456609D01*
X1469804Y456533D01*
X1469545Y456341D01*
X1469339Y456073D01*
X1469287Y455804D01*
X1469339Y455536D01*
X1469545Y455191D01*
X1468202Y455306D01*
Y456341D01*
G01Y458866D02*
X1468305Y458559D01*
X1468564Y458329D01*
X1468874Y458176D01*
X1469287Y458061D01*
X1469752Y458023D01*
X1470217Y458061D01*
X1470630Y458176D01*
X1470940Y458329D01*
X1471199Y458559D01*
X1471302Y458866D01*
X1471199Y459173D01*
X1470940Y459403D01*
X1470630Y459556D01*
X1470217Y459671D01*
X1469752Y459709D01*
X1469287Y459671D01*
X1468874Y459556D01*
X1468564Y459403D01*
X1468305Y459173D01*
X1468202Y458866D01*
G01X1470837Y464555D02*
X1471095Y464785D01*
X1471250Y465053D01*
X1471302Y465398D01*
X1471199Y465743D01*
X1470992Y466011D01*
X1470630Y466203D01*
X1470217Y466241D01*
X1469804Y466165D01*
X1469545Y465973D01*
X1469339Y465705D01*
X1469287Y465436D01*
X1469339Y465168D01*
X1469545Y464823D01*
X1468202Y464938D01*
Y465973D01*
G01X1470837Y467655D02*
X1471095Y467885D01*
X1471250Y468153D01*
X1471302Y468498D01*
X1471199Y468843D01*
X1470992Y469111D01*
X1470630Y469303D01*
X1470217Y469341D01*
X1469804Y469265D01*
X1469545Y469073D01*
X1469339Y468805D01*
X1469287Y468536D01*
X1469339Y468268D01*
X1469545Y467923D01*
X1468202Y468038D01*
Y469073D01*
G01X1470550Y429537D02*
X1470912Y429767D01*
X1471118Y430073D01*
X1471170Y430418D01*
X1471118Y430725D01*
X1470860Y431032D01*
X1470550Y431223D01*
X1470240Y431262D01*
X1469878Y431185D01*
X1469620Y430917D01*
X1469517Y430648D01*
Y430303D01*
G01Y430648D02*
X1469362Y430878D01*
X1469103Y431070D01*
X1468793Y431147D01*
X1468483Y431070D01*
X1468225Y430878D01*
X1468070Y430533D01*
X1468122Y430188D01*
X1468328Y429843D01*
G01X1470705Y432637D02*
X1470963Y432867D01*
X1471118Y433135D01*
X1471170Y433480D01*
X1471067Y433825D01*
X1470860Y434093D01*
X1470498Y434285D01*
X1470085Y434323D01*
X1469672Y434247D01*
X1469413Y434055D01*
X1469207Y433787D01*
X1469155Y433518D01*
X1469207Y433250D01*
X1469413Y432905D01*
X1468070Y433020D01*
Y434055D01*
G01X1471350Y437960D02*
X1468250D01*
X1470472Y436542D01*
Y438458D01*
G01X1468250Y440600D02*
X1468353Y440293D01*
X1468612Y440063D01*
X1468922Y439910D01*
X1469335Y439795D01*
X1469800Y439757D01*
X1470265Y439795D01*
X1470678Y439910D01*
X1470988Y440063D01*
X1471247Y440293D01*
X1471350Y440600D01*
X1471247Y440907D01*
X1470988Y441137D01*
X1470678Y441290D01*
X1470265Y441405D01*
X1469800Y441443D01*
X1469335Y441405D01*
X1468922Y441290D01*
X1468612Y441137D01*
X1468353Y440907D01*
X1468250Y440600D01*
G01X1468734Y409685D02*
X1468424Y409915D01*
X1468269Y410183D01*
X1468217Y410490D01*
X1468320Y410873D01*
X1468579Y411141D01*
X1468889Y411218D01*
X1469199Y411180D01*
X1469457Y411026D01*
X1469974Y410260D01*
X1470335Y409915D01*
X1470852Y409685D01*
X1471317Y409608D01*
Y411218D01*
G01X1470852Y412670D02*
X1471110Y412900D01*
X1471265Y413168D01*
X1471317Y413513D01*
X1471214Y413858D01*
X1471007Y414126D01*
X1470645Y414318D01*
X1470232Y414356D01*
X1469819Y414280D01*
X1469560Y414088D01*
X1469354Y413820D01*
X1469302Y413551D01*
X1469354Y413283D01*
X1469560Y412938D01*
X1468217Y413053D01*
Y414088D01*
G01X1471101Y420070D02*
X1471463Y420300D01*
X1471669Y420606D01*
X1471721Y420951D01*
X1471669Y421258D01*
X1471411Y421565D01*
X1471101Y421756D01*
X1470791Y421795D01*
X1470429Y421718D01*
X1470171Y421450D01*
X1470068Y421181D01*
Y420836D01*
G01Y421181D02*
X1469913Y421411D01*
X1469654Y421603D01*
X1469344Y421680D01*
X1469034Y421603D01*
X1468776Y421411D01*
X1468621Y421066D01*
X1468673Y420721D01*
X1468879Y420376D01*
G01X1468621Y424013D02*
X1468724Y423706D01*
X1468983Y423476D01*
X1469293Y423323D01*
X1469706Y423208D01*
X1470171Y423170D01*
X1470636Y423208D01*
X1471049Y423323D01*
X1471359Y423476D01*
X1471618Y423706D01*
X1471721Y424013D01*
X1471618Y424320D01*
X1471359Y424550D01*
X1471049Y424703D01*
X1470636Y424818D01*
X1470171Y424856D01*
X1469706Y424818D01*
X1469293Y424703D01*
X1468983Y424550D01*
X1468724Y424320D01*
X1468621Y424013D01*
G01X1530400Y500200D02*
X1519700D01*
Y523200D01*
X1533000D01*
Y541900D01*
G01X1499442Y519517D02*
X1499317Y519267D01*
X1499234Y518975D01*
Y518642D01*
X1499359Y518267D01*
X1499567Y517975D01*
X1499817Y517767D01*
X1500234Y517600D01*
X1500609Y517558D01*
X1500984Y517642D01*
X1501234Y517767D01*
X1501484Y518017D01*
X1501651Y518308D01*
X1501734Y518600D01*
Y518892D01*
X1501651Y519183D01*
X1501526Y519433D01*
X1501359Y519642D01*
G01X1501734Y521617D02*
X1501192Y521700D01*
X1500734Y521825D01*
X1500317Y521992D01*
X1499859Y522200D01*
X1499234Y522533D01*
Y520867D01*
G01X1501734Y523758D02*
X1499234Y524800D01*
X1501734Y525842D01*
G01X1500859Y525467D02*
Y524133D01*
G01X1501234Y526983D02*
X1501526Y527233D01*
X1501692Y527567D01*
X1501734Y527942D01*
X1501692Y528275D01*
X1501484Y528608D01*
X1501234Y528817D01*
X1500984Y528858D01*
X1500692Y528775D01*
X1500484Y528483D01*
X1500401Y528192D01*
Y527817D01*
G01Y528192D02*
X1500276Y528442D01*
X1500067Y528650D01*
X1499817Y528733D01*
X1499567Y528650D01*
X1499359Y528442D01*
X1499234Y528067D01*
X1499276Y527692D01*
X1499442Y527317D01*
G01X1501734Y531000D02*
X1499234D01*
X1499734Y530500D01*
G01X1501734D02*
Y531500D01*
G01X1494642Y517917D02*
X1494517Y517667D01*
X1494434Y517375D01*
Y517042D01*
X1494559Y516667D01*
X1494767Y516375D01*
X1495017Y516167D01*
X1495434Y516000D01*
X1495809Y515958D01*
X1496184Y516042D01*
X1496434Y516167D01*
X1496684Y516417D01*
X1496851Y516708D01*
X1496934Y517000D01*
Y517292D01*
X1496851Y517583D01*
X1496726Y517833D01*
X1496559Y518042D01*
G01X1496934Y520017D02*
X1496392Y520100D01*
X1495934Y520225D01*
X1495517Y520392D01*
X1495059Y520600D01*
X1494434Y520933D01*
Y519267D01*
G01X1496934Y522158D02*
X1494434Y523200D01*
X1496934Y524242D01*
G01X1496059Y523867D02*
Y522533D01*
G01X1496434Y525383D02*
X1496726Y525633D01*
X1496892Y525967D01*
X1496934Y526342D01*
X1496892Y526675D01*
X1496684Y527008D01*
X1496434Y527217D01*
X1496184Y527258D01*
X1495892Y527175D01*
X1495684Y526883D01*
X1495601Y526592D01*
Y526217D01*
G01Y526592D02*
X1495476Y526842D01*
X1495267Y527050D01*
X1495017Y527133D01*
X1494767Y527050D01*
X1494559Y526842D01*
X1494434Y526467D01*
X1494476Y526092D01*
X1494642Y525717D01*
G01X1494434Y529400D02*
X1494517Y529067D01*
X1494726Y528817D01*
X1494976Y528650D01*
X1495309Y528525D01*
X1495684Y528483D01*
X1496059Y528525D01*
X1496392Y528650D01*
X1496642Y528817D01*
X1496851Y529067D01*
X1496934Y529400D01*
X1496851Y529733D01*
X1496642Y529983D01*
X1496392Y530150D01*
X1496059Y530275D01*
X1495684Y530317D01*
X1495309Y530275D01*
X1494976Y530150D01*
X1494726Y529983D01*
X1494517Y529733D01*
X1494434Y529400D01*
G01X1506767Y528792D02*
X1506517Y528917D01*
X1506225Y529000D01*
X1505892D01*
X1505517Y528875D01*
X1505225Y528667D01*
X1505017Y528417D01*
X1504850Y528000D01*
X1504808Y527625D01*
X1504892Y527250D01*
X1505017Y527000D01*
X1505267Y526750D01*
X1505558Y526583D01*
X1505850Y526500D01*
X1506142D01*
X1506433Y526583D01*
X1506683Y526708D01*
X1506892Y526875D01*
G01X1508867Y526500D02*
X1508950Y527042D01*
X1509075Y527500D01*
X1509242Y527917D01*
X1509450Y528375D01*
X1509783Y529000D01*
X1508117D01*
G01X1512383Y527833D02*
X1512550Y527958D01*
X1512675Y528167D01*
X1512758Y528458D01*
X1512675Y528708D01*
X1512508Y528875D01*
X1512217Y529000D01*
X1511092D01*
Y526500D01*
X1512467D01*
X1512758Y526667D01*
X1512925Y526917D01*
X1513008Y527208D01*
X1512925Y527500D01*
X1512675Y527750D01*
X1512383Y527833D01*
X1511092D01*
G01X1515650Y526500D02*
Y529000D01*
X1514108Y527208D01*
X1516192D01*
G01X1526531Y527123D02*
X1526406Y526873D01*
X1526323Y526581D01*
Y526248D01*
X1526448Y525873D01*
X1526656Y525581D01*
X1526906Y525373D01*
X1527323Y525206D01*
X1527698Y525164D01*
X1528073Y525248D01*
X1528323Y525373D01*
X1528573Y525623D01*
X1528740Y525914D01*
X1528823Y526206D01*
Y526498D01*
X1528740Y526789D01*
X1528615Y527039D01*
X1528448Y527248D01*
G01X1528823Y529223D02*
X1528281Y529306D01*
X1527823Y529431D01*
X1527406Y529598D01*
X1526948Y529806D01*
X1526323Y530139D01*
Y528473D01*
G01X1528823Y531364D02*
X1526323Y532406D01*
X1528823Y533448D01*
G01X1527948Y533073D02*
Y531739D01*
G01X1528823Y536006D02*
X1526323D01*
X1528115Y534464D01*
Y536548D01*
G01X1526740Y537814D02*
X1526490Y538064D01*
X1526365Y538356D01*
X1526323Y538689D01*
X1526406Y539106D01*
X1526615Y539398D01*
X1526865Y539481D01*
X1527115Y539439D01*
X1527323Y539273D01*
X1527740Y538439D01*
X1528031Y538064D01*
X1528448Y537814D01*
X1528823Y537731D01*
Y539481D01*
G01X1523917Y507667D02*
Y510167D01*
X1524958D01*
X1525292Y510042D01*
X1525500Y509875D01*
X1525583Y509542D01*
X1525500Y509209D01*
X1525250Y509000D01*
X1524958Y508875D01*
X1523917D01*
G01X1524958D02*
X1525583Y507667D01*
G01X1527058Y509750D02*
X1527308Y510000D01*
X1527600Y510125D01*
X1527933Y510167D01*
X1528350Y510084D01*
X1528642Y509875D01*
X1528725Y509625D01*
X1528683Y509375D01*
X1528517Y509167D01*
X1527683Y508750D01*
X1527308Y508459D01*
X1527058Y508042D01*
X1526975Y507667D01*
X1528725D01*
G01X1529867D02*
Y510167D01*
X1530950Y508084D01*
X1532033Y510167D01*
Y507667D01*
G01X1533967D02*
X1534050Y508209D01*
X1534175Y508667D01*
X1534342Y509084D01*
X1534550Y509542D01*
X1534883Y510167D01*
X1533217D01*
G01X1524036Y511309D02*
Y513809D01*
X1525077D01*
X1525411Y513684D01*
X1525619Y513517D01*
X1525702Y513184D01*
X1525619Y512851D01*
X1525369Y512642D01*
X1525077Y512517D01*
X1524036D01*
G01X1525077D02*
X1525702Y511309D01*
G01X1527969D02*
X1528261Y511351D01*
X1528594Y511476D01*
X1528802Y511684D01*
X1528886Y511976D01*
X1528802Y512267D01*
X1528552Y512517D01*
X1528177Y512642D01*
X1527761D01*
X1527511Y512726D01*
X1527302Y512934D01*
X1527219Y513226D01*
X1527344Y513517D01*
X1527636Y513726D01*
X1527969Y513809D01*
X1528302Y513726D01*
X1528594Y513517D01*
X1528719Y513226D01*
X1528636Y512934D01*
X1528427Y512726D01*
X1528177Y512642D01*
X1527761D01*
X1527386Y512517D01*
X1527136Y512267D01*
X1527052Y511976D01*
X1527136Y511684D01*
X1527344Y511476D01*
X1527677Y511351D01*
X1527969Y511309D01*
G01X1531402Y512642D02*
X1531569Y512767D01*
X1531694Y512976D01*
X1531777Y513267D01*
X1531694Y513517D01*
X1531527Y513684D01*
X1531236Y513809D01*
X1530111D01*
Y511309D01*
X1531486D01*
X1531777Y511476D01*
X1531944Y511726D01*
X1532027Y512017D01*
X1531944Y512309D01*
X1531694Y512559D01*
X1531402Y512642D01*
X1530111D01*
G01X1533377Y513392D02*
X1533627Y513642D01*
X1533919Y513767D01*
X1534252Y513809D01*
X1534669Y513726D01*
X1534961Y513517D01*
X1535044Y513267D01*
X1535002Y513017D01*
X1534836Y512809D01*
X1534002Y512392D01*
X1533627Y512101D01*
X1533377Y511684D01*
X1533294Y511309D01*
X1535044D01*
G01X1536352Y511809D02*
X1536602Y511517D01*
X1536936Y511351D01*
X1537311Y511309D01*
X1537644Y511351D01*
X1537977Y511559D01*
X1538186Y511809D01*
X1538227Y512059D01*
X1538144Y512351D01*
X1537852Y512559D01*
X1537561Y512642D01*
X1537186D01*
G01X1537561D02*
X1537811Y512767D01*
X1538019Y512976D01*
X1538102Y513226D01*
X1538019Y513476D01*
X1537811Y513684D01*
X1537436Y513809D01*
X1537061Y513767D01*
X1536686Y513601D01*
G01X1526766Y501423D02*
Y503923D01*
X1527807D01*
X1528141Y503798D01*
X1528349Y503631D01*
X1528432Y503298D01*
X1528349Y502965D01*
X1528099Y502756D01*
X1527807Y502631D01*
X1526766D01*
G01X1527807D02*
X1528432Y501423D01*
G01X1530699D02*
X1530991Y501465D01*
X1531324Y501590D01*
X1531532Y501798D01*
X1531616Y502090D01*
X1531532Y502381D01*
X1531282Y502631D01*
X1530907Y502756D01*
X1530491D01*
X1530241Y502840D01*
X1530032Y503048D01*
X1529949Y503340D01*
X1530074Y503631D01*
X1530366Y503840D01*
X1530699Y503923D01*
X1531032Y503840D01*
X1531324Y503631D01*
X1531449Y503340D01*
X1531366Y503048D01*
X1531157Y502840D01*
X1530907Y502756D01*
X1530491D01*
X1530116Y502631D01*
X1529866Y502381D01*
X1529782Y502090D01*
X1529866Y501798D01*
X1530074Y501590D01*
X1530407Y501465D01*
X1530699Y501423D01*
G01X1534716Y503715D02*
X1534466Y503840D01*
X1534174Y503923D01*
X1533841D01*
X1533466Y503798D01*
X1533174Y503590D01*
X1532966Y503340D01*
X1532799Y502923D01*
X1532757Y502548D01*
X1532841Y502173D01*
X1532966Y501923D01*
X1533216Y501673D01*
X1533507Y501506D01*
X1533799Y501423D01*
X1534091D01*
X1534382Y501506D01*
X1534632Y501631D01*
X1534841Y501798D01*
G01X1536899Y501423D02*
Y503923D01*
X1536399Y503423D01*
G01Y501423D02*
X1537399D01*
G01X1539999D02*
X1540291Y501465D01*
X1540624Y501590D01*
X1540832Y501798D01*
X1540916Y502090D01*
X1540832Y502381D01*
X1540582Y502631D01*
X1540207Y502756D01*
X1539791D01*
X1539541Y502840D01*
X1539332Y503048D01*
X1539249Y503340D01*
X1539374Y503631D01*
X1539666Y503840D01*
X1539999Y503923D01*
X1540332Y503840D01*
X1540624Y503631D01*
X1540749Y503340D01*
X1540666Y503048D01*
X1540457Y502840D01*
X1540207Y502756D01*
X1539791D01*
X1539416Y502631D01*
X1539166Y502381D01*
X1539082Y502090D01*
X1539166Y501798D01*
X1539374Y501590D01*
X1539707Y501465D01*
X1539999Y501423D01*
G01X1469708Y503027D02*
X1469583Y502777D01*
X1469500Y502485D01*
Y502152D01*
X1469625Y501777D01*
X1469833Y501485D01*
X1470083Y501277D01*
X1470500Y501110D01*
X1470875Y501068D01*
X1471250Y501152D01*
X1471500Y501277D01*
X1471750Y501527D01*
X1471917Y501818D01*
X1472000Y502110D01*
Y502402D01*
X1471917Y502693D01*
X1471792Y502943D01*
X1471625Y503152D01*
G01X1472000Y505127D02*
X1471458Y505210D01*
X1471000Y505335D01*
X1470583Y505502D01*
X1470125Y505710D01*
X1469500Y506043D01*
Y504377D01*
G01X1470667Y508643D02*
X1470542Y508810D01*
X1470333Y508935D01*
X1470042Y509018D01*
X1469792Y508935D01*
X1469625Y508768D01*
X1469500Y508477D01*
Y507352D01*
X1472000D01*
Y508727D01*
X1471833Y509018D01*
X1471583Y509185D01*
X1471292Y509268D01*
X1471000Y509185D01*
X1470750Y508935D01*
X1470667Y508643D01*
Y507352D01*
G01X1469917Y510618D02*
X1469667Y510868D01*
X1469542Y511160D01*
X1469500Y511493D01*
X1469583Y511910D01*
X1469792Y512202D01*
X1470042Y512285D01*
X1470292Y512243D01*
X1470500Y512077D01*
X1470917Y511243D01*
X1471208Y510868D01*
X1471625Y510618D01*
X1472000Y510535D01*
Y512285D01*
G01Y515010D02*
X1469500D01*
X1471292Y513468D01*
Y515552D01*
G01X1466208Y503027D02*
X1466083Y502777D01*
X1466000Y502485D01*
Y502152D01*
X1466125Y501777D01*
X1466333Y501485D01*
X1466583Y501277D01*
X1467000Y501110D01*
X1467375Y501068D01*
X1467750Y501152D01*
X1468000Y501277D01*
X1468250Y501527D01*
X1468417Y501818D01*
X1468500Y502110D01*
Y502402D01*
X1468417Y502693D01*
X1468292Y502943D01*
X1468125Y503152D01*
G01X1468500Y505127D02*
X1467958Y505210D01*
X1467500Y505335D01*
X1467083Y505502D01*
X1466625Y505710D01*
X1466000Y506043D01*
Y504377D01*
G01X1467167Y508643D02*
X1467042Y508810D01*
X1466833Y508935D01*
X1466542Y509018D01*
X1466292Y508935D01*
X1466125Y508768D01*
X1466000Y508477D01*
Y507352D01*
X1468500D01*
Y508727D01*
X1468333Y509018D01*
X1468083Y509185D01*
X1467792Y509268D01*
X1467500Y509185D01*
X1467250Y508935D01*
X1467167Y508643D01*
Y507352D01*
G01X1466417Y510618D02*
X1466167Y510868D01*
X1466042Y511160D01*
X1466000Y511493D01*
X1466083Y511910D01*
X1466292Y512202D01*
X1466542Y512285D01*
X1466792Y512243D01*
X1467000Y512077D01*
X1467417Y511243D01*
X1467708Y510868D01*
X1468125Y510618D01*
X1468500Y510535D01*
Y512285D01*
G01X1468000Y513593D02*
X1468292Y513843D01*
X1468458Y514177D01*
X1468500Y514552D01*
X1468458Y514885D01*
X1468250Y515218D01*
X1468000Y515427D01*
X1467750Y515468D01*
X1467458Y515385D01*
X1467250Y515093D01*
X1467167Y514802D01*
Y514427D01*
G01Y514802D02*
X1467042Y515052D01*
X1466833Y515260D01*
X1466583Y515343D01*
X1466333Y515260D01*
X1466125Y515052D01*
X1466000Y514677D01*
X1466042Y514302D01*
X1466208Y513927D01*
G01X1473608Y503427D02*
X1473483Y503177D01*
X1473400Y502885D01*
Y502552D01*
X1473525Y502177D01*
X1473733Y501885D01*
X1473983Y501677D01*
X1474400Y501510D01*
X1474775Y501468D01*
X1475150Y501552D01*
X1475400Y501677D01*
X1475650Y501927D01*
X1475817Y502218D01*
X1475900Y502510D01*
Y502802D01*
X1475817Y503093D01*
X1475692Y503343D01*
X1475525Y503552D01*
G01X1475900Y505527D02*
X1475358Y505610D01*
X1474900Y505735D01*
X1474483Y505902D01*
X1474025Y506110D01*
X1473400Y506443D01*
Y504777D01*
G01X1474567Y509043D02*
X1474442Y509210D01*
X1474233Y509335D01*
X1473942Y509418D01*
X1473692Y509335D01*
X1473525Y509168D01*
X1473400Y508877D01*
Y507752D01*
X1475900D01*
Y509127D01*
X1475733Y509418D01*
X1475483Y509585D01*
X1475192Y509668D01*
X1474900Y509585D01*
X1474650Y509335D01*
X1474567Y509043D01*
Y507752D01*
G01X1473817Y511018D02*
X1473567Y511268D01*
X1473442Y511560D01*
X1473400Y511893D01*
X1473483Y512310D01*
X1473692Y512602D01*
X1473942Y512685D01*
X1474192Y512643D01*
X1474400Y512477D01*
X1474817Y511643D01*
X1475108Y511268D01*
X1475525Y511018D01*
X1475900Y510935D01*
Y512685D01*
G01X1473400Y514910D02*
X1473483Y514577D01*
X1473692Y514327D01*
X1473942Y514160D01*
X1474275Y514035D01*
X1474650Y513993D01*
X1475025Y514035D01*
X1475358Y514160D01*
X1475608Y514327D01*
X1475817Y514577D01*
X1475900Y514910D01*
X1475817Y515243D01*
X1475608Y515493D01*
X1475358Y515660D01*
X1475025Y515785D01*
X1474650Y515827D01*
X1474275Y515785D01*
X1473942Y515660D01*
X1473692Y515493D01*
X1473483Y515243D01*
X1473400Y514910D01*
G01X1485542Y517317D02*
X1485417Y517067D01*
X1485334Y516775D01*
Y516442D01*
X1485459Y516067D01*
X1485667Y515775D01*
X1485917Y515567D01*
X1486334Y515400D01*
X1486709Y515358D01*
X1487084Y515442D01*
X1487334Y515567D01*
X1487584Y515817D01*
X1487751Y516108D01*
X1487834Y516400D01*
Y516692D01*
X1487751Y516983D01*
X1487626Y517233D01*
X1487459Y517442D01*
G01X1487834Y519417D02*
X1487292Y519500D01*
X1486834Y519625D01*
X1486417Y519792D01*
X1485959Y520000D01*
X1485334Y520333D01*
Y518667D01*
G01X1487834Y521558D02*
X1485334Y522600D01*
X1487834Y523642D01*
G01X1486959Y523267D02*
Y521933D01*
G01X1487334Y524783D02*
X1487626Y525033D01*
X1487792Y525367D01*
X1487834Y525742D01*
X1487792Y526075D01*
X1487584Y526408D01*
X1487334Y526617D01*
X1487084Y526658D01*
X1486792Y526575D01*
X1486584Y526283D01*
X1486501Y525992D01*
Y525617D01*
G01Y525992D02*
X1486376Y526242D01*
X1486167Y526450D01*
X1485917Y526533D01*
X1485667Y526450D01*
X1485459Y526242D01*
X1485334Y525867D01*
X1485376Y525492D01*
X1485542Y525117D01*
G01X1486792Y528008D02*
X1486501Y528300D01*
X1486334Y528550D01*
X1486251Y528883D01*
X1486334Y529175D01*
X1486501Y529383D01*
X1486751Y529550D01*
X1487042Y529592D01*
X1487292Y529550D01*
X1487542Y529383D01*
X1487751Y529133D01*
X1487834Y528842D01*
X1487751Y528508D01*
X1487501Y528217D01*
X1487126Y528050D01*
X1486709Y528008D01*
X1486167Y528092D01*
X1485876Y528217D01*
X1485584Y528425D01*
X1485376Y528717D01*
X1485334Y529008D01*
X1485417Y529300D01*
X1485626Y529508D01*
G01X1523297Y518858D02*
X1523047Y518983D01*
X1522755Y519066D01*
X1522422D01*
X1522047Y518941D01*
X1521755Y518733D01*
X1521547Y518483D01*
X1521380Y518066D01*
X1521338Y517691D01*
X1521422Y517316D01*
X1521547Y517066D01*
X1521797Y516816D01*
X1522088Y516649D01*
X1522380Y516566D01*
X1522672D01*
X1522963Y516649D01*
X1523213Y516774D01*
X1523422Y516941D01*
G01X1525480Y516566D02*
X1525772Y516608D01*
X1526105Y516733D01*
X1526313Y516941D01*
X1526397Y517233D01*
X1526313Y517524D01*
X1526063Y517774D01*
X1525688Y517899D01*
X1525272D01*
X1525022Y517983D01*
X1524813Y518191D01*
X1524730Y518483D01*
X1524855Y518774D01*
X1525147Y518983D01*
X1525480Y519066D01*
X1525813Y518983D01*
X1526105Y518774D01*
X1526230Y518483D01*
X1526147Y518191D01*
X1525938Y517983D01*
X1525688Y517899D01*
X1525272D01*
X1524897Y517774D01*
X1524647Y517524D01*
X1524563Y517233D01*
X1524647Y516941D01*
X1524855Y516733D01*
X1525188Y516608D01*
X1525480Y516566D01*
G01X1528913Y517899D02*
X1529080Y518024D01*
X1529205Y518233D01*
X1529288Y518524D01*
X1529205Y518774D01*
X1529038Y518941D01*
X1528747Y519066D01*
X1527622D01*
Y516566D01*
X1528997D01*
X1529288Y516733D01*
X1529455Y516983D01*
X1529538Y517274D01*
X1529455Y517566D01*
X1529205Y517816D01*
X1528913Y517899D01*
X1527622D01*
G01X1531680Y516566D02*
Y519066D01*
X1531180Y518566D01*
G01Y516566D02*
X1532180D01*
G01X1533863Y517066D02*
X1534113Y516774D01*
X1534447Y516608D01*
X1534822Y516566D01*
X1535155Y516608D01*
X1535488Y516816D01*
X1535697Y517066D01*
X1535738Y517316D01*
X1535655Y517608D01*
X1535363Y517816D01*
X1535072Y517899D01*
X1534697D01*
G01X1535072D02*
X1535322Y518024D01*
X1535530Y518233D01*
X1535613Y518483D01*
X1535530Y518733D01*
X1535322Y518941D01*
X1534947Y519066D01*
X1534572Y519024D01*
X1534197Y518858D01*
G01X1523196Y522197D02*
X1522946Y522322D01*
X1522654Y522405D01*
X1522321D01*
X1521946Y522280D01*
X1521654Y522072D01*
X1521446Y521822D01*
X1521279Y521405D01*
X1521237Y521030D01*
X1521321Y520655D01*
X1521446Y520405D01*
X1521696Y520155D01*
X1521987Y519988D01*
X1522279Y519905D01*
X1522571D01*
X1522862Y519988D01*
X1523112Y520113D01*
X1523321Y520280D01*
G01X1525379Y519905D02*
X1525671Y519947D01*
X1526004Y520072D01*
X1526212Y520280D01*
X1526296Y520572D01*
X1526212Y520863D01*
X1525962Y521113D01*
X1525587Y521238D01*
X1525171D01*
X1524921Y521322D01*
X1524712Y521530D01*
X1524629Y521822D01*
X1524754Y522113D01*
X1525046Y522322D01*
X1525379Y522405D01*
X1525712Y522322D01*
X1526004Y522113D01*
X1526129Y521822D01*
X1526046Y521530D01*
X1525837Y521322D01*
X1525587Y521238D01*
X1525171D01*
X1524796Y521113D01*
X1524546Y520863D01*
X1524462Y520572D01*
X1524546Y520280D01*
X1524754Y520072D01*
X1525087Y519947D01*
X1525379Y519905D01*
G01X1528812Y521238D02*
X1528979Y521363D01*
X1529104Y521572D01*
X1529187Y521863D01*
X1529104Y522113D01*
X1528937Y522280D01*
X1528646Y522405D01*
X1527521D01*
Y519905D01*
X1528896D01*
X1529187Y520072D01*
X1529354Y520322D01*
X1529437Y520613D01*
X1529354Y520905D01*
X1529104Y521155D01*
X1528812Y521238D01*
X1527521D01*
G01X1531579Y519905D02*
Y522405D01*
X1531079Y521905D01*
G01Y519905D02*
X1532079D01*
G01X1535179D02*
Y522405D01*
X1533637Y520613D01*
X1535721D01*
G01X1471302Y492875D02*
X1470630Y492952D01*
X1470062Y493067D01*
X1469545Y493220D01*
X1468977Y493412D01*
X1468202Y493719D01*
Y492185D01*
G01Y496052D02*
X1468305Y495745D01*
X1468564Y495515D01*
X1468874Y495362D01*
X1469287Y495247D01*
X1469752Y495209D01*
X1470217Y495247D01*
X1470630Y495362D01*
X1470940Y495515D01*
X1471199Y495745D01*
X1471302Y496052D01*
X1471199Y496359D01*
X1470940Y496589D01*
X1470630Y496742D01*
X1470217Y496857D01*
X1469752Y496895D01*
X1469287Y496857D01*
X1468874Y496742D01*
X1468564Y496589D01*
X1468305Y496359D01*
X1468202Y496052D01*
G01X1470010Y472864D02*
X1469649Y473132D01*
X1469442Y473362D01*
X1469339Y473669D01*
X1469442Y473937D01*
X1469649Y474129D01*
X1469959Y474282D01*
X1470320Y474320D01*
X1470630Y474282D01*
X1470940Y474129D01*
X1471199Y473899D01*
X1471302Y473630D01*
X1471199Y473324D01*
X1470889Y473055D01*
X1470424Y472902D01*
X1469907Y472864D01*
X1469235Y472940D01*
X1468874Y473055D01*
X1468512Y473247D01*
X1468254Y473515D01*
X1468202Y473784D01*
X1468305Y474052D01*
X1468564Y474244D01*
G01X1468202Y476692D02*
X1468305Y476385D01*
X1468564Y476155D01*
X1468874Y476002D01*
X1469287Y475887D01*
X1469752Y475849D01*
X1470217Y475887D01*
X1470630Y476002D01*
X1470940Y476155D01*
X1471199Y476385D01*
X1471302Y476692D01*
X1471199Y476999D01*
X1470940Y477229D01*
X1470630Y477382D01*
X1470217Y477497D01*
X1469752Y477535D01*
X1469287Y477497D01*
X1468874Y477382D01*
X1468564Y477229D01*
X1468305Y476999D01*
X1468202Y476692D01*
G01X1470010Y482640D02*
X1469649Y482908D01*
X1469442Y483138D01*
X1469339Y483445D01*
X1469442Y483713D01*
X1469649Y483905D01*
X1469959Y484058D01*
X1470320Y484096D01*
X1470630Y484058D01*
X1470940Y483905D01*
X1471199Y483675D01*
X1471302Y483406D01*
X1471199Y483100D01*
X1470889Y482831D01*
X1470424Y482678D01*
X1469907Y482640D01*
X1469235Y482716D01*
X1468874Y482831D01*
X1468512Y483023D01*
X1468254Y483291D01*
X1468202Y483560D01*
X1468305Y483828D01*
X1468564Y484020D01*
G01X1470837Y485625D02*
X1471095Y485855D01*
X1471250Y486123D01*
X1471302Y486468D01*
X1471199Y486813D01*
X1470992Y487081D01*
X1470630Y487273D01*
X1470217Y487311D01*
X1469804Y487235D01*
X1469545Y487043D01*
X1469339Y486775D01*
X1469287Y486506D01*
X1469339Y486238D01*
X1469545Y485893D01*
X1468202Y486008D01*
Y487043D01*
G01X1491643Y503250D02*
Y501458D01*
X1491810Y501083D01*
X1492143Y500833D01*
X1492560Y500750D01*
X1492977Y500833D01*
X1493310Y501083D01*
X1493477Y501458D01*
Y503250D01*
G01X1495577Y500750D02*
X1495660Y501292D01*
X1495785Y501750D01*
X1495952Y502167D01*
X1496160Y502625D01*
X1496493Y503250D01*
X1494827D01*
G01X1499677Y503042D02*
X1499427Y503167D01*
X1499135Y503250D01*
X1498802D01*
X1498427Y503125D01*
X1498135Y502917D01*
X1497927Y502667D01*
X1497760Y502250D01*
X1497718Y501875D01*
X1497802Y501500D01*
X1497927Y501250D01*
X1498177Y501000D01*
X1498468Y500833D01*
X1498760Y500750D01*
X1499052D01*
X1499343Y500833D01*
X1499593Y500958D01*
X1499802Y501125D01*
G01X1501860Y500750D02*
Y503250D01*
X1501360Y502750D01*
G01Y500750D02*
X1502360D01*
G01X1506767Y536892D02*
X1506517Y537017D01*
X1506225Y537100D01*
X1505892D01*
X1505517Y536975D01*
X1505225Y536767D01*
X1505017Y536517D01*
X1504850Y536100D01*
X1504808Y535725D01*
X1504892Y535350D01*
X1505017Y535100D01*
X1505267Y534850D01*
X1505558Y534683D01*
X1505850Y534600D01*
X1506142D01*
X1506433Y534683D01*
X1506683Y534808D01*
X1506892Y534975D01*
G01X1508033Y535100D02*
X1508283Y534808D01*
X1508617Y534642D01*
X1508992Y534600D01*
X1509325Y534642D01*
X1509658Y534850D01*
X1509867Y535100D01*
X1509908Y535350D01*
X1509825Y535642D01*
X1509533Y535850D01*
X1509242Y535933D01*
X1508867D01*
G01X1509242D02*
X1509492Y536058D01*
X1509700Y536267D01*
X1509783Y536517D01*
X1509700Y536767D01*
X1509492Y536975D01*
X1509117Y537100D01*
X1508742Y537058D01*
X1508367Y536892D01*
G01X1510967Y534600D02*
Y537100D01*
X1512050Y535017D01*
X1513133Y537100D01*
Y534600D01*
G01X1515067D02*
X1515150Y535142D01*
X1515275Y535600D01*
X1515442Y536017D01*
X1515650Y536475D01*
X1515983Y537100D01*
X1514317D01*
G01X1506767Y540392D02*
X1506517Y540517D01*
X1506225Y540600D01*
X1505892D01*
X1505517Y540475D01*
X1505225Y540267D01*
X1505017Y540017D01*
X1504850Y539600D01*
X1504808Y539225D01*
X1504892Y538850D01*
X1505017Y538600D01*
X1505267Y538350D01*
X1505558Y538183D01*
X1505850Y538100D01*
X1506142D01*
X1506433Y538183D01*
X1506683Y538308D01*
X1506892Y538475D01*
G01X1508033Y538600D02*
X1508283Y538308D01*
X1508617Y538142D01*
X1508992Y538100D01*
X1509325Y538142D01*
X1509658Y538350D01*
X1509867Y538600D01*
X1509908Y538850D01*
X1509825Y539142D01*
X1509533Y539350D01*
X1509242Y539433D01*
X1508867D01*
G01X1509242D02*
X1509492Y539558D01*
X1509700Y539767D01*
X1509783Y540017D01*
X1509700Y540267D01*
X1509492Y540475D01*
X1509117Y540600D01*
X1508742Y540558D01*
X1508367Y540392D01*
G01X1510967Y538100D02*
Y540600D01*
X1512050Y538517D01*
X1513133Y540600D01*
Y538100D01*
G01X1514358Y539142D02*
X1514650Y539433D01*
X1514900Y539600D01*
X1515233Y539683D01*
X1515525Y539600D01*
X1515733Y539433D01*
X1515900Y539183D01*
X1515942Y538892D01*
X1515900Y538642D01*
X1515733Y538392D01*
X1515483Y538183D01*
X1515192Y538100D01*
X1514858Y538183D01*
X1514567Y538433D01*
X1514400Y538808D01*
X1514358Y539225D01*
X1514442Y539767D01*
X1514567Y540058D01*
X1514775Y540350D01*
X1515067Y540558D01*
X1515358Y540600D01*
X1515650Y540517D01*
X1515858Y540308D01*
G01X1521313Y536572D02*
X1521188Y536322D01*
X1521105Y536030D01*
Y535697D01*
X1521230Y535322D01*
X1521438Y535030D01*
X1521688Y534822D01*
X1522105Y534655D01*
X1522480Y534613D01*
X1522855Y534697D01*
X1523105Y534822D01*
X1523355Y535072D01*
X1523522Y535363D01*
X1523605Y535655D01*
Y535947D01*
X1523522Y536238D01*
X1523397Y536488D01*
X1523230Y536697D01*
G01X1523605Y538672D02*
X1523063Y538755D01*
X1522605Y538880D01*
X1522188Y539047D01*
X1521730Y539255D01*
X1521105Y539588D01*
Y537922D01*
G01X1522272Y542188D02*
X1522147Y542355D01*
X1521938Y542480D01*
X1521647Y542563D01*
X1521397Y542480D01*
X1521230Y542313D01*
X1521105Y542022D01*
Y540897D01*
X1523605D01*
Y542272D01*
X1523438Y542563D01*
X1523188Y542730D01*
X1522897Y542813D01*
X1522605Y542730D01*
X1522355Y542480D01*
X1522272Y542188D01*
Y540897D01*
G01X1523605Y544955D02*
X1521105D01*
X1521605Y544455D01*
G01X1523605D02*
Y545455D01*
G01Y548055D02*
X1523563Y548347D01*
X1523438Y548680D01*
X1523230Y548888D01*
X1522938Y548972D01*
X1522647Y548888D01*
X1522397Y548638D01*
X1522272Y548263D01*
Y547847D01*
X1522188Y547597D01*
X1521980Y547388D01*
X1521688Y547305D01*
X1521397Y547430D01*
X1521188Y547722D01*
X1521105Y548055D01*
X1521188Y548388D01*
X1521397Y548680D01*
X1521688Y548805D01*
X1521980Y548722D01*
X1522188Y548513D01*
X1522272Y548263D01*
Y547847D01*
X1522397Y547472D01*
X1522647Y547222D01*
X1522938Y547138D01*
X1523230Y547222D01*
X1523438Y547430D01*
X1523563Y547763D01*
X1523605Y548055D01*
G01X1517412Y536243D02*
X1517287Y535993D01*
X1517204Y535701D01*
Y535368D01*
X1517329Y534993D01*
X1517537Y534701D01*
X1517787Y534493D01*
X1518204Y534326D01*
X1518579Y534284D01*
X1518954Y534368D01*
X1519204Y534493D01*
X1519454Y534743D01*
X1519621Y535034D01*
X1519704Y535326D01*
Y535618D01*
X1519621Y535909D01*
X1519496Y536159D01*
X1519329Y536368D01*
G01X1519704Y538343D02*
X1519162Y538426D01*
X1518704Y538551D01*
X1518287Y538718D01*
X1517829Y538926D01*
X1517204Y539259D01*
Y537593D01*
G01X1518371Y541859D02*
X1518246Y542026D01*
X1518037Y542151D01*
X1517746Y542234D01*
X1517496Y542151D01*
X1517329Y541984D01*
X1517204Y541693D01*
Y540568D01*
X1519704D01*
Y541943D01*
X1519537Y542234D01*
X1519287Y542401D01*
X1518996Y542484D01*
X1518704Y542401D01*
X1518454Y542151D01*
X1518371Y541859D01*
Y540568D01*
G01X1519704Y544626D02*
X1517204D01*
X1517704Y544126D01*
G01X1519704D02*
Y545126D01*
G01X1519329Y546809D02*
X1519537Y547059D01*
X1519662Y547351D01*
X1519704Y547726D01*
X1519621Y548101D01*
X1519454Y548393D01*
X1519162Y548601D01*
X1518829Y548643D01*
X1518496Y548559D01*
X1518287Y548351D01*
X1518121Y548059D01*
X1518079Y547768D01*
X1518121Y547476D01*
X1518287Y547101D01*
X1517204Y547226D01*
Y548351D01*
G01X1495842Y576967D02*
X1495717Y576717D01*
X1495634Y576425D01*
Y576092D01*
X1495759Y575717D01*
X1495967Y575425D01*
X1496217Y575217D01*
X1496634Y575050D01*
X1497009Y575008D01*
X1497384Y575092D01*
X1497634Y575217D01*
X1497884Y575467D01*
X1498051Y575758D01*
X1498134Y576050D01*
Y576342D01*
X1498051Y576633D01*
X1497926Y576883D01*
X1497759Y577092D01*
G01X1495634Y579150D02*
X1498134D01*
G01X1495634Y578192D02*
Y580108D01*
G01X1497092Y581458D02*
X1496801Y581750D01*
X1496634Y582000D01*
X1496551Y582333D01*
X1496634Y582625D01*
X1496801Y582833D01*
X1497051Y583000D01*
X1497342Y583042D01*
X1497592Y583000D01*
X1497842Y582833D01*
X1498051Y582583D01*
X1498134Y582292D01*
X1498051Y581958D01*
X1497801Y581667D01*
X1497426Y581500D01*
X1497009Y581458D01*
X1496467Y581542D01*
X1496176Y581667D01*
X1495884Y581875D01*
X1495676Y582167D01*
X1495634Y582458D01*
X1495717Y582750D01*
X1495926Y582958D01*
G01X1498134Y585350D02*
X1498092Y585642D01*
X1497967Y585975D01*
X1497759Y586183D01*
X1497467Y586267D01*
X1497176Y586183D01*
X1496926Y585933D01*
X1496801Y585558D01*
Y585142D01*
X1496717Y584892D01*
X1496509Y584683D01*
X1496217Y584600D01*
X1495926Y584725D01*
X1495717Y585017D01*
X1495634Y585350D01*
X1495717Y585683D01*
X1495926Y585975D01*
X1496217Y586100D01*
X1496509Y586017D01*
X1496717Y585808D01*
X1496801Y585558D01*
Y585142D01*
X1496926Y584767D01*
X1497176Y584517D01*
X1497467Y584433D01*
X1497759Y584517D01*
X1497967Y584725D01*
X1498092Y585058D01*
X1498134Y585350D01*
G01X1501834Y566017D02*
X1504334D01*
Y567683D01*
G01Y569867D02*
X1503792Y569950D01*
X1503334Y570075D01*
X1502917Y570242D01*
X1502459Y570450D01*
X1501834Y570783D01*
Y569117D01*
G01X1504334Y572008D02*
X1501834Y573050D01*
X1504334Y574092D01*
G01X1503459Y573717D02*
Y572383D01*
G01X1504334Y576650D02*
X1501834D01*
X1503626Y575108D01*
Y577192D01*
G01X1546650Y570516D02*
Y564468D01*
X1509250D01*
Y570516D01*
G01Y583616D02*
Y589664D01*
G01X1475617Y545366D02*
Y542866D01*
X1477283D01*
G01X1479467D02*
X1479550Y543408D01*
X1479675Y543866D01*
X1479842Y544283D01*
X1480050Y544741D01*
X1480383Y545366D01*
X1478717D01*
G01X1481608Y542866D02*
X1482650Y545366D01*
X1483692Y542866D01*
G01X1483317Y543741D02*
X1481983D01*
G01X1484958Y544949D02*
X1485208Y545199D01*
X1485500Y545324D01*
X1485833Y545366D01*
X1486250Y545283D01*
X1486542Y545074D01*
X1486625Y544824D01*
X1486583Y544574D01*
X1486417Y544366D01*
X1485583Y543949D01*
X1485208Y543658D01*
X1484958Y543241D01*
X1484875Y542866D01*
X1486625D01*
G01X1475250Y549250D02*
X1469202D01*
Y586650D01*
X1475250D01*
G01X1488350D02*
X1494398D01*
G01D02*
Y549250D01*
X1488350D01*
G01X1471257Y589600D02*
X1475400D01*
G01X1488600Y589500D02*
X1494233D01*
Y602372D01*
X1504800D01*
Y590600D01*
X1543300D01*
G01X1498134Y588617D02*
X1495634D01*
Y589658D01*
X1495759Y589992D01*
X1495926Y590200D01*
X1496259Y590283D01*
X1496592Y590200D01*
X1496801Y589950D01*
X1496926Y589658D01*
Y588617D01*
G01Y589658D02*
X1498134Y590283D01*
G01X1495634Y592550D02*
X1498134D01*
G01X1495634Y591592D02*
Y593508D01*
G01X1498134Y596150D02*
X1495634D01*
X1497426Y594608D01*
Y596692D01*
G01X1497759Y597833D02*
X1497967Y598083D01*
X1498092Y598375D01*
X1498134Y598750D01*
X1498051Y599125D01*
X1497884Y599417D01*
X1497592Y599625D01*
X1497259Y599667D01*
X1496926Y599583D01*
X1496717Y599375D01*
X1496551Y599083D01*
X1496509Y598792D01*
X1496551Y598500D01*
X1496717Y598125D01*
X1495634Y598250D01*
Y599375D01*
G01X1469912Y590232D02*
Y617532D01*
X1493462D01*
Y590232D01*
X1469912D01*
G01X1505450Y591500D02*
Y618800D01*
X1529000D01*
Y591500D01*
X1505450D01*
G01X1509250Y589664D02*
X1546650D01*
Y583616D01*
G01X1543239Y639878D02*
X1510539D01*
Y658578D01*
X1543239D01*
Y639878D01*
G01X1531600Y4900D02*
X1535200D01*
G01X1538300D02*
X1571436D01*
Y7698D01*
X1580217D01*
Y7150D01*
G01X1580635Y-2690D02*
X1579320D01*
Y-4939D01*
G01X1580242Y3792D02*
X1580241D01*
Y1355D01*
G01X1544694Y8575D02*
X1544924Y8885D01*
X1545192Y9040D01*
X1545499Y9092D01*
X1545882Y8989D01*
X1546150Y8730D01*
X1546227Y8420D01*
X1546189Y8110D01*
X1546035Y7852D01*
X1545269Y7335D01*
X1544924Y6974D01*
X1544694Y6457D01*
X1544617Y5992D01*
X1546227D01*
G01X1548522Y9092D02*
X1548215Y8989D01*
X1547985Y8730D01*
X1547832Y8420D01*
X1547717Y8007D01*
X1547679Y7542D01*
X1547717Y7077D01*
X1547832Y6664D01*
X1547985Y6354D01*
X1548215Y6095D01*
X1548522Y5992D01*
X1548829Y6095D01*
X1549059Y6354D01*
X1549212Y6664D01*
X1549327Y7077D01*
X1549365Y7542D01*
X1549327Y8007D01*
X1549212Y8420D01*
X1549059Y8730D01*
X1548829Y8989D01*
X1548522Y9092D01*
G01X1551622D02*
X1551315Y8989D01*
X1551085Y8730D01*
X1550932Y8420D01*
X1550817Y8007D01*
X1550779Y7542D01*
X1550817Y7077D01*
X1550932Y6664D01*
X1551085Y6354D01*
X1551315Y6095D01*
X1551622Y5992D01*
X1551929Y6095D01*
X1552159Y6354D01*
X1552312Y6664D01*
X1552427Y7077D01*
X1552465Y7542D01*
X1552427Y8007D01*
X1552312Y8420D01*
X1552159Y8730D01*
X1551929Y8989D01*
X1551622Y9092D01*
G01X1580860Y-9430D02*
X1581128Y-9378D01*
X1581435Y-9223D01*
X1581627Y-8965D01*
X1581703Y-8603D01*
X1581627Y-8242D01*
X1581397Y-7932D01*
X1581052Y-7777D01*
X1580668D01*
X1580438Y-7673D01*
X1580247Y-7415D01*
X1580170Y-7053D01*
X1580285Y-6692D01*
X1580553Y-6433D01*
X1580860Y-6330D01*
X1581167Y-6433D01*
X1581435Y-6692D01*
X1581550Y-7053D01*
X1581473Y-7415D01*
X1581282Y-7673D01*
X1581052Y-7777D01*
X1580668D01*
X1580323Y-7932D01*
X1580093Y-8242D01*
X1580017Y-8603D01*
X1580093Y-8965D01*
X1580285Y-9223D01*
X1580592Y-9378D01*
X1580860Y-9430D01*
G01X1575850Y48850D02*
X1578950D01*
G01X1575850Y47968D02*
Y49732D01*
G01X1578950Y51183D02*
X1575850D01*
Y52142D01*
X1576005Y52448D01*
X1576212Y52640D01*
X1576625Y52717D01*
X1577038Y52640D01*
X1577297Y52410D01*
X1577452Y52142D01*
Y51183D01*
G01Y52142D02*
X1578950Y52717D01*
G01X1578537Y54245D02*
X1578795Y54552D01*
X1578950Y54897D01*
Y55203D01*
X1578795Y55510D01*
X1578537Y55740D01*
X1578175Y55855D01*
X1577813Y55778D01*
X1577503Y55587D01*
X1577297Y55242D01*
X1577193Y54782D01*
X1576987Y54513D01*
X1576625Y54398D01*
X1576263Y54475D01*
X1576005Y54667D01*
X1575850Y54935D01*
Y55203D01*
X1575953Y55472D01*
X1576212Y55702D01*
G01X1575850Y58150D02*
X1578950D01*
G01X1575850Y57268D02*
Y59032D01*
G01X1584634Y48433D02*
X1581534D01*
Y49353D01*
X1581689Y49660D01*
X1582051Y49890D01*
X1582464Y49967D01*
X1582877Y49890D01*
X1583187Y49698D01*
X1583342Y49353D01*
Y48433D01*
G01X1583084Y52530D02*
Y53297D01*
X1584014D01*
X1584324Y53067D01*
X1584531Y52798D01*
X1584634Y52415D01*
X1584531Y52032D01*
X1584324Y51763D01*
X1584014Y51533D01*
X1583652Y51380D01*
X1583239Y51303D01*
X1582877D01*
X1582567Y51380D01*
X1582206Y51533D01*
X1581896Y51763D01*
X1581689Y51993D01*
X1581534Y52300D01*
Y52568D01*
X1581637Y52875D01*
X1581844Y53105D01*
G01X1584634Y54557D02*
X1581534D01*
Y55323D01*
X1581689Y55630D01*
X1581896Y55860D01*
X1582206Y56052D01*
X1582567Y56205D01*
X1583084Y56243D01*
X1583601Y56205D01*
X1583962Y56052D01*
X1584272Y55860D01*
X1584479Y55630D01*
X1584634Y55323D01*
Y54557D01*
G01X1585667Y57350D02*
Y59650D01*
G01X1584014Y60757D02*
X1584376Y60987D01*
X1584582Y61293D01*
X1584634Y61638D01*
X1584582Y61945D01*
X1584324Y62252D01*
X1584014Y62443D01*
X1583704Y62482D01*
X1583342Y62405D01*
X1583084Y62137D01*
X1582981Y61868D01*
Y61523D01*
G01Y61868D02*
X1582826Y62098D01*
X1582567Y62290D01*
X1582257Y62367D01*
X1581947Y62290D01*
X1581689Y62098D01*
X1581534Y61753D01*
X1581586Y61408D01*
X1581792Y61063D01*
G01X1581534Y63742D02*
X1584634Y64700D01*
X1581534Y65658D01*
G01X1584014Y66957D02*
X1584376Y67187D01*
X1584582Y67493D01*
X1584634Y67838D01*
X1584582Y68145D01*
X1584324Y68452D01*
X1584014Y68643D01*
X1583704Y68682D01*
X1583342Y68605D01*
X1583084Y68337D01*
X1582981Y68068D01*
Y67723D01*
G01Y68068D02*
X1582826Y68298D01*
X1582567Y68490D01*
X1582257Y68567D01*
X1581947Y68490D01*
X1581689Y68298D01*
X1581534Y67953D01*
X1581586Y67608D01*
X1581792Y67263D01*
G01X1585667Y69750D02*
Y72050D01*
G01X1584221Y73195D02*
X1584479Y73502D01*
X1584634Y73847D01*
Y74153D01*
X1584479Y74460D01*
X1584221Y74690D01*
X1583859Y74805D01*
X1583497Y74728D01*
X1583187Y74537D01*
X1582981Y74192D01*
X1582877Y73732D01*
X1582671Y73463D01*
X1582309Y73348D01*
X1581947Y73425D01*
X1581689Y73617D01*
X1581534Y73885D01*
Y74153D01*
X1581637Y74422D01*
X1581896Y74652D01*
G01X1581534Y77100D02*
X1584634D01*
G01X1581534Y76218D02*
Y77982D01*
G01X1582981Y80507D02*
X1582826Y80660D01*
X1582567Y80775D01*
X1582206Y80852D01*
X1581896Y80775D01*
X1581689Y80622D01*
X1581534Y80353D01*
Y79318D01*
X1584634D01*
Y80583D01*
X1584427Y80852D01*
X1584117Y81005D01*
X1583756Y81082D01*
X1583394Y81005D01*
X1583084Y80775D01*
X1582981Y80507D01*
Y79318D01*
G01X1587750Y49200D02*
X1590850D01*
G01X1587750Y48318D02*
Y50082D01*
G01X1590850Y51303D02*
X1587750D01*
X1590333Y52300D01*
X1587750Y53297D01*
X1590850D01*
G01X1590437Y54595D02*
X1590695Y54902D01*
X1590850Y55247D01*
Y55553D01*
X1590695Y55860D01*
X1590437Y56090D01*
X1590075Y56205D01*
X1589713Y56128D01*
X1589403Y55937D01*
X1589197Y55592D01*
X1589093Y55132D01*
X1588887Y54863D01*
X1588525Y54748D01*
X1588163Y54825D01*
X1587905Y55017D01*
X1587750Y55285D01*
Y55553D01*
X1587853Y55822D01*
X1588112Y56052D01*
G01X1563950Y48900D02*
X1567050D01*
G01X1563950Y48018D02*
Y49782D01*
G01X1567050Y51157D02*
X1563950D01*
Y51923D01*
X1564105Y52230D01*
X1564312Y52460D01*
X1564622Y52652D01*
X1564983Y52805D01*
X1565500Y52843D01*
X1566017Y52805D01*
X1566378Y52652D01*
X1566688Y52460D01*
X1566895Y52230D01*
X1567050Y51923D01*
Y51157D01*
G01Y55100D02*
X1566998Y54793D01*
X1566792Y54525D01*
X1566482Y54295D01*
X1566120Y54142D01*
X1565707Y54065D01*
X1565293D01*
X1564880Y54142D01*
X1564518Y54295D01*
X1564208Y54525D01*
X1564002Y54793D01*
X1563950Y55100D01*
X1564002Y55407D01*
X1564208Y55675D01*
X1564518Y55905D01*
X1564880Y56058D01*
X1565293Y56135D01*
X1565707D01*
X1566120Y56058D01*
X1566482Y55905D01*
X1566792Y55675D01*
X1566998Y55407D01*
X1567050Y55100D01*
G01X1569950Y49000D02*
X1573050D01*
G01X1569950Y48118D02*
Y49882D01*
G01X1573050Y51257D02*
X1569950D01*
Y52023D01*
X1570105Y52330D01*
X1570312Y52560D01*
X1570622Y52752D01*
X1570983Y52905D01*
X1571500Y52943D01*
X1572017Y52905D01*
X1572378Y52752D01*
X1572688Y52560D01*
X1572895Y52330D01*
X1573050Y52023D01*
Y51257D01*
G01X1569950Y54740D02*
Y55660D01*
G01Y55200D02*
X1573050D01*
G01Y54740D02*
Y55660D01*
G01X1551108Y96238D02*
X1554441Y103238D01*
X1557774Y96238D01*
G01X1556574Y98688D02*
X1552308D01*
G01X1564108Y99971D02*
X1564641Y100321D01*
X1565041Y100905D01*
X1565308Y101721D01*
X1565041Y102421D01*
X1564508Y102888D01*
X1563574Y103238D01*
X1559974D01*
Y96238D01*
X1564374D01*
X1565308Y96705D01*
X1565841Y97405D01*
X1566108Y98221D01*
X1565841Y99038D01*
X1565041Y99738D01*
X1564108Y99971D01*
X1559974D01*
G01X1547862Y88214D02*
X1544762D01*
X1547345Y89211D01*
X1544762Y90208D01*
X1547862D01*
G01X1547965Y92311D02*
X1547914Y92234D01*
X1547810D01*
X1547759Y92311D01*
X1547810Y92388D01*
X1547914D01*
X1547965Y92311D01*
G01X1545279Y94683D02*
X1544969Y94913D01*
X1544814Y95181D01*
X1544762Y95488D01*
X1544865Y95871D01*
X1545124Y96139D01*
X1545434Y96216D01*
X1545744Y96178D01*
X1546002Y96024D01*
X1546519Y95258D01*
X1546880Y94913D01*
X1547397Y94683D01*
X1547862Y94606D01*
Y96216D01*
G01X1547965Y98511D02*
X1547914Y98434D01*
X1547810D01*
X1547759Y98511D01*
X1547810Y98588D01*
X1547914D01*
X1547965Y98511D01*
G01X1546570D02*
X1546519Y98434D01*
X1546415D01*
X1546364Y98511D01*
X1546415Y98588D01*
X1546519D01*
X1546570Y98511D01*
G01X1547862Y104711D02*
X1547810Y104979D01*
X1547655Y105286D01*
X1547397Y105478D01*
X1547035Y105554D01*
X1546674Y105478D01*
X1546364Y105248D01*
X1546209Y104903D01*
Y104519D01*
X1546105Y104289D01*
X1545847Y104098D01*
X1545485Y104021D01*
X1545124Y104136D01*
X1544865Y104404D01*
X1544762Y104711D01*
X1544865Y105018D01*
X1545124Y105286D01*
X1545485Y105401D01*
X1545847Y105324D01*
X1546105Y105133D01*
X1546209Y104903D01*
Y104519D01*
X1546364Y104174D01*
X1546674Y103944D01*
X1547035Y103868D01*
X1547397Y103944D01*
X1547655Y104136D01*
X1547810Y104443D01*
X1547862Y104711D01*
G01X1544762Y107811D02*
X1544865Y107504D01*
X1545124Y107274D01*
X1545434Y107121D01*
X1545847Y107006D01*
X1546312Y106968D01*
X1546777Y107006D01*
X1547190Y107121D01*
X1547500Y107274D01*
X1547759Y107504D01*
X1547862Y107811D01*
X1547759Y108118D01*
X1547500Y108348D01*
X1547190Y108501D01*
X1546777Y108616D01*
X1546312Y108654D01*
X1545847Y108616D01*
X1545434Y108501D01*
X1545124Y108348D01*
X1544865Y108118D01*
X1544762Y107811D01*
G01X1547862Y109914D02*
X1544762D01*
X1547345Y110911D01*
X1544762Y111908D01*
X1547862D01*
G01Y113014D02*
X1544762D01*
X1547345Y114011D01*
X1544762Y115008D01*
X1547862D01*
G01X1548895Y121361D02*
X1545795Y119444D01*
X1545279D01*
X1544762Y119828D01*
Y120211D01*
X1545279Y120594D01*
X1545795D01*
X1546312Y120211D01*
X1546829Y119444D01*
X1547345Y119061D01*
X1548379D01*
X1548895Y119444D01*
Y120594D01*
X1547862Y121361D01*
G01Y123311D02*
X1544762D01*
X1545382Y122851D01*
G01X1547862D02*
Y123771D01*
G01Y126411D02*
X1544762D01*
X1545382Y125951D01*
G01X1547862D02*
Y126871D01*
G01X1544762Y129511D02*
X1544865Y129204D01*
X1545124Y128974D01*
X1545434Y128821D01*
X1545847Y128706D01*
X1546312Y128668D01*
X1546777Y128706D01*
X1547190Y128821D01*
X1547500Y128974D01*
X1547759Y129204D01*
X1547862Y129511D01*
X1547759Y129818D01*
X1547500Y130048D01*
X1547190Y130201D01*
X1546777Y130316D01*
X1546312Y130354D01*
X1545847Y130316D01*
X1545434Y130201D01*
X1545124Y130048D01*
X1544865Y129818D01*
X1544762Y129511D01*
G01X1547862Y131614D02*
X1544762D01*
X1547345Y132611D01*
X1544762Y133608D01*
X1547862D01*
G01Y134714D02*
X1544762D01*
X1547345Y135711D01*
X1544762Y136708D01*
X1547862D01*
G01X1548080Y48583D02*
X1548390Y48775D01*
X1548597Y49005D01*
X1548700Y49273D01*
X1548597Y49580D01*
X1548390Y49810D01*
X1548080Y50040D01*
X1547667Y50117D01*
X1545600D01*
G01X1548700Y52373D02*
X1548028Y52450D01*
X1547460Y52565D01*
X1546943Y52718D01*
X1546375Y52910D01*
X1545600Y53217D01*
Y51683D01*
G01X1547150Y55780D02*
Y56547D01*
X1548080D01*
X1548390Y56317D01*
X1548597Y56048D01*
X1548700Y55665D01*
X1548597Y55282D01*
X1548390Y55013D01*
X1548080Y54783D01*
X1547718Y54630D01*
X1547305Y54553D01*
X1546943D01*
X1546633Y54630D01*
X1546272Y54783D01*
X1545962Y55013D01*
X1545755Y55243D01*
X1545600Y55550D01*
Y55818D01*
X1545703Y56125D01*
X1545910Y56355D01*
G01X1546117Y57922D02*
X1545807Y58152D01*
X1545652Y58420D01*
X1545600Y58727D01*
X1545703Y59110D01*
X1545962Y59378D01*
X1546272Y59455D01*
X1546582Y59417D01*
X1546840Y59263D01*
X1547357Y58497D01*
X1547718Y58152D01*
X1548235Y57922D01*
X1548700Y57845D01*
Y59455D01*
G01X1560734Y48333D02*
X1557634D01*
Y49253D01*
X1557789Y49560D01*
X1558151Y49790D01*
X1558564Y49867D01*
X1558977Y49790D01*
X1559287Y49598D01*
X1559442Y49253D01*
Y48333D01*
G01X1560114Y51357D02*
X1560476Y51587D01*
X1560682Y51893D01*
X1560734Y52238D01*
X1560682Y52545D01*
X1560424Y52852D01*
X1560114Y53043D01*
X1559804Y53082D01*
X1559442Y53005D01*
X1559184Y52737D01*
X1559081Y52468D01*
Y52123D01*
G01Y52468D02*
X1558926Y52698D01*
X1558667Y52890D01*
X1558357Y52967D01*
X1558047Y52890D01*
X1557789Y52698D01*
X1557634Y52353D01*
X1557686Y52008D01*
X1557892Y51663D01*
G01X1557634Y54342D02*
X1560734Y55300D01*
X1557634Y56258D01*
G01X1560114Y57557D02*
X1560476Y57787D01*
X1560682Y58093D01*
X1560734Y58438D01*
X1560682Y58745D01*
X1560424Y59052D01*
X1560114Y59243D01*
X1559804Y59282D01*
X1559442Y59205D01*
X1559184Y58937D01*
X1559081Y58668D01*
Y58323D01*
G01Y58668D02*
X1558926Y58898D01*
X1558667Y59090D01*
X1558357Y59167D01*
X1558047Y59090D01*
X1557789Y58898D01*
X1557634Y58553D01*
X1557686Y58208D01*
X1557892Y57863D01*
G01X1561767Y60350D02*
Y62650D01*
G01X1560321Y63795D02*
X1560579Y64102D01*
X1560734Y64447D01*
Y64753D01*
X1560579Y65060D01*
X1560321Y65290D01*
X1559959Y65405D01*
X1559597Y65328D01*
X1559287Y65137D01*
X1559081Y64792D01*
X1558977Y64332D01*
X1558771Y64063D01*
X1558409Y63948D01*
X1558047Y64025D01*
X1557789Y64217D01*
X1557634Y64485D01*
Y64753D01*
X1557737Y65022D01*
X1557996Y65252D01*
G01X1557634Y67700D02*
X1560734D01*
G01X1557634Y66818D02*
Y68582D01*
G01X1559081Y71107D02*
X1558926Y71260D01*
X1558667Y71375D01*
X1558306Y71452D01*
X1557996Y71375D01*
X1557789Y71222D01*
X1557634Y70953D01*
Y69918D01*
X1560734D01*
Y71183D01*
X1560527Y71452D01*
X1560217Y71605D01*
X1559856Y71682D01*
X1559494Y71605D01*
X1559184Y71375D01*
X1559081Y71107D01*
Y69918D01*
G01X1560734Y73900D02*
X1559339D01*
X1557634Y73133D01*
G01Y74667D02*
X1559339Y73900D01*
G01X1551858Y50593D02*
X1551703Y50363D01*
X1551600Y50095D01*
Y49788D01*
X1551755Y49443D01*
X1552013Y49175D01*
X1552323Y48983D01*
X1552840Y48830D01*
X1553305Y48792D01*
X1553770Y48868D01*
X1554080Y48983D01*
X1554390Y49213D01*
X1554597Y49482D01*
X1554700Y49750D01*
Y50018D01*
X1554597Y50287D01*
X1554442Y50517D01*
X1554235Y50708D01*
G01X1554700Y52083D02*
X1551600D01*
Y53003D01*
X1551755Y53310D01*
X1552117Y53540D01*
X1552530Y53617D01*
X1552943Y53540D01*
X1553253Y53348D01*
X1553408Y53003D01*
Y52083D01*
G01X1551600Y55183D02*
X1554700D01*
Y56717D01*
G01Y58207D02*
X1551600D01*
Y58973D01*
X1551755Y59280D01*
X1551962Y59510D01*
X1552272Y59702D01*
X1552633Y59855D01*
X1553150Y59893D01*
X1553667Y59855D01*
X1554028Y59702D01*
X1554338Y59510D01*
X1554545Y59280D01*
X1554700Y58973D01*
Y58207D01*
G01Y64483D02*
X1551600D01*
Y65403D01*
X1551755Y65710D01*
X1552117Y65940D01*
X1552530Y66017D01*
X1552943Y65940D01*
X1553253Y65748D01*
X1553408Y65403D01*
Y64483D01*
G01X1554700Y67583D02*
X1551600D01*
Y68542D01*
X1551755Y68848D01*
X1551962Y69040D01*
X1552375Y69117D01*
X1552788Y69040D01*
X1553047Y68810D01*
X1553202Y68542D01*
Y67583D01*
G01Y68542D02*
X1554700Y69117D01*
G01Y71450D02*
X1554648Y71143D01*
X1554442Y70875D01*
X1554132Y70645D01*
X1553770Y70492D01*
X1553357Y70415D01*
X1552943D01*
X1552530Y70492D01*
X1552168Y70645D01*
X1551858Y70875D01*
X1551652Y71143D01*
X1551600Y71450D01*
X1551652Y71757D01*
X1551858Y72025D01*
X1552168Y72255D01*
X1552530Y72408D01*
X1552943Y72485D01*
X1553357D01*
X1553770Y72408D01*
X1554132Y72255D01*
X1554442Y72025D01*
X1554648Y71757D01*
X1554700Y71450D01*
G01X1553150Y74780D02*
Y75547D01*
X1554080D01*
X1554390Y75317D01*
X1554597Y75048D01*
X1554700Y74665D01*
X1554597Y74282D01*
X1554390Y74013D01*
X1554080Y73783D01*
X1553718Y73630D01*
X1553305Y73553D01*
X1552943D01*
X1552633Y73630D01*
X1552272Y73783D01*
X1551962Y74013D01*
X1551755Y74243D01*
X1551600Y74550D01*
Y74818D01*
X1551703Y75125D01*
X1551910Y75355D01*
G01X1554700Y79945D02*
X1551600D01*
G01Y81555D02*
X1554700D01*
G01X1553150D02*
Y79945D01*
G01X1554700Y83007D02*
X1551600D01*
Y83773D01*
X1551755Y84080D01*
X1551962Y84310D01*
X1552272Y84502D01*
X1552633Y84655D01*
X1553150Y84693D01*
X1553667Y84655D01*
X1554028Y84502D01*
X1554338Y84310D01*
X1554545Y84080D01*
X1554700Y83773D01*
Y83007D01*
G01Y86183D02*
X1551600D01*
Y87142D01*
X1551755Y87448D01*
X1551962Y87640D01*
X1552375Y87717D01*
X1552788Y87640D01*
X1553047Y87410D01*
X1553202Y87142D01*
Y86183D01*
G01Y87142D02*
X1554700Y87717D01*
G01X1586500Y70100D02*
Y59400D01*
G01X1580500Y66300D02*
Y82900D01*
X1586500D01*
Y73600D01*
G01X1568500Y66300D02*
X1574500D01*
G01X1592500Y46800D02*
X1598500D01*
Y59400D01*
X1592500D01*
Y46800D01*
X1586500D01*
G01X1580500D02*
X1586500D01*
Y59400D01*
X1592500D01*
G01X1568500Y46800D02*
X1574500D01*
Y66300D01*
X1580500D01*
Y46800D01*
X1574500D01*
G01X1556500Y74768D02*
Y78600D01*
X1562500D01*
Y66300D01*
G01Y46800D02*
X1568500D01*
Y66300D01*
X1562500D01*
Y46800D01*
X1556500D01*
G01Y78600D02*
Y88700D01*
X1550500D01*
Y46800D01*
X1556500D01*
Y70945D01*
G01X1584400Y38700D02*
X1581500D01*
G01X1574700D02*
X1572200D01*
G01X1565700D02*
X1562500D01*
G01X1555700D02*
X1553500D01*
G01X1624400Y40200D02*
Y59400D01*
X1605400D01*
Y46000D01*
X1546500D01*
Y38700D01*
X1546800D01*
G01X1567738Y104600D02*
X1549819D01*
Y94500D01*
X1559904D01*
G01X1573572D02*
X1575700D01*
Y85400D01*
X1600700D01*
Y74100D01*
G01X1538385Y41193D02*
Y44293D01*
X1537925Y43673D01*
G01Y41193D02*
X1538845D01*
G01X1540833Y41555D02*
X1541102Y41296D01*
X1541408Y41193D01*
X1541715Y41296D01*
X1541983Y41606D01*
X1542175Y42071D01*
X1542252Y42536D01*
Y43105D01*
X1542175Y43570D01*
X1541983Y43983D01*
X1541753Y44190D01*
X1541485Y44293D01*
X1541178Y44190D01*
X1540948Y43983D01*
X1540795Y43673D01*
X1540718Y43260D01*
X1540795Y42898D01*
X1540987Y42536D01*
X1541217Y42330D01*
X1541485Y42278D01*
X1541792Y42381D01*
X1542022Y42640D01*
X1542252Y43105D01*
G01X1543933Y41555D02*
X1544202Y41296D01*
X1544508Y41193D01*
X1544815Y41296D01*
X1545083Y41606D01*
X1545275Y42071D01*
X1545352Y42536D01*
Y43105D01*
X1545275Y43570D01*
X1545083Y43983D01*
X1544853Y44190D01*
X1544585Y44293D01*
X1544278Y44190D01*
X1544048Y43983D01*
X1543895Y43673D01*
X1543818Y43260D01*
X1543895Y42898D01*
X1544087Y42536D01*
X1544317Y42330D01*
X1544585Y42278D01*
X1544892Y42381D01*
X1545122Y42640D01*
X1545352Y43105D01*
G01X1575000Y104600D02*
X1571973D01*
G01X1588400D02*
X1589200D01*
Y96900D01*
X1614353D01*
G01X1578000Y104600D02*
X1578600D01*
G01X1583100D02*
X1584400D01*
G01X1551222Y146060D02*
Y148560D01*
X1552263D01*
X1552597Y148435D01*
X1552805Y148268D01*
X1552888Y147935D01*
X1552805Y147602D01*
X1552555Y147393D01*
X1552263Y147268D01*
X1551222D01*
G01X1552263D02*
X1552888Y146060D01*
G01X1554363Y147102D02*
X1554655Y147393D01*
X1554905Y147560D01*
X1555238Y147643D01*
X1555530Y147560D01*
X1555738Y147393D01*
X1555905Y147143D01*
X1555947Y146852D01*
X1555905Y146602D01*
X1555738Y146352D01*
X1555488Y146143D01*
X1555197Y146060D01*
X1554863Y146143D01*
X1554572Y146393D01*
X1554405Y146768D01*
X1554363Y147185D01*
X1554447Y147727D01*
X1554572Y148018D01*
X1554780Y148310D01*
X1555072Y148518D01*
X1555363Y148560D01*
X1555655Y148477D01*
X1555863Y148268D01*
G01X1557005Y148560D02*
X1557588Y146060D01*
X1558255Y148560D01*
X1558922Y146060D01*
X1559505Y148560D01*
G01X1561355Y146060D02*
Y148560D01*
X1560855Y148060D01*
G01Y146060D02*
X1561855D01*
G01X1564372D02*
X1564455Y146602D01*
X1564580Y147060D01*
X1564747Y147477D01*
X1564955Y147935D01*
X1565288Y148560D01*
X1563622D01*
G01X1551090Y141993D02*
Y144493D01*
X1552131D01*
X1552465Y144368D01*
X1552673Y144201D01*
X1552756Y143868D01*
X1552673Y143535D01*
X1552423Y143326D01*
X1552131Y143201D01*
X1551090D01*
G01X1552131D02*
X1552756Y141993D01*
G01X1554231Y143035D02*
X1554523Y143326D01*
X1554773Y143493D01*
X1555106Y143576D01*
X1555398Y143493D01*
X1555606Y143326D01*
X1555773Y143076D01*
X1555815Y142785D01*
X1555773Y142535D01*
X1555606Y142285D01*
X1555356Y142076D01*
X1555065Y141993D01*
X1554731Y142076D01*
X1554440Y142326D01*
X1554273Y142701D01*
X1554231Y143118D01*
X1554315Y143660D01*
X1554440Y143951D01*
X1554648Y144243D01*
X1554940Y144451D01*
X1555231Y144493D01*
X1555523Y144410D01*
X1555731Y144201D01*
G01X1556873Y144493D02*
X1557456Y141993D01*
X1558123Y144493D01*
X1558790Y141993D01*
X1559373Y144493D01*
G01X1561223Y141993D02*
Y144493D01*
X1560723Y143993D01*
G01Y141993D02*
X1561723D01*
G01X1564323D02*
X1564615Y142035D01*
X1564948Y142160D01*
X1565156Y142368D01*
X1565240Y142660D01*
X1565156Y142951D01*
X1564906Y143201D01*
X1564531Y143326D01*
X1564115D01*
X1563865Y143410D01*
X1563656Y143618D01*
X1563573Y143910D01*
X1563698Y144201D01*
X1563990Y144410D01*
X1564323Y144493D01*
X1564656Y144410D01*
X1564948Y144201D01*
X1565073Y143910D01*
X1564990Y143618D01*
X1564781Y143410D01*
X1564531Y143326D01*
X1564115D01*
X1563740Y143201D01*
X1563490Y142951D01*
X1563406Y142660D01*
X1563490Y142368D01*
X1563698Y142160D01*
X1564031Y142035D01*
X1564323Y141993D01*
G01X1553035Y150259D02*
Y152759D01*
X1554076D01*
X1554410Y152634D01*
X1554618Y152467D01*
X1554701Y152134D01*
X1554618Y151801D01*
X1554368Y151592D01*
X1554076Y151467D01*
X1553035D01*
G01X1554076D02*
X1554701Y150259D01*
G01X1556968D02*
Y152759D01*
X1556468Y152259D01*
G01Y150259D02*
X1557468D01*
G01X1559235Y152759D02*
Y150259D01*
X1560901D01*
G01X1563085D02*
X1563168Y150801D01*
X1563293Y151259D01*
X1563460Y151676D01*
X1563668Y152134D01*
X1564001Y152759D01*
X1562335D01*
G01X1550100Y151417D02*
X1547600D01*
Y152458D01*
X1547725Y152792D01*
X1547892Y153000D01*
X1548225Y153083D01*
X1548558Y153000D01*
X1548767Y152750D01*
X1548892Y152458D01*
Y151417D01*
G01Y152458D02*
X1550100Y153083D01*
G01X1548017Y154558D02*
X1547767Y154808D01*
X1547642Y155100D01*
X1547600Y155433D01*
X1547683Y155850D01*
X1547892Y156142D01*
X1548142Y156225D01*
X1548392Y156183D01*
X1548600Y156017D01*
X1549017Y155183D01*
X1549308Y154808D01*
X1549725Y154558D01*
X1550100Y154475D01*
Y156225D01*
G01X1549725Y157533D02*
X1549933Y157783D01*
X1550058Y158075D01*
X1550100Y158450D01*
X1550017Y158825D01*
X1549850Y159117D01*
X1549558Y159325D01*
X1549225Y159367D01*
X1548892Y159283D01*
X1548683Y159075D01*
X1548517Y158783D01*
X1548475Y158492D01*
X1548517Y158200D01*
X1548683Y157825D01*
X1547600Y157950D01*
Y159075D01*
G01Y160300D02*
X1550100Y160883D01*
X1547600Y161550D01*
X1550100Y162217D01*
X1547600Y162800D01*
G01X1550100Y164650D02*
X1547600D01*
X1548100Y164150D01*
G01X1550100D02*
Y165150D01*
G01Y167750D02*
X1550058Y168042D01*
X1549933Y168375D01*
X1549725Y168583D01*
X1549433Y168667D01*
X1549142Y168583D01*
X1548892Y168333D01*
X1548767Y167958D01*
Y167542D01*
X1548683Y167292D01*
X1548475Y167083D01*
X1548183Y167000D01*
X1547892Y167125D01*
X1547683Y167417D01*
X1547600Y167750D01*
X1547683Y168083D01*
X1547892Y168375D01*
X1548183Y168500D01*
X1548475Y168417D01*
X1548683Y168208D01*
X1548767Y167958D01*
Y167542D01*
X1548892Y167167D01*
X1549142Y166917D01*
X1549433Y166833D01*
X1549725Y166917D01*
X1549933Y167125D01*
X1550058Y167458D01*
X1550100Y167750D01*
G01X1548017Y170058D02*
X1547767Y170308D01*
X1547642Y170600D01*
X1547600Y170933D01*
X1547683Y171350D01*
X1547892Y171642D01*
X1548142Y171725D01*
X1548392Y171683D01*
X1548600Y171517D01*
X1549017Y170683D01*
X1549308Y170308D01*
X1549725Y170058D01*
X1550100Y169975D01*
Y171725D01*
G01X1551970Y128069D02*
Y130569D01*
X1553011D01*
X1553345Y130444D01*
X1553553Y130277D01*
X1553636Y129944D01*
X1553553Y129611D01*
X1553303Y129402D01*
X1553011Y129277D01*
X1551970D01*
G01X1553011D02*
X1553636Y128069D01*
G01X1555903D02*
X1556195Y128111D01*
X1556528Y128236D01*
X1556736Y128444D01*
X1556820Y128736D01*
X1556736Y129027D01*
X1556486Y129277D01*
X1556111Y129402D01*
X1555695D01*
X1555445Y129486D01*
X1555236Y129694D01*
X1555153Y129986D01*
X1555278Y130277D01*
X1555570Y130486D01*
X1555903Y130569D01*
X1556236Y130486D01*
X1556528Y130277D01*
X1556653Y129986D01*
X1556570Y129694D01*
X1556361Y129486D01*
X1556111Y129402D01*
X1555695D01*
X1555320Y129277D01*
X1555070Y129027D01*
X1554986Y128736D01*
X1555070Y128444D01*
X1555278Y128236D01*
X1555611Y128111D01*
X1555903Y128069D01*
G01X1559253Y129319D02*
X1560086D01*
Y128569D01*
X1559836Y128319D01*
X1559545Y128152D01*
X1559128Y128069D01*
X1558711Y128152D01*
X1558420Y128319D01*
X1558170Y128569D01*
X1558003Y128861D01*
X1557920Y129194D01*
Y129486D01*
X1558003Y129736D01*
X1558170Y130027D01*
X1558420Y130277D01*
X1558670Y130444D01*
X1559003Y130569D01*
X1559295D01*
X1559628Y130486D01*
X1559878Y130319D01*
G01X1561311Y129111D02*
X1561603Y129402D01*
X1561853Y129569D01*
X1562186Y129652D01*
X1562478Y129569D01*
X1562686Y129402D01*
X1562853Y129152D01*
X1562895Y128861D01*
X1562853Y128611D01*
X1562686Y128361D01*
X1562436Y128152D01*
X1562145Y128069D01*
X1561811Y128152D01*
X1561520Y128402D01*
X1561353Y128777D01*
X1561311Y129194D01*
X1561395Y129736D01*
X1561520Y130027D01*
X1561728Y130319D01*
X1562020Y130527D01*
X1562311Y130569D01*
X1562603Y130486D01*
X1562811Y130277D01*
G01X1562400Y109417D02*
X1559900D01*
Y110458D01*
X1560025Y110792D01*
X1560192Y111000D01*
X1560525Y111083D01*
X1560858Y111000D01*
X1561067Y110750D01*
X1561192Y110458D01*
Y109417D01*
G01Y110458D02*
X1562400Y111083D01*
G01X1560317Y112558D02*
X1560067Y112808D01*
X1559942Y113100D01*
X1559900Y113433D01*
X1559983Y113850D01*
X1560192Y114142D01*
X1560442Y114225D01*
X1560692Y114183D01*
X1560900Y114017D01*
X1561317Y113183D01*
X1561608Y112808D01*
X1562025Y112558D01*
X1562400Y112475D01*
Y114225D01*
G01X1562025Y115533D02*
X1562233Y115783D01*
X1562358Y116075D01*
X1562400Y116450D01*
X1562317Y116825D01*
X1562150Y117117D01*
X1561858Y117325D01*
X1561525Y117367D01*
X1561192Y117283D01*
X1560983Y117075D01*
X1560817Y116783D01*
X1560775Y116492D01*
X1560817Y116200D01*
X1560983Y115825D01*
X1559900Y115950D01*
Y117075D01*
G01Y118300D02*
X1562400Y118883D01*
X1559900Y119550D01*
X1562400Y120217D01*
X1559900Y120800D01*
G01X1562400Y122650D02*
X1562358Y122942D01*
X1562233Y123275D01*
X1562025Y123483D01*
X1561733Y123567D01*
X1561442Y123483D01*
X1561192Y123233D01*
X1561067Y122858D01*
Y122442D01*
X1560983Y122192D01*
X1560775Y121983D01*
X1560483Y121900D01*
X1560192Y122025D01*
X1559983Y122317D01*
X1559900Y122650D01*
X1559983Y122983D01*
X1560192Y123275D01*
X1560483Y123400D01*
X1560775Y123317D01*
X1560983Y123108D01*
X1561067Y122858D01*
Y122442D01*
X1561192Y122067D01*
X1561442Y121817D01*
X1561733Y121733D01*
X1562025Y121817D01*
X1562233Y122025D01*
X1562358Y122358D01*
X1562400Y122650D01*
G01Y125667D02*
X1561858Y125750D01*
X1561400Y125875D01*
X1560983Y126042D01*
X1560525Y126250D01*
X1559900Y126583D01*
Y124917D01*
G01X1552300Y106167D02*
X1549800D01*
Y107208D01*
X1549925Y107542D01*
X1550092Y107750D01*
X1550425Y107833D01*
X1550758Y107750D01*
X1550967Y107500D01*
X1551092Y107208D01*
Y106167D01*
G01Y107208D02*
X1552300Y107833D01*
G01X1550217Y109308D02*
X1549967Y109558D01*
X1549842Y109850D01*
X1549800Y110183D01*
X1549883Y110600D01*
X1550092Y110892D01*
X1550342Y110975D01*
X1550592Y110933D01*
X1550800Y110767D01*
X1551217Y109933D01*
X1551508Y109558D01*
X1551925Y109308D01*
X1552300Y109225D01*
Y110975D01*
G01X1551925Y112283D02*
X1552133Y112533D01*
X1552258Y112825D01*
X1552300Y113200D01*
X1552217Y113575D01*
X1552050Y113867D01*
X1551758Y114075D01*
X1551425Y114117D01*
X1551092Y114033D01*
X1550883Y113825D01*
X1550717Y113533D01*
X1550675Y113242D01*
X1550717Y112950D01*
X1550883Y112575D01*
X1549800Y112700D01*
Y113825D01*
G01Y115050D02*
X1552300Y115633D01*
X1549800Y116300D01*
X1552300Y116967D01*
X1549800Y117550D01*
G01X1552300Y119400D02*
X1549800D01*
X1550300Y118900D01*
G01X1552300D02*
Y119900D01*
G01Y123000D02*
X1549800D01*
X1551592Y121458D01*
Y123542D01*
G01X1552300Y125600D02*
X1552258Y125892D01*
X1552133Y126225D01*
X1551925Y126433D01*
X1551633Y126517D01*
X1551342Y126433D01*
X1551092Y126183D01*
X1550967Y125808D01*
Y125392D01*
X1550883Y125142D01*
X1550675Y124933D01*
X1550383Y124850D01*
X1550092Y124975D01*
X1549883Y125267D01*
X1549800Y125600D01*
X1549883Y125933D01*
X1550092Y126225D01*
X1550383Y126350D01*
X1550675Y126267D01*
X1550883Y126058D01*
X1550967Y125808D01*
Y125392D01*
X1551092Y125017D01*
X1551342Y124767D01*
X1551633Y124683D01*
X1551925Y124767D01*
X1552133Y124975D01*
X1552258Y125308D01*
X1552300Y125600D01*
G01X1566504Y107636D02*
X1564004D01*
Y108677D01*
X1564129Y109011D01*
X1564296Y109219D01*
X1564629Y109302D01*
X1564962Y109219D01*
X1565171Y108969D01*
X1565296Y108677D01*
Y107636D01*
G01Y108677D02*
X1566504Y109302D01*
G01X1564421Y110777D02*
X1564171Y111027D01*
X1564046Y111319D01*
X1564004Y111652D01*
X1564087Y112069D01*
X1564296Y112361D01*
X1564546Y112444D01*
X1564796Y112402D01*
X1565004Y112236D01*
X1565421Y111402D01*
X1565712Y111027D01*
X1566129Y110777D01*
X1566504Y110694D01*
Y112444D01*
G01X1566129Y113752D02*
X1566337Y114002D01*
X1566462Y114294D01*
X1566504Y114669D01*
X1566421Y115044D01*
X1566254Y115336D01*
X1565962Y115544D01*
X1565629Y115586D01*
X1565296Y115502D01*
X1565087Y115294D01*
X1564921Y115002D01*
X1564879Y114711D01*
X1564921Y114419D01*
X1565087Y114044D01*
X1564004Y114169D01*
Y115294D01*
G01Y116519D02*
X1566504Y117102D01*
X1564004Y117769D01*
X1566504Y118436D01*
X1564004Y119019D01*
G01X1566504Y120869D02*
X1564004D01*
X1564504Y120369D01*
G01X1566504D02*
Y121369D01*
G01X1564004Y123969D02*
X1564087Y123636D01*
X1564296Y123386D01*
X1564546Y123219D01*
X1564879Y123094D01*
X1565254Y123052D01*
X1565629Y123094D01*
X1565962Y123219D01*
X1566212Y123386D01*
X1566421Y123636D01*
X1566504Y123969D01*
X1566421Y124302D01*
X1566212Y124552D01*
X1565962Y124719D01*
X1565629Y124844D01*
X1565254Y124886D01*
X1564879Y124844D01*
X1564546Y124719D01*
X1564296Y124552D01*
X1564087Y124302D01*
X1564004Y123969D01*
G01X1566504Y127069D02*
X1566462Y127361D01*
X1566337Y127694D01*
X1566129Y127902D01*
X1565837Y127986D01*
X1565546Y127902D01*
X1565296Y127652D01*
X1565171Y127277D01*
Y126861D01*
X1565087Y126611D01*
X1564879Y126402D01*
X1564587Y126319D01*
X1564296Y126444D01*
X1564087Y126736D01*
X1564004Y127069D01*
X1564087Y127402D01*
X1564296Y127694D01*
X1564587Y127819D01*
X1564879Y127736D01*
X1565087Y127527D01*
X1565171Y127277D01*
Y126861D01*
X1565296Y126486D01*
X1565546Y126236D01*
X1565837Y126152D01*
X1566129Y126236D01*
X1566337Y126444D01*
X1566462Y126777D01*
X1566504Y127069D01*
G01X1578865Y133767D02*
X1576365D01*
Y134808D01*
X1576490Y135142D01*
X1576657Y135350D01*
X1576990Y135433D01*
X1577323Y135350D01*
X1577532Y135100D01*
X1577657Y134808D01*
Y133767D01*
G01Y134808D02*
X1578865Y135433D01*
G01Y137700D02*
X1578823Y137992D01*
X1578698Y138325D01*
X1578490Y138533D01*
X1578198Y138617D01*
X1577907Y138533D01*
X1577657Y138283D01*
X1577532Y137908D01*
Y137492D01*
X1577448Y137242D01*
X1577240Y137033D01*
X1576948Y136950D01*
X1576657Y137075D01*
X1576448Y137367D01*
X1576365Y137700D01*
X1576448Y138033D01*
X1576657Y138325D01*
X1576948Y138450D01*
X1577240Y138367D01*
X1577448Y138158D01*
X1577532Y137908D01*
Y137492D01*
X1577657Y137117D01*
X1577907Y136867D01*
X1578198Y136783D01*
X1578490Y136867D01*
X1578698Y137075D01*
X1578823Y137408D01*
X1578865Y137700D01*
G01X1576573Y141717D02*
X1576448Y141467D01*
X1576365Y141175D01*
Y140842D01*
X1576490Y140467D01*
X1576698Y140175D01*
X1576948Y139967D01*
X1577365Y139800D01*
X1577740Y139758D01*
X1578115Y139842D01*
X1578365Y139967D01*
X1578615Y140217D01*
X1578782Y140508D01*
X1578865Y140800D01*
Y141092D01*
X1578782Y141383D01*
X1578657Y141633D01*
X1578490Y141842D01*
G01X1578865Y143900D02*
X1576365D01*
X1576865Y143400D01*
G01X1578865D02*
Y144400D01*
G01X1577823Y146208D02*
X1577532Y146500D01*
X1577365Y146750D01*
X1577282Y147083D01*
X1577365Y147375D01*
X1577532Y147583D01*
X1577782Y147750D01*
X1578073Y147792D01*
X1578323Y147750D01*
X1578573Y147583D01*
X1578782Y147333D01*
X1578865Y147042D01*
X1578782Y146708D01*
X1578532Y146417D01*
X1578157Y146250D01*
X1577740Y146208D01*
X1577198Y146292D01*
X1576907Y146417D01*
X1576615Y146625D01*
X1576407Y146917D01*
X1576365Y147208D01*
X1576448Y147500D01*
X1576657Y147708D01*
G01X1575878Y123266D02*
Y125766D01*
X1576919D01*
X1577253Y125641D01*
X1577461Y125474D01*
X1577544Y125141D01*
X1577461Y124808D01*
X1577211Y124599D01*
X1576919Y124474D01*
X1575878D01*
G01X1576919D02*
X1577544Y123266D01*
G01X1579019Y125349D02*
X1579269Y125599D01*
X1579561Y125724D01*
X1579894Y125766D01*
X1580311Y125683D01*
X1580603Y125474D01*
X1580686Y125224D01*
X1580644Y124974D01*
X1580478Y124766D01*
X1579644Y124349D01*
X1579269Y124058D01*
X1579019Y123641D01*
X1578936Y123266D01*
X1580686D01*
G01X1581994Y125766D02*
Y123974D01*
X1582161Y123599D01*
X1582494Y123349D01*
X1582911Y123266D01*
X1583328Y123349D01*
X1583661Y123599D01*
X1583828Y123974D01*
Y125766D01*
G01X1585094Y123766D02*
X1585344Y123474D01*
X1585678Y123308D01*
X1586053Y123266D01*
X1586386Y123308D01*
X1586719Y123516D01*
X1586928Y123766D01*
X1586969Y124016D01*
X1586886Y124308D01*
X1586594Y124516D01*
X1586303Y124599D01*
X1585928D01*
G01X1586303D02*
X1586553Y124724D01*
X1586761Y124933D01*
X1586844Y125183D01*
X1586761Y125433D01*
X1586553Y125641D01*
X1586178Y125766D01*
X1585803Y125724D01*
X1585428Y125558D01*
G01X1588194Y123766D02*
X1588444Y123474D01*
X1588778Y123308D01*
X1589153Y123266D01*
X1589486Y123308D01*
X1589819Y123516D01*
X1590028Y123766D01*
X1590069Y124016D01*
X1589986Y124308D01*
X1589694Y124516D01*
X1589403Y124599D01*
X1589028D01*
G01X1589403D02*
X1589653Y124724D01*
X1589861Y124933D01*
X1589944Y125183D01*
X1589861Y125433D01*
X1589653Y125641D01*
X1589278Y125766D01*
X1588903Y125724D01*
X1588528Y125558D01*
G01X1582567Y117967D02*
Y120467D01*
X1583608D01*
X1583942Y120342D01*
X1584150Y120175D01*
X1584233Y119842D01*
X1584150Y119509D01*
X1583900Y119300D01*
X1583608Y119175D01*
X1582567D01*
G01X1583608D02*
X1584233Y117967D01*
G01X1586500D02*
Y120467D01*
X1586000Y119967D01*
G01Y117967D02*
X1587000D01*
G01X1589600Y120467D02*
Y117967D01*
G01X1588642Y120467D02*
X1590558D01*
G01X1591908Y120050D02*
X1592158Y120300D01*
X1592450Y120425D01*
X1592783Y120467D01*
X1593200Y120384D01*
X1593492Y120175D01*
X1593575Y119925D01*
X1593533Y119675D01*
X1593367Y119467D01*
X1592533Y119050D01*
X1592158Y118759D01*
X1591908Y118342D01*
X1591825Y117967D01*
X1593575D01*
G01X1594883Y118342D02*
X1595133Y118134D01*
X1595425Y118009D01*
X1595800Y117967D01*
X1596175Y118050D01*
X1596467Y118217D01*
X1596675Y118509D01*
X1596717Y118842D01*
X1596633Y119175D01*
X1596425Y119384D01*
X1596133Y119550D01*
X1595842Y119592D01*
X1595550Y119550D01*
X1595175Y119384D01*
X1595300Y120467D01*
X1596425D01*
G01X1554937Y135208D02*
Y137708D01*
X1555978D01*
X1556312Y137583D01*
X1556520Y137416D01*
X1556603Y137083D01*
X1556520Y136750D01*
X1556270Y136541D01*
X1555978Y136416D01*
X1554937D01*
G01X1555978D02*
X1556603Y135208D01*
G01X1558870D02*
X1559162Y135250D01*
X1559495Y135375D01*
X1559703Y135583D01*
X1559787Y135875D01*
X1559703Y136166D01*
X1559453Y136416D01*
X1559078Y136541D01*
X1558662D01*
X1558412Y136625D01*
X1558203Y136833D01*
X1558120Y137125D01*
X1558245Y137416D01*
X1558537Y137625D01*
X1558870Y137708D01*
X1559203Y137625D01*
X1559495Y137416D01*
X1559620Y137125D01*
X1559537Y136833D01*
X1559328Y136625D01*
X1559078Y136541D01*
X1558662D01*
X1558287Y136416D01*
X1558037Y136166D01*
X1557953Y135875D01*
X1558037Y135583D01*
X1558245Y135375D01*
X1558578Y135250D01*
X1558870Y135208D01*
G01X1562220Y136458D02*
X1563053D01*
Y135708D01*
X1562803Y135458D01*
X1562512Y135291D01*
X1562095Y135208D01*
X1561678Y135291D01*
X1561387Y135458D01*
X1561137Y135708D01*
X1560970Y136000D01*
X1560887Y136333D01*
Y136625D01*
X1560970Y136875D01*
X1561137Y137166D01*
X1561387Y137416D01*
X1561637Y137583D01*
X1561970Y137708D01*
X1562262D01*
X1562595Y137625D01*
X1562845Y137458D01*
G01X1565570Y135208D02*
Y137708D01*
X1564028Y135916D01*
X1566112D01*
G01X1555114Y138523D02*
Y141023D01*
X1556155D01*
X1556489Y140898D01*
X1556697Y140731D01*
X1556780Y140398D01*
X1556697Y140065D01*
X1556447Y139856D01*
X1556155Y139731D01*
X1555114D01*
G01X1556155D02*
X1556780Y138523D01*
G01X1559047D02*
X1559339Y138565D01*
X1559672Y138690D01*
X1559880Y138898D01*
X1559964Y139190D01*
X1559880Y139481D01*
X1559630Y139731D01*
X1559255Y139856D01*
X1558839D01*
X1558589Y139940D01*
X1558380Y140148D01*
X1558297Y140440D01*
X1558422Y140731D01*
X1558714Y140940D01*
X1559047Y141023D01*
X1559380Y140940D01*
X1559672Y140731D01*
X1559797Y140440D01*
X1559714Y140148D01*
X1559505Y139940D01*
X1559255Y139856D01*
X1558839D01*
X1558464Y139731D01*
X1558214Y139481D01*
X1558130Y139190D01*
X1558214Y138898D01*
X1558422Y138690D01*
X1558755Y138565D01*
X1559047Y138523D01*
G01X1562397Y139773D02*
X1563230D01*
Y139023D01*
X1562980Y138773D01*
X1562689Y138606D01*
X1562272Y138523D01*
X1561855Y138606D01*
X1561564Y138773D01*
X1561314Y139023D01*
X1561147Y139315D01*
X1561064Y139648D01*
Y139940D01*
X1561147Y140190D01*
X1561314Y140481D01*
X1561564Y140731D01*
X1561814Y140898D01*
X1562147Y141023D01*
X1562439D01*
X1562772Y140940D01*
X1563022Y140773D01*
G01X1564330Y139023D02*
X1564580Y138731D01*
X1564914Y138565D01*
X1565289Y138523D01*
X1565622Y138565D01*
X1565955Y138773D01*
X1566164Y139023D01*
X1566205Y139273D01*
X1566122Y139565D01*
X1565830Y139773D01*
X1565539Y139856D01*
X1565164D01*
G01X1565539D02*
X1565789Y139981D01*
X1565997Y140190D01*
X1566080Y140440D01*
X1565997Y140690D01*
X1565789Y140898D01*
X1565414Y141023D01*
X1565039Y140981D01*
X1564664Y140815D01*
G01X1554937Y131827D02*
Y134327D01*
X1555978D01*
X1556312Y134202D01*
X1556520Y134035D01*
X1556603Y133702D01*
X1556520Y133369D01*
X1556270Y133160D01*
X1555978Y133035D01*
X1554937D01*
G01X1555978D02*
X1556603Y131827D01*
G01X1558870D02*
X1559162Y131869D01*
X1559495Y131994D01*
X1559703Y132202D01*
X1559787Y132494D01*
X1559703Y132785D01*
X1559453Y133035D01*
X1559078Y133160D01*
X1558662D01*
X1558412Y133244D01*
X1558203Y133452D01*
X1558120Y133744D01*
X1558245Y134035D01*
X1558537Y134244D01*
X1558870Y134327D01*
X1559203Y134244D01*
X1559495Y134035D01*
X1559620Y133744D01*
X1559537Y133452D01*
X1559328Y133244D01*
X1559078Y133160D01*
X1558662D01*
X1558287Y133035D01*
X1558037Y132785D01*
X1557953Y132494D01*
X1558037Y132202D01*
X1558245Y131994D01*
X1558578Y131869D01*
X1558870Y131827D01*
G01X1562220Y133077D02*
X1563053D01*
Y132327D01*
X1562803Y132077D01*
X1562512Y131910D01*
X1562095Y131827D01*
X1561678Y131910D01*
X1561387Y132077D01*
X1561137Y132327D01*
X1560970Y132619D01*
X1560887Y132952D01*
Y133244D01*
X1560970Y133494D01*
X1561137Y133785D01*
X1561387Y134035D01*
X1561637Y134202D01*
X1561970Y134327D01*
X1562262D01*
X1562595Y134244D01*
X1562845Y134077D01*
G01X1564153Y132202D02*
X1564403Y131994D01*
X1564695Y131869D01*
X1565070Y131827D01*
X1565445Y131910D01*
X1565737Y132077D01*
X1565945Y132369D01*
X1565987Y132702D01*
X1565903Y133035D01*
X1565695Y133244D01*
X1565403Y133410D01*
X1565112Y133452D01*
X1564820Y133410D01*
X1564445Y133244D01*
X1564570Y134327D01*
X1565695D01*
G01X1566367Y155992D02*
X1566117Y156117D01*
X1565825Y156200D01*
X1565492D01*
X1565117Y156075D01*
X1564825Y155867D01*
X1564617Y155617D01*
X1564450Y155200D01*
X1564408Y154825D01*
X1564492Y154450D01*
X1564617Y154200D01*
X1564867Y153950D01*
X1565158Y153783D01*
X1565450Y153700D01*
X1565742D01*
X1566033Y153783D01*
X1566283Y153908D01*
X1566492Y154075D01*
G01X1567842Y153992D02*
X1568133Y153783D01*
X1568467Y153700D01*
X1568800Y153783D01*
X1569092Y154033D01*
X1569300Y154408D01*
X1569383Y154783D01*
Y155242D01*
X1569300Y155617D01*
X1569092Y155950D01*
X1568842Y156117D01*
X1568550Y156200D01*
X1568217Y156117D01*
X1567967Y155950D01*
X1567800Y155700D01*
X1567717Y155367D01*
X1567800Y155075D01*
X1568008Y154783D01*
X1568258Y154617D01*
X1568550Y154575D01*
X1568883Y154658D01*
X1569133Y154867D01*
X1569383Y155242D01*
G01X1570400Y156200D02*
X1570983Y153700D01*
X1571650Y156200D01*
X1572317Y153700D01*
X1572900Y156200D01*
G01X1574667Y153700D02*
X1574750Y154242D01*
X1574875Y154700D01*
X1575042Y155117D01*
X1575250Y155575D01*
X1575583Y156200D01*
X1573917D01*
G01X1590797Y183437D02*
X1589730Y183554D01*
X1588797Y184020D01*
X1587997Y184720D01*
X1587464Y185537D01*
X1587197Y186470D01*
Y187404D01*
X1587464Y188337D01*
X1587997Y189154D01*
X1588797Y189854D01*
X1589730Y190320D01*
X1590797Y190437D01*
X1591864Y190320D01*
X1592797Y189854D01*
X1593597Y189154D01*
X1594130Y188337D01*
X1594397Y187404D01*
Y186470D01*
X1594130Y185537D01*
X1593597Y184720D01*
X1592797Y184020D01*
X1591864Y183554D01*
X1590797Y183437D01*
G01X1591864Y185304D02*
X1593464Y183437D01*
G01X1527883Y174200D02*
Y177300D01*
X1528803D01*
X1529110Y177145D01*
X1529340Y176783D01*
X1529417Y176370D01*
X1529340Y175957D01*
X1529148Y175647D01*
X1528803Y175492D01*
X1527883D01*
G01X1530983Y174200D02*
Y177300D01*
X1531942D01*
X1532248Y177145D01*
X1532440Y176938D01*
X1532517Y176525D01*
X1532440Y176112D01*
X1532210Y175853D01*
X1531942Y175698D01*
X1530983D01*
G01X1531942D02*
X1532517Y174200D01*
G01X1534390Y177300D02*
X1535310D01*
G01X1534850D02*
Y174200D01*
G01X1534390D02*
X1535310D01*
G01X1536953D02*
Y177300D01*
X1537950Y174717D01*
X1538947Y177300D01*
Y174200D01*
G01X1540092D02*
X1541050Y177300D01*
X1542008Y174200D01*
G01X1541663Y175285D02*
X1540437D01*
G01X1543383Y174200D02*
Y177300D01*
X1544342D01*
X1544648Y177145D01*
X1544840Y176938D01*
X1544917Y176525D01*
X1544840Y176112D01*
X1544610Y175853D01*
X1544342Y175698D01*
X1543383D01*
G01X1544342D02*
X1544917Y174200D01*
G01X1547250D02*
Y175595D01*
X1546483Y177300D01*
G01X1548017D02*
X1547250Y175595D01*
G01X1553757Y175853D02*
X1553910Y176008D01*
X1554025Y176267D01*
X1554102Y176628D01*
X1554025Y176938D01*
X1553872Y177145D01*
X1553603Y177300D01*
X1552568D01*
Y174200D01*
X1553833D01*
X1554102Y174407D01*
X1554255Y174717D01*
X1554332Y175078D01*
X1554255Y175440D01*
X1554025Y175750D01*
X1553757Y175853D01*
X1552568D01*
G01X1556090Y177300D02*
X1557010D01*
G01X1556550D02*
Y174200D01*
G01X1556090D02*
X1557010D01*
G01X1559650D02*
X1559343Y174252D01*
X1559075Y174458D01*
X1558845Y174768D01*
X1558692Y175130D01*
X1558615Y175543D01*
Y175957D01*
X1558692Y176370D01*
X1558845Y176732D01*
X1559075Y177042D01*
X1559343Y177248D01*
X1559650Y177300D01*
X1559957Y177248D01*
X1560225Y177042D01*
X1560455Y176732D01*
X1560608Y176370D01*
X1560685Y175957D01*
Y175543D01*
X1560608Y175130D01*
X1560455Y174768D01*
X1560225Y174458D01*
X1559957Y174252D01*
X1559650Y174200D01*
G01X1561945Y174613D02*
X1562252Y174355D01*
X1562597Y174200D01*
X1562903D01*
X1563210Y174355D01*
X1563440Y174613D01*
X1563555Y174975D01*
X1563478Y175337D01*
X1563287Y175647D01*
X1562942Y175853D01*
X1562482Y175957D01*
X1562213Y176163D01*
X1562098Y176525D01*
X1562175Y176887D01*
X1562367Y177145D01*
X1562635Y177300D01*
X1562903D01*
X1563172Y177197D01*
X1563402Y176938D01*
G01X1585968Y187400D02*
X1585101D01*
X1585100Y187399D01*
Y177801D01*
X1585101Y177800D01*
X1605199D01*
X1605200Y177801D01*
Y180100D01*
G01X1583257Y210037D02*
Y212537D01*
X1584298D01*
X1584632Y212412D01*
X1584840Y212245D01*
X1584923Y211912D01*
X1584840Y211579D01*
X1584590Y211370D01*
X1584298Y211245D01*
X1583257D01*
G01X1584298D02*
X1584923Y210037D01*
G01X1587107D02*
X1587190Y210579D01*
X1587315Y211037D01*
X1587482Y211454D01*
X1587690Y211912D01*
X1588023Y212537D01*
X1586357D01*
G01X1589498Y210037D02*
Y212537D01*
X1591082D01*
G01X1590498Y211329D02*
X1589498D01*
G01X1593890Y210037D02*
Y212537D01*
X1592348Y210745D01*
X1594432D01*
G01X1583000Y205720D02*
Y208220D01*
X1584041D01*
X1584375Y208095D01*
X1584583Y207928D01*
X1584666Y207595D01*
X1584583Y207262D01*
X1584333Y207053D01*
X1584041Y206928D01*
X1583000D01*
G01X1584041D02*
X1584666Y205720D01*
G01X1586850D02*
X1586933Y206262D01*
X1587058Y206720D01*
X1587225Y207137D01*
X1587433Y207595D01*
X1587766Y208220D01*
X1586100D01*
G01X1589241Y205720D02*
Y208220D01*
X1590825D01*
G01X1590241Y207012D02*
X1589241D01*
G01X1592216Y206095D02*
X1592466Y205887D01*
X1592758Y205762D01*
X1593133Y205720D01*
X1593508Y205803D01*
X1593800Y205970D01*
X1594008Y206262D01*
X1594050Y206595D01*
X1593966Y206928D01*
X1593758Y207137D01*
X1593466Y207303D01*
X1593175Y207345D01*
X1592883Y207303D01*
X1592508Y207137D01*
X1592633Y208220D01*
X1593758D01*
G01X1583543Y171449D02*
X1581043D01*
Y172490D01*
X1581168Y172824D01*
X1581335Y173032D01*
X1581668Y173115D01*
X1582001Y173032D01*
X1582210Y172782D01*
X1582335Y172490D01*
Y171449D01*
G01Y172490D02*
X1583543Y173115D01*
G01Y175299D02*
X1583001Y175382D01*
X1582543Y175507D01*
X1582126Y175674D01*
X1581668Y175882D01*
X1581043Y176215D01*
Y174549D01*
G01X1583543Y177690D02*
X1581043D01*
Y179274D01*
G01X1582251Y178690D02*
Y177690D01*
G01X1583043Y180665D02*
X1583335Y180915D01*
X1583501Y181249D01*
X1583543Y181624D01*
X1583501Y181957D01*
X1583293Y182290D01*
X1583043Y182499D01*
X1582793Y182540D01*
X1582501Y182457D01*
X1582293Y182165D01*
X1582210Y181874D01*
Y181499D01*
G01Y181874D02*
X1582085Y182124D01*
X1581876Y182332D01*
X1581626Y182415D01*
X1581376Y182332D01*
X1581168Y182124D01*
X1581043Y181749D01*
X1581085Y181374D01*
X1581251Y180999D01*
G01X1581460Y183890D02*
X1581210Y184140D01*
X1581085Y184432D01*
X1581043Y184765D01*
X1581126Y185182D01*
X1581335Y185474D01*
X1581585Y185557D01*
X1581835Y185515D01*
X1582043Y185349D01*
X1582460Y184515D01*
X1582751Y184140D01*
X1583168Y183890D01*
X1583543Y183807D01*
Y185557D01*
G01X1580143Y165349D02*
X1577643D01*
Y166390D01*
X1577768Y166724D01*
X1577935Y166932D01*
X1578268Y167015D01*
X1578601Y166932D01*
X1578810Y166682D01*
X1578935Y166390D01*
Y165349D01*
G01Y166390D02*
X1580143Y167015D01*
G01Y169199D02*
X1579601Y169282D01*
X1579143Y169407D01*
X1578726Y169574D01*
X1578268Y169782D01*
X1577643Y170115D01*
Y168449D01*
G01X1580143Y171590D02*
X1577643D01*
Y173174D01*
G01X1578851Y172590D02*
Y171590D01*
G01X1579643Y174565D02*
X1579935Y174815D01*
X1580101Y175149D01*
X1580143Y175524D01*
X1580101Y175857D01*
X1579893Y176190D01*
X1579643Y176399D01*
X1579393Y176440D01*
X1579101Y176357D01*
X1578893Y176065D01*
X1578810Y175774D01*
Y175399D01*
G01Y175774D02*
X1578685Y176024D01*
X1578476Y176232D01*
X1578226Y176315D01*
X1577976Y176232D01*
X1577768Y176024D01*
X1577643Y175649D01*
X1577685Y175274D01*
X1577851Y174899D01*
G01X1555167Y168800D02*
Y171300D01*
X1556208D01*
X1556542Y171175D01*
X1556750Y171008D01*
X1556833Y170675D01*
X1556750Y170342D01*
X1556500Y170133D01*
X1556208Y170008D01*
X1555167D01*
G01X1556208D02*
X1556833Y168800D01*
G01X1559100D02*
Y171300D01*
X1558600Y170800D01*
G01Y168800D02*
X1559600D01*
G01X1562200Y171300D02*
Y168800D01*
G01X1561242Y171300D02*
X1563158D01*
G01X1564383Y169300D02*
X1564633Y169008D01*
X1564967Y168842D01*
X1565342Y168800D01*
X1565675Y168842D01*
X1566008Y169050D01*
X1566217Y169300D01*
X1566258Y169550D01*
X1566175Y169842D01*
X1565883Y170050D01*
X1565592Y170133D01*
X1565217D01*
G01X1565592D02*
X1565842Y170258D01*
X1566050Y170467D01*
X1566133Y170717D01*
X1566050Y170967D01*
X1565842Y171175D01*
X1565467Y171300D01*
X1565092Y171258D01*
X1564717Y171092D01*
G01X1567483Y169175D02*
X1567733Y168967D01*
X1568025Y168842D01*
X1568400Y168800D01*
X1568775Y168883D01*
X1569067Y169050D01*
X1569275Y169342D01*
X1569317Y169675D01*
X1569233Y170008D01*
X1569025Y170217D01*
X1568733Y170383D01*
X1568442Y170425D01*
X1568150Y170383D01*
X1567775Y170217D01*
X1567900Y171300D01*
X1569025D01*
G01X1555167Y165300D02*
Y167800D01*
X1556208D01*
X1556542Y167675D01*
X1556750Y167508D01*
X1556833Y167175D01*
X1556750Y166842D01*
X1556500Y166633D01*
X1556208Y166508D01*
X1555167D01*
G01X1556208D02*
X1556833Y165300D01*
G01X1559100D02*
Y167800D01*
X1558600Y167300D01*
G01Y165300D02*
X1559600D01*
G01X1562200Y167800D02*
Y165300D01*
G01X1561242Y167800D02*
X1563158D01*
G01X1564383Y165800D02*
X1564633Y165508D01*
X1564967Y165342D01*
X1565342Y165300D01*
X1565675Y165342D01*
X1566008Y165550D01*
X1566217Y165800D01*
X1566258Y166050D01*
X1566175Y166342D01*
X1565883Y166550D01*
X1565592Y166633D01*
X1565217D01*
G01X1565592D02*
X1565842Y166758D01*
X1566050Y166967D01*
X1566133Y167217D01*
X1566050Y167467D01*
X1565842Y167675D01*
X1565467Y167800D01*
X1565092Y167758D01*
X1564717Y167592D01*
G01X1567608Y166342D02*
X1567900Y166633D01*
X1568150Y166800D01*
X1568483Y166883D01*
X1568775Y166800D01*
X1568983Y166633D01*
X1569150Y166383D01*
X1569192Y166092D01*
X1569150Y165842D01*
X1568983Y165592D01*
X1568733Y165383D01*
X1568442Y165300D01*
X1568108Y165383D01*
X1567817Y165633D01*
X1567650Y166008D01*
X1567608Y166425D01*
X1567692Y166967D01*
X1567817Y167258D01*
X1568025Y167550D01*
X1568317Y167758D01*
X1568608Y167800D01*
X1568900Y167717D01*
X1569108Y167508D01*
G01X1555167Y158300D02*
Y160800D01*
X1556208D01*
X1556542Y160675D01*
X1556750Y160508D01*
X1556833Y160175D01*
X1556750Y159842D01*
X1556500Y159633D01*
X1556208Y159508D01*
X1555167D01*
G01X1556208D02*
X1556833Y158300D01*
G01X1559100D02*
Y160800D01*
X1558600Y160300D01*
G01Y158300D02*
X1559600D01*
G01X1562200Y160800D02*
Y158300D01*
G01X1561242Y160800D02*
X1563158D01*
G01X1564383Y158800D02*
X1564633Y158508D01*
X1564967Y158342D01*
X1565342Y158300D01*
X1565675Y158342D01*
X1566008Y158550D01*
X1566217Y158800D01*
X1566258Y159050D01*
X1566175Y159342D01*
X1565883Y159550D01*
X1565592Y159633D01*
X1565217D01*
G01X1565592D02*
X1565842Y159758D01*
X1566050Y159967D01*
X1566133Y160217D01*
X1566050Y160467D01*
X1565842Y160675D01*
X1565467Y160800D01*
X1565092Y160758D01*
X1564717Y160592D01*
G01X1568317Y158300D02*
X1568400Y158842D01*
X1568525Y159300D01*
X1568692Y159717D01*
X1568900Y160175D01*
X1569233Y160800D01*
X1567567D01*
G01X1555167Y161800D02*
Y164300D01*
X1556208D01*
X1556542Y164175D01*
X1556750Y164008D01*
X1556833Y163675D01*
X1556750Y163342D01*
X1556500Y163133D01*
X1556208Y163008D01*
X1555167D01*
G01X1556208D02*
X1556833Y161800D01*
G01X1559100D02*
Y164300D01*
X1558600Y163800D01*
G01Y161800D02*
X1559600D01*
G01X1562200Y164300D02*
Y161800D01*
G01X1561242Y164300D02*
X1563158D01*
G01X1564383Y162300D02*
X1564633Y162008D01*
X1564967Y161842D01*
X1565342Y161800D01*
X1565675Y161842D01*
X1566008Y162050D01*
X1566217Y162300D01*
X1566258Y162550D01*
X1566175Y162842D01*
X1565883Y163050D01*
X1565592Y163133D01*
X1565217D01*
G01X1565592D02*
X1565842Y163258D01*
X1566050Y163467D01*
X1566133Y163717D01*
X1566050Y163967D01*
X1565842Y164175D01*
X1565467Y164300D01*
X1565092Y164258D01*
X1564717Y164092D01*
G01X1568400Y161800D02*
X1568692Y161842D01*
X1569025Y161967D01*
X1569233Y162175D01*
X1569317Y162467D01*
X1569233Y162758D01*
X1568983Y163008D01*
X1568608Y163133D01*
X1568192D01*
X1567942Y163217D01*
X1567733Y163425D01*
X1567650Y163717D01*
X1567775Y164008D01*
X1568067Y164217D01*
X1568400Y164300D01*
X1568733Y164217D01*
X1569025Y164008D01*
X1569150Y163717D01*
X1569067Y163425D01*
X1568858Y163217D01*
X1568608Y163133D01*
X1568192D01*
X1567817Y163008D01*
X1567567Y162758D01*
X1567483Y162467D01*
X1567567Y162175D01*
X1567775Y161967D01*
X1568108Y161842D01*
X1568400Y161800D01*
G01X1580400Y198317D02*
X1577900D01*
Y199358D01*
X1578025Y199692D01*
X1578192Y199900D01*
X1578525Y199983D01*
X1578858Y199900D01*
X1579067Y199650D01*
X1579192Y199358D01*
Y198317D01*
G01Y199358D02*
X1580400Y199983D01*
G01Y202167D02*
X1579858Y202250D01*
X1579400Y202375D01*
X1578983Y202542D01*
X1578525Y202750D01*
X1577900Y203083D01*
Y201417D01*
G01X1580400Y204558D02*
X1577900D01*
Y206142D01*
G01X1579108Y205558D02*
Y204558D01*
G01X1579358Y207658D02*
X1579067Y207950D01*
X1578900Y208200D01*
X1578817Y208533D01*
X1578900Y208825D01*
X1579067Y209033D01*
X1579317Y209200D01*
X1579608Y209242D01*
X1579858Y209200D01*
X1580108Y209033D01*
X1580317Y208783D01*
X1580400Y208492D01*
X1580317Y208158D01*
X1580067Y207867D01*
X1579692Y207700D01*
X1579275Y207658D01*
X1578733Y207742D01*
X1578442Y207867D01*
X1578150Y208075D01*
X1577942Y208367D01*
X1577900Y208658D01*
X1577983Y208950D01*
X1578192Y209158D01*
G01X1584167Y199192D02*
X1583917Y199317D01*
X1583625Y199400D01*
X1583292D01*
X1582917Y199275D01*
X1582625Y199067D01*
X1582417Y198817D01*
X1582250Y198400D01*
X1582208Y198025D01*
X1582292Y197650D01*
X1582417Y197400D01*
X1582667Y197150D01*
X1582958Y196983D01*
X1583250Y196900D01*
X1583542D01*
X1583833Y196983D01*
X1584083Y197108D01*
X1584292Y197275D01*
G01X1586267Y196900D02*
X1586350Y197442D01*
X1586475Y197900D01*
X1586642Y198317D01*
X1586850Y198775D01*
X1587183Y199400D01*
X1585517D01*
G01X1588658Y196900D02*
Y199400D01*
X1590242D01*
G01X1589658Y198192D02*
X1588658D01*
G01X1591758Y198983D02*
X1592008Y199233D01*
X1592300Y199358D01*
X1592633Y199400D01*
X1593050Y199317D01*
X1593342Y199108D01*
X1593425Y198858D01*
X1593383Y198608D01*
X1593217Y198400D01*
X1592383Y197983D01*
X1592008Y197692D01*
X1591758Y197275D01*
X1591675Y196900D01*
X1593425D01*
G01X1584167Y202892D02*
X1583917Y203017D01*
X1583625Y203100D01*
X1583292D01*
X1582917Y202975D01*
X1582625Y202767D01*
X1582417Y202517D01*
X1582250Y202100D01*
X1582208Y201725D01*
X1582292Y201350D01*
X1582417Y201100D01*
X1582667Y200850D01*
X1582958Y200683D01*
X1583250Y200600D01*
X1583542D01*
X1583833Y200683D01*
X1584083Y200808D01*
X1584292Y200975D01*
G01X1586267Y200600D02*
X1586350Y201142D01*
X1586475Y201600D01*
X1586642Y202017D01*
X1586850Y202475D01*
X1587183Y203100D01*
X1585517D01*
G01X1588658Y200600D02*
Y203100D01*
X1590242D01*
G01X1589658Y201892D02*
X1588658D01*
G01X1592550Y200600D02*
Y203100D01*
X1592050Y202600D01*
G01Y200600D02*
X1593050D01*
G01X1581333Y220867D02*
Y219075D01*
X1581500Y218700D01*
X1581833Y218450D01*
X1582250Y218367D01*
X1582667Y218450D01*
X1583000Y218700D01*
X1583167Y219075D01*
Y220867D01*
G01X1585350Y218367D02*
X1585642Y218409D01*
X1585975Y218534D01*
X1586183Y218742D01*
X1586267Y219034D01*
X1586183Y219325D01*
X1585933Y219575D01*
X1585558Y219700D01*
X1585142D01*
X1584892Y219784D01*
X1584683Y219992D01*
X1584600Y220284D01*
X1584725Y220575D01*
X1585017Y220784D01*
X1585350Y220867D01*
X1585683Y220784D01*
X1585975Y220575D01*
X1586100Y220284D01*
X1586017Y219992D01*
X1585808Y219784D01*
X1585558Y219700D01*
X1585142D01*
X1584767Y219575D01*
X1584517Y219325D01*
X1584433Y219034D01*
X1584517Y218742D01*
X1584725Y218534D01*
X1585058Y218409D01*
X1585350Y218367D01*
G01X1587533D02*
Y220867D01*
X1588367D01*
X1588700Y220742D01*
X1588950Y220575D01*
X1589158Y220325D01*
X1589325Y220034D01*
X1589367Y219617D01*
X1589325Y219200D01*
X1589158Y218909D01*
X1588950Y218659D01*
X1588700Y218492D01*
X1588367Y218367D01*
X1587533D01*
G01X1592050D02*
Y220867D01*
X1590508Y219075D01*
X1592592D01*
G01X1592630Y259940D02*
Y256640D01*
X1565830D01*
Y259940D01*
G01X1550857Y277550D02*
Y280050D01*
X1551898D01*
X1552232Y279925D01*
X1552440Y279758D01*
X1552523Y279425D01*
X1552440Y279092D01*
X1552190Y278883D01*
X1551898Y278758D01*
X1550857D01*
G01X1551898D02*
X1552523Y277550D01*
G01X1554707D02*
X1554790Y278092D01*
X1554915Y278550D01*
X1555082Y278967D01*
X1555290Y279425D01*
X1555623Y280050D01*
X1553957D01*
G01X1558723Y277550D02*
X1557057D01*
Y280050D01*
X1558723D01*
G01X1558057Y278842D02*
X1557057D01*
G01X1560990Y277550D02*
Y280050D01*
X1560490Y279550D01*
G01Y277550D02*
X1561490D01*
G01X1563173Y277925D02*
X1563423Y277717D01*
X1563715Y277592D01*
X1564090Y277550D01*
X1564465Y277633D01*
X1564757Y277800D01*
X1564965Y278092D01*
X1565007Y278425D01*
X1564923Y278758D01*
X1564715Y278967D01*
X1564423Y279133D01*
X1564132Y279175D01*
X1563840Y279133D01*
X1563465Y278967D01*
X1563590Y280050D01*
X1564715D01*
G01X1548700Y236067D02*
X1546200D01*
Y237108D01*
X1546325Y237442D01*
X1546492Y237650D01*
X1546825Y237733D01*
X1547158Y237650D01*
X1547367Y237400D01*
X1547492Y237108D01*
Y236067D01*
G01Y237108D02*
X1548700Y237733D01*
G01Y240000D02*
X1548658Y240292D01*
X1548533Y240625D01*
X1548325Y240833D01*
X1548033Y240917D01*
X1547742Y240833D01*
X1547492Y240583D01*
X1547367Y240208D01*
Y239792D01*
X1547283Y239542D01*
X1547075Y239333D01*
X1546783Y239250D01*
X1546492Y239375D01*
X1546283Y239667D01*
X1546200Y240000D01*
X1546283Y240333D01*
X1546492Y240625D01*
X1546783Y240750D01*
X1547075Y240667D01*
X1547283Y240458D01*
X1547367Y240208D01*
Y239792D01*
X1547492Y239417D01*
X1547742Y239167D01*
X1548033Y239083D01*
X1548325Y239167D01*
X1548533Y239375D01*
X1548658Y239708D01*
X1548700Y240000D01*
G01Y243933D02*
Y242267D01*
X1546200D01*
Y243933D01*
G01X1547408Y243267D02*
Y242267D01*
G01X1548200Y245283D02*
X1548492Y245533D01*
X1548658Y245867D01*
X1548700Y246242D01*
X1548658Y246575D01*
X1548450Y246908D01*
X1548200Y247117D01*
X1547950Y247158D01*
X1547658Y247075D01*
X1547450Y246783D01*
X1547367Y246492D01*
Y246117D01*
G01Y246492D02*
X1547242Y246742D01*
X1547033Y246950D01*
X1546783Y247033D01*
X1546533Y246950D01*
X1546325Y246742D01*
X1546200Y246367D01*
X1546242Y245992D01*
X1546408Y245617D01*
G01X1548700Y249217D02*
X1548158Y249300D01*
X1547700Y249425D01*
X1547283Y249592D01*
X1546825Y249800D01*
X1546200Y250133D01*
Y248467D01*
G01X1543967Y229900D02*
Y232400D01*
X1545008D01*
X1545342Y232275D01*
X1545550Y232108D01*
X1545633Y231775D01*
X1545550Y231442D01*
X1545300Y231233D01*
X1545008Y231108D01*
X1543967D01*
G01X1545008D02*
X1545633Y229900D01*
G01X1547900D02*
X1548192Y229942D01*
X1548525Y230067D01*
X1548733Y230275D01*
X1548817Y230567D01*
X1548733Y230858D01*
X1548483Y231108D01*
X1548108Y231233D01*
X1547692D01*
X1547442Y231317D01*
X1547233Y231525D01*
X1547150Y231817D01*
X1547275Y232108D01*
X1547567Y232317D01*
X1547900Y232400D01*
X1548233Y232317D01*
X1548525Y232108D01*
X1548650Y231817D01*
X1548567Y231525D01*
X1548358Y231317D01*
X1548108Y231233D01*
X1547692D01*
X1547317Y231108D01*
X1547067Y230858D01*
X1546983Y230567D01*
X1547067Y230275D01*
X1547275Y230067D01*
X1547608Y229942D01*
X1547900Y229900D01*
G01X1551833D02*
X1550167D01*
Y232400D01*
X1551833D01*
G01X1551167Y231192D02*
X1550167D01*
G01X1553183Y230400D02*
X1553433Y230108D01*
X1553767Y229942D01*
X1554142Y229900D01*
X1554475Y229942D01*
X1554808Y230150D01*
X1555017Y230400D01*
X1555058Y230650D01*
X1554975Y230942D01*
X1554683Y231150D01*
X1554392Y231233D01*
X1554017D01*
G01X1554392D02*
X1554642Y231358D01*
X1554850Y231567D01*
X1554933Y231817D01*
X1554850Y232067D01*
X1554642Y232275D01*
X1554267Y232400D01*
X1553892Y232358D01*
X1553517Y232192D01*
G01X1556283Y230400D02*
X1556533Y230108D01*
X1556867Y229942D01*
X1557242Y229900D01*
X1557575Y229942D01*
X1557908Y230150D01*
X1558117Y230400D01*
X1558158Y230650D01*
X1558075Y230942D01*
X1557783Y231150D01*
X1557492Y231233D01*
X1557117D01*
G01X1557492D02*
X1557742Y231358D01*
X1557950Y231567D01*
X1558033Y231817D01*
X1557950Y232067D01*
X1557742Y232275D01*
X1557367Y232400D01*
X1556992Y232358D01*
X1556617Y232192D01*
G01X1579834Y219467D02*
X1577334D01*
Y220508D01*
X1577459Y220842D01*
X1577626Y221050D01*
X1577959Y221133D01*
X1578292Y221050D01*
X1578501Y220800D01*
X1578626Y220508D01*
Y219467D01*
G01Y220508D02*
X1579834Y221133D01*
G01Y223400D02*
X1579792Y223692D01*
X1579667Y224025D01*
X1579459Y224233D01*
X1579167Y224317D01*
X1578876Y224233D01*
X1578626Y223983D01*
X1578501Y223608D01*
Y223192D01*
X1578417Y222942D01*
X1578209Y222733D01*
X1577917Y222650D01*
X1577626Y222775D01*
X1577417Y223067D01*
X1577334Y223400D01*
X1577417Y223733D01*
X1577626Y224025D01*
X1577917Y224150D01*
X1578209Y224067D01*
X1578417Y223858D01*
X1578501Y223608D01*
Y223192D01*
X1578626Y222817D01*
X1578876Y222567D01*
X1579167Y222483D01*
X1579459Y222567D01*
X1579667Y222775D01*
X1579792Y223108D01*
X1579834Y223400D01*
G01Y227333D02*
Y225667D01*
X1577334D01*
Y227333D01*
G01X1578542Y226667D02*
Y225667D01*
G01X1579834Y229600D02*
X1577334D01*
X1577834Y229100D01*
G01X1579834D02*
Y230100D01*
G01Y232700D02*
X1579792Y232992D01*
X1579667Y233325D01*
X1579459Y233533D01*
X1579167Y233617D01*
X1578876Y233533D01*
X1578626Y233283D01*
X1578501Y232908D01*
Y232492D01*
X1578417Y232242D01*
X1578209Y232033D01*
X1577917Y231950D01*
X1577626Y232075D01*
X1577417Y232367D01*
X1577334Y232700D01*
X1577417Y233033D01*
X1577626Y233325D01*
X1577917Y233450D01*
X1578209Y233367D01*
X1578417Y233158D01*
X1578501Y232908D01*
Y232492D01*
X1578626Y232117D01*
X1578876Y231867D01*
X1579167Y231783D01*
X1579459Y231867D01*
X1579667Y232075D01*
X1579792Y232408D01*
X1579834Y232700D01*
G01X1534708Y235917D02*
X1534583Y235667D01*
X1534500Y235375D01*
Y235042D01*
X1534625Y234667D01*
X1534833Y234375D01*
X1535083Y234167D01*
X1535500Y234000D01*
X1535875Y233958D01*
X1536250Y234042D01*
X1536500Y234167D01*
X1536750Y234417D01*
X1536917Y234708D01*
X1537000Y235000D01*
Y235292D01*
X1536917Y235583D01*
X1536792Y235833D01*
X1536625Y236042D01*
G01X1537000Y238100D02*
X1536958Y238392D01*
X1536833Y238725D01*
X1536625Y238933D01*
X1536333Y239017D01*
X1536042Y238933D01*
X1535792Y238683D01*
X1535667Y238308D01*
Y237892D01*
X1535583Y237642D01*
X1535375Y237433D01*
X1535083Y237350D01*
X1534792Y237475D01*
X1534583Y237767D01*
X1534500Y238100D01*
X1534583Y238433D01*
X1534792Y238725D01*
X1535083Y238850D01*
X1535375Y238767D01*
X1535583Y238558D01*
X1535667Y238308D01*
Y237892D01*
X1535792Y237517D01*
X1536042Y237267D01*
X1536333Y237183D01*
X1536625Y237267D01*
X1536833Y237475D01*
X1536958Y237808D01*
X1537000Y238100D01*
G01Y242033D02*
Y240367D01*
X1534500D01*
Y242033D01*
G01X1535708Y241367D02*
Y240367D01*
G01X1537000Y244300D02*
X1534500D01*
X1535000Y243800D01*
G01X1537000D02*
Y244800D01*
G01X1536625Y246483D02*
X1536833Y246733D01*
X1536958Y247025D01*
X1537000Y247400D01*
X1536917Y247775D01*
X1536750Y248067D01*
X1536458Y248275D01*
X1536125Y248317D01*
X1535792Y248233D01*
X1535583Y248025D01*
X1535417Y247733D01*
X1535375Y247442D01*
X1535417Y247150D01*
X1535583Y246775D01*
X1534500Y246900D01*
Y248025D01*
G01X1538808Y231117D02*
X1538683Y230867D01*
X1538600Y230575D01*
Y230242D01*
X1538725Y229867D01*
X1538933Y229575D01*
X1539183Y229367D01*
X1539600Y229200D01*
X1539975Y229158D01*
X1540350Y229242D01*
X1540600Y229367D01*
X1540850Y229617D01*
X1541017Y229908D01*
X1541100Y230200D01*
Y230492D01*
X1541017Y230783D01*
X1540892Y231033D01*
X1540725Y231242D01*
G01X1541100Y233300D02*
X1541058Y233592D01*
X1540933Y233925D01*
X1540725Y234133D01*
X1540433Y234217D01*
X1540142Y234133D01*
X1539892Y233883D01*
X1539767Y233508D01*
Y233092D01*
X1539683Y232842D01*
X1539475Y232633D01*
X1539183Y232550D01*
X1538892Y232675D01*
X1538683Y232967D01*
X1538600Y233300D01*
X1538683Y233633D01*
X1538892Y233925D01*
X1539183Y234050D01*
X1539475Y233967D01*
X1539683Y233758D01*
X1539767Y233508D01*
Y233092D01*
X1539892Y232717D01*
X1540142Y232467D01*
X1540433Y232383D01*
X1540725Y232467D01*
X1540933Y232675D01*
X1541058Y233008D01*
X1541100Y233300D01*
G01Y237233D02*
Y235567D01*
X1538600D01*
Y237233D01*
G01X1539808Y236567D02*
Y235567D01*
G01X1541100Y239500D02*
X1538600D01*
X1539100Y239000D01*
G01X1541100D02*
Y240000D01*
G01X1540600Y241683D02*
X1540892Y241933D01*
X1541058Y242267D01*
X1541100Y242642D01*
X1541058Y242975D01*
X1540850Y243308D01*
X1540600Y243517D01*
X1540350Y243558D01*
X1540058Y243475D01*
X1539850Y243183D01*
X1539767Y242892D01*
Y242517D01*
G01Y242892D02*
X1539642Y243142D01*
X1539433Y243350D01*
X1539183Y243433D01*
X1538933Y243350D01*
X1538725Y243142D01*
X1538600Y242767D01*
X1538642Y242392D01*
X1538808Y242017D01*
G01X1573233Y229496D02*
X1573501Y229548D01*
X1573808Y229703D01*
X1574000Y229961D01*
X1574076Y230323D01*
X1574000Y230684D01*
X1573770Y230994D01*
X1573425Y231149D01*
X1573041D01*
X1572811Y231253D01*
X1572620Y231511D01*
X1572543Y231873D01*
X1572658Y232234D01*
X1572926Y232493D01*
X1573233Y232596D01*
X1573540Y232493D01*
X1573808Y232234D01*
X1573923Y231873D01*
X1573846Y231511D01*
X1573655Y231253D01*
X1573425Y231149D01*
X1573041D01*
X1572696Y230994D01*
X1572466Y230684D01*
X1572390Y230323D01*
X1572466Y229961D01*
X1572658Y229703D01*
X1572965Y229548D01*
X1573233Y229496D01*
G01X1585842Y224267D02*
X1585717Y224017D01*
X1585634Y223725D01*
Y223392D01*
X1585759Y223017D01*
X1585967Y222725D01*
X1586217Y222517D01*
X1586634Y222350D01*
X1587009Y222308D01*
X1587384Y222392D01*
X1587634Y222517D01*
X1587884Y222767D01*
X1588051Y223058D01*
X1588134Y223350D01*
Y223642D01*
X1588051Y223933D01*
X1587926Y224183D01*
X1587759Y224392D01*
G01X1588134Y226450D02*
X1588092Y226742D01*
X1587967Y227075D01*
X1587759Y227283D01*
X1587467Y227367D01*
X1587176Y227283D01*
X1586926Y227033D01*
X1586801Y226658D01*
Y226242D01*
X1586717Y225992D01*
X1586509Y225783D01*
X1586217Y225700D01*
X1585926Y225825D01*
X1585717Y226117D01*
X1585634Y226450D01*
X1585717Y226783D01*
X1585926Y227075D01*
X1586217Y227200D01*
X1586509Y227117D01*
X1586717Y226908D01*
X1586801Y226658D01*
Y226242D01*
X1586926Y225867D01*
X1587176Y225617D01*
X1587467Y225533D01*
X1587759Y225617D01*
X1587967Y225825D01*
X1588092Y226158D01*
X1588134Y226450D01*
G01Y230383D02*
Y228717D01*
X1585634D01*
Y230383D01*
G01X1586842Y229717D02*
Y228717D01*
G01X1588134Y232567D02*
X1587592Y232650D01*
X1587134Y232775D01*
X1586717Y232942D01*
X1586259Y233150D01*
X1585634Y233483D01*
Y231817D01*
G01X1581742Y224267D02*
X1581617Y224017D01*
X1581534Y223725D01*
Y223392D01*
X1581659Y223017D01*
X1581867Y222725D01*
X1582117Y222517D01*
X1582534Y222350D01*
X1582909Y222308D01*
X1583284Y222392D01*
X1583534Y222517D01*
X1583784Y222767D01*
X1583951Y223058D01*
X1584034Y223350D01*
Y223642D01*
X1583951Y223933D01*
X1583826Y224183D01*
X1583659Y224392D01*
G01X1584034Y226450D02*
X1583992Y226742D01*
X1583867Y227075D01*
X1583659Y227283D01*
X1583367Y227367D01*
X1583076Y227283D01*
X1582826Y227033D01*
X1582701Y226658D01*
Y226242D01*
X1582617Y225992D01*
X1582409Y225783D01*
X1582117Y225700D01*
X1581826Y225825D01*
X1581617Y226117D01*
X1581534Y226450D01*
X1581617Y226783D01*
X1581826Y227075D01*
X1582117Y227200D01*
X1582409Y227117D01*
X1582617Y226908D01*
X1582701Y226658D01*
Y226242D01*
X1582826Y225867D01*
X1583076Y225617D01*
X1583367Y225533D01*
X1583659Y225617D01*
X1583867Y225825D01*
X1583992Y226158D01*
X1584034Y226450D01*
G01Y230383D02*
Y228717D01*
X1581534D01*
Y230383D01*
G01X1582742Y229717D02*
Y228717D01*
G01X1583742Y231942D02*
X1583951Y232233D01*
X1584034Y232567D01*
X1583951Y232900D01*
X1583701Y233192D01*
X1583326Y233400D01*
X1582951Y233483D01*
X1582492D01*
X1582117Y233400D01*
X1581784Y233192D01*
X1581617Y232942D01*
X1581534Y232650D01*
X1581617Y232317D01*
X1581784Y232067D01*
X1582034Y231900D01*
X1582367Y231817D01*
X1582659Y231900D01*
X1582951Y232108D01*
X1583117Y232358D01*
X1583159Y232650D01*
X1583076Y232983D01*
X1582867Y233233D01*
X1582492Y233483D01*
G01X1564765Y234947D02*
X1553565D01*
G01D02*
Y252947D01*
G01D02*
X1564765D01*
G01X1580765Y234947D02*
X1591965D01*
G01Y252947D02*
X1580765D01*
G01X1538797Y273685D02*
X1536815D01*
Y272687D01*
G01X1551185D02*
Y273685D01*
X1549203D01*
G01Y259315D02*
X1551185D01*
Y260313D01*
G01X1536815D02*
Y259315D01*
X1538797D01*
G01X1531500Y341500D02*
X1538399D01*
X1538400Y341499D01*
Y337750D01*
G01X1561970Y335120D02*
Y339720D01*
G01X1547100Y334876D02*
X1551733D01*
Y333257D01*
X1561750D01*
Y326377D01*
G01X1538630Y335938D02*
X1545200D01*
G01X1587030Y287179D02*
Y284679D01*
X1588696D01*
G01X1590963D02*
X1591255Y284721D01*
X1591588Y284846D01*
X1591796Y285054D01*
X1591880Y285346D01*
X1591796Y285637D01*
X1591546Y285887D01*
X1591171Y286012D01*
X1590755D01*
X1590505Y286096D01*
X1590296Y286304D01*
X1590213Y286596D01*
X1590338Y286887D01*
X1590630Y287096D01*
X1590963Y287179D01*
X1591296Y287096D01*
X1591588Y286887D01*
X1591713Y286596D01*
X1591630Y286304D01*
X1591421Y286096D01*
X1591171Y286012D01*
X1590755D01*
X1590380Y285887D01*
X1590130Y285637D01*
X1590046Y285346D01*
X1590130Y285054D01*
X1590338Y284846D01*
X1590671Y284721D01*
X1590963Y284679D01*
G01X1594896D02*
X1593230D01*
Y287179D01*
X1594896D01*
G01X1594230Y285971D02*
X1593230D01*
G01X1597163Y284679D02*
Y287179D01*
X1596663Y286679D01*
G01Y284679D02*
X1597663D01*
G01X1565830Y280140D02*
Y283440D01*
X1592630D01*
Y280140D01*
G01X1532355Y325260D02*
Y327760D01*
X1533396D01*
X1533730Y327635D01*
X1533938Y327468D01*
X1534021Y327135D01*
X1533938Y326802D01*
X1533688Y326593D01*
X1533396Y326468D01*
X1532355D01*
G01X1533396D02*
X1534021Y325260D01*
G01X1536205D02*
X1536288Y325802D01*
X1536413Y326260D01*
X1536580Y326677D01*
X1536788Y327135D01*
X1537121Y327760D01*
X1535455D01*
G01X1538471Y325260D02*
Y327760D01*
X1539305D01*
X1539638Y327635D01*
X1539888Y327468D01*
X1540096Y327218D01*
X1540263Y326927D01*
X1540305Y326510D01*
X1540263Y326093D01*
X1540096Y325802D01*
X1539888Y325552D01*
X1539638Y325385D01*
X1539305Y325260D01*
X1538471D01*
G01X1541571Y325760D02*
X1541821Y325468D01*
X1542155Y325302D01*
X1542530Y325260D01*
X1542863Y325302D01*
X1543196Y325510D01*
X1543405Y325760D01*
X1543446Y326010D01*
X1543363Y326302D01*
X1543071Y326510D01*
X1542780Y326593D01*
X1542405D01*
G01X1542780D02*
X1543030Y326718D01*
X1543238Y326927D01*
X1543321Y327177D01*
X1543238Y327427D01*
X1543030Y327635D01*
X1542655Y327760D01*
X1542280Y327718D01*
X1541905Y327552D01*
G01X1544796Y327343D02*
X1545046Y327593D01*
X1545338Y327718D01*
X1545671Y327760D01*
X1546088Y327677D01*
X1546380Y327468D01*
X1546463Y327218D01*
X1546421Y326968D01*
X1546255Y326760D01*
X1545421Y326343D01*
X1545046Y326052D01*
X1544796Y325635D01*
X1544713Y325260D01*
X1546463D01*
G01X1548877Y285040D02*
Y287540D01*
X1549918D01*
X1550252Y287415D01*
X1550460Y287248D01*
X1550543Y286915D01*
X1550460Y286582D01*
X1550210Y286373D01*
X1549918Y286248D01*
X1548877D01*
G01X1549918D02*
X1550543Y285040D01*
G01X1552727D02*
X1552810Y285582D01*
X1552935Y286040D01*
X1553102Y286457D01*
X1553310Y286915D01*
X1553643Y287540D01*
X1551977D01*
G01X1556743Y285040D02*
X1555077D01*
Y287540D01*
X1556743D01*
G01X1556077Y286332D02*
X1555077D01*
G01X1559010Y285040D02*
Y287540D01*
X1558510Y287040D01*
G01Y285040D02*
X1559510D01*
G01X1561318Y287123D02*
X1561568Y287373D01*
X1561860Y287498D01*
X1562193Y287540D01*
X1562610Y287457D01*
X1562902Y287248D01*
X1562985Y286998D01*
X1562943Y286748D01*
X1562777Y286540D01*
X1561943Y286123D01*
X1561568Y285832D01*
X1561318Y285415D01*
X1561235Y285040D01*
X1562985D01*
G01X1548677Y288980D02*
Y291480D01*
X1549718D01*
X1550052Y291355D01*
X1550260Y291188D01*
X1550343Y290855D01*
X1550260Y290522D01*
X1550010Y290313D01*
X1549718Y290188D01*
X1548677D01*
G01X1549718D02*
X1550343Y288980D01*
G01X1552527D02*
X1552610Y289522D01*
X1552735Y289980D01*
X1552902Y290397D01*
X1553110Y290855D01*
X1553443Y291480D01*
X1551777D01*
G01X1554793Y288980D02*
Y291480D01*
X1555627D01*
X1555960Y291355D01*
X1556210Y291188D01*
X1556418Y290938D01*
X1556585Y290647D01*
X1556627Y290230D01*
X1556585Y289813D01*
X1556418Y289522D01*
X1556210Y289272D01*
X1555960Y289105D01*
X1555627Y288980D01*
X1554793D01*
G01X1557893Y289480D02*
X1558143Y289188D01*
X1558477Y289022D01*
X1558852Y288980D01*
X1559185Y289022D01*
X1559518Y289230D01*
X1559727Y289480D01*
X1559768Y289730D01*
X1559685Y290022D01*
X1559393Y290230D01*
X1559102Y290313D01*
X1558727D01*
G01X1559102D02*
X1559352Y290438D01*
X1559560Y290647D01*
X1559643Y290897D01*
X1559560Y291147D01*
X1559352Y291355D01*
X1558977Y291480D01*
X1558602Y291438D01*
X1558227Y291272D01*
G01X1562410Y288980D02*
Y291480D01*
X1560868Y289688D01*
X1562952D01*
G01X1552642Y320383D02*
Y322883D01*
X1553683D01*
X1554017Y322758D01*
X1554225Y322591D01*
X1554308Y322258D01*
X1554225Y321925D01*
X1553975Y321716D01*
X1553683Y321591D01*
X1552642D01*
G01X1553683D02*
X1554308Y320383D01*
G01X1556492D02*
X1556575Y320925D01*
X1556700Y321383D01*
X1556867Y321800D01*
X1557075Y322258D01*
X1557408Y322883D01*
X1555742D01*
G01X1558758Y320383D02*
Y322883D01*
X1559592D01*
X1559925Y322758D01*
X1560175Y322591D01*
X1560383Y322341D01*
X1560550Y322050D01*
X1560592Y321633D01*
X1560550Y321216D01*
X1560383Y320925D01*
X1560175Y320675D01*
X1559925Y320508D01*
X1559592Y320383D01*
X1558758D01*
G01X1561983Y322466D02*
X1562233Y322716D01*
X1562525Y322841D01*
X1562858Y322883D01*
X1563275Y322800D01*
X1563567Y322591D01*
X1563650Y322341D01*
X1563608Y322091D01*
X1563442Y321883D01*
X1562608Y321466D01*
X1562233Y321175D01*
X1561983Y320758D01*
X1561900Y320383D01*
X1563650D01*
G01X1564958Y320758D02*
X1565208Y320550D01*
X1565500Y320425D01*
X1565875Y320383D01*
X1566250Y320466D01*
X1566542Y320633D01*
X1566750Y320925D01*
X1566792Y321258D01*
X1566708Y321591D01*
X1566500Y321800D01*
X1566208Y321966D01*
X1565917Y322008D01*
X1565625Y321966D01*
X1565250Y321800D01*
X1565375Y322883D01*
X1566500D01*
G01X1562592Y316510D02*
Y319010D01*
X1563633D01*
X1563967Y318885D01*
X1564175Y318718D01*
X1564258Y318385D01*
X1564175Y318052D01*
X1563925Y317843D01*
X1563633Y317718D01*
X1562592D01*
G01X1563633D02*
X1564258Y316510D01*
G01X1566442D02*
X1566525Y317052D01*
X1566650Y317510D01*
X1566817Y317927D01*
X1567025Y318385D01*
X1567358Y319010D01*
X1565692D01*
G01X1568708Y316510D02*
Y319010D01*
X1569542D01*
X1569875Y318885D01*
X1570125Y318718D01*
X1570333Y318468D01*
X1570500Y318177D01*
X1570542Y317760D01*
X1570500Y317343D01*
X1570333Y317052D01*
X1570125Y316802D01*
X1569875Y316635D01*
X1569542Y316510D01*
X1568708D01*
G01X1571933Y318593D02*
X1572183Y318843D01*
X1572475Y318968D01*
X1572808Y319010D01*
X1573225Y318927D01*
X1573517Y318718D01*
X1573600Y318468D01*
X1573558Y318218D01*
X1573392Y318010D01*
X1572558Y317593D01*
X1572183Y317302D01*
X1571933Y316885D01*
X1571850Y316510D01*
X1573600D01*
G01X1575117Y316802D02*
X1575408Y316593D01*
X1575742Y316510D01*
X1576075Y316593D01*
X1576367Y316843D01*
X1576575Y317218D01*
X1576658Y317593D01*
Y318052D01*
X1576575Y318427D01*
X1576367Y318760D01*
X1576117Y318927D01*
X1575825Y319010D01*
X1575492Y318927D01*
X1575242Y318760D01*
X1575075Y318510D01*
X1574992Y318177D01*
X1575075Y317885D01*
X1575283Y317593D01*
X1575533Y317427D01*
X1575825Y317385D01*
X1576158Y317468D01*
X1576408Y317677D01*
X1576658Y318052D01*
G01X1549457Y292900D02*
Y295400D01*
X1550498D01*
X1550832Y295275D01*
X1551040Y295108D01*
X1551123Y294775D01*
X1551040Y294442D01*
X1550790Y294233D01*
X1550498Y294108D01*
X1549457D01*
G01X1550498D02*
X1551123Y292900D01*
G01X1553307D02*
X1553390Y293442D01*
X1553515Y293900D01*
X1553682Y294317D01*
X1553890Y294775D01*
X1554223Y295400D01*
X1552557D01*
G01X1555573Y292900D02*
Y295400D01*
X1556407D01*
X1556740Y295275D01*
X1556990Y295108D01*
X1557198Y294858D01*
X1557365Y294567D01*
X1557407Y294150D01*
X1557365Y293733D01*
X1557198Y293442D01*
X1556990Y293192D01*
X1556740Y293025D01*
X1556407Y292900D01*
X1555573D01*
G01X1558673Y293400D02*
X1558923Y293108D01*
X1559257Y292942D01*
X1559632Y292900D01*
X1559965Y292942D01*
X1560298Y293150D01*
X1560507Y293400D01*
X1560548Y293650D01*
X1560465Y293942D01*
X1560173Y294150D01*
X1559882Y294233D01*
X1559507D01*
G01X1559882D02*
X1560132Y294358D01*
X1560340Y294567D01*
X1560423Y294817D01*
X1560340Y295067D01*
X1560132Y295275D01*
X1559757Y295400D01*
X1559382Y295358D01*
X1559007Y295192D01*
G01X1562690Y292900D02*
Y295400D01*
X1562190Y294900D01*
G01Y292900D02*
X1563190D01*
G01X1531457Y285550D02*
Y288050D01*
X1532498D01*
X1532832Y287925D01*
X1533040Y287758D01*
X1533123Y287425D01*
X1533040Y287092D01*
X1532790Y286883D01*
X1532498Y286758D01*
X1531457D01*
G01X1532498D02*
X1533123Y285550D01*
G01X1535307D02*
X1535390Y286092D01*
X1535515Y286550D01*
X1535682Y286967D01*
X1535890Y287425D01*
X1536223Y288050D01*
X1534557D01*
G01X1539323Y285550D02*
X1537657D01*
Y288050D01*
X1539323D01*
G01X1538657Y286842D02*
X1537657D01*
G01X1541590Y285550D02*
Y288050D01*
X1541090Y287550D01*
G01Y285550D02*
X1542090D01*
G01X1545190D02*
Y288050D01*
X1543648Y286258D01*
X1545732D01*
G01X1546600Y312617D02*
X1544100D01*
Y313658D01*
X1544225Y313992D01*
X1544392Y314200D01*
X1544725Y314283D01*
X1545058Y314200D01*
X1545267Y313950D01*
X1545392Y313658D01*
Y312617D01*
G01Y313658D02*
X1546600Y314283D01*
G01Y316467D02*
X1546058Y316550D01*
X1545600Y316675D01*
X1545183Y316842D01*
X1544725Y317050D01*
X1544100Y317383D01*
Y315717D01*
G01Y318400D02*
X1546600Y318983D01*
X1544100Y319650D01*
X1546600Y320317D01*
X1544100Y320900D01*
G01X1546600Y323250D02*
X1544100D01*
X1545892Y321708D01*
Y323792D01*
G01X1585042Y290167D02*
X1584917Y289917D01*
X1584834Y289625D01*
Y289292D01*
X1584959Y288917D01*
X1585167Y288625D01*
X1585417Y288417D01*
X1585834Y288250D01*
X1586209Y288208D01*
X1586584Y288292D01*
X1586834Y288417D01*
X1587084Y288667D01*
X1587251Y288958D01*
X1587334Y289250D01*
Y289542D01*
X1587251Y289833D01*
X1587126Y290083D01*
X1586959Y290292D01*
G01X1587334Y292350D02*
X1587292Y292642D01*
X1587167Y292975D01*
X1586959Y293183D01*
X1586667Y293267D01*
X1586376Y293183D01*
X1586126Y292933D01*
X1586001Y292558D01*
Y292142D01*
X1585917Y291892D01*
X1585709Y291683D01*
X1585417Y291600D01*
X1585126Y291725D01*
X1584917Y292017D01*
X1584834Y292350D01*
X1584917Y292683D01*
X1585126Y292975D01*
X1585417Y293100D01*
X1585709Y293017D01*
X1585917Y292808D01*
X1586001Y292558D01*
Y292142D01*
X1586126Y291767D01*
X1586376Y291517D01*
X1586667Y291433D01*
X1586959Y291517D01*
X1587167Y291725D01*
X1587292Y292058D01*
X1587334Y292350D01*
G01Y296283D02*
Y294617D01*
X1584834D01*
Y296283D01*
G01X1586042Y295617D02*
Y294617D01*
G01X1586834Y297633D02*
X1587126Y297883D01*
X1587292Y298217D01*
X1587334Y298592D01*
X1587292Y298925D01*
X1587084Y299258D01*
X1586834Y299467D01*
X1586584Y299508D01*
X1586292Y299425D01*
X1586084Y299133D01*
X1586001Y298842D01*
Y298467D01*
G01Y298842D02*
X1585876Y299092D01*
X1585667Y299300D01*
X1585417Y299383D01*
X1585167Y299300D01*
X1584959Y299092D01*
X1584834Y298717D01*
X1584876Y298342D01*
X1585042Y297967D01*
G01X1534867Y330992D02*
X1534617Y331117D01*
X1534325Y331200D01*
X1533992D01*
X1533617Y331075D01*
X1533325Y330867D01*
X1533117Y330617D01*
X1532950Y330200D01*
X1532908Y329825D01*
X1532992Y329450D01*
X1533117Y329200D01*
X1533367Y328950D01*
X1533658Y328783D01*
X1533950Y328700D01*
X1534242D01*
X1534533Y328783D01*
X1534783Y328908D01*
X1534992Y329075D01*
G01X1536967Y328700D02*
X1537050Y329242D01*
X1537175Y329700D01*
X1537342Y330117D01*
X1537550Y330575D01*
X1537883Y331200D01*
X1536217D01*
G01X1539233Y328700D02*
Y331200D01*
X1540067D01*
X1540400Y331075D01*
X1540650Y330908D01*
X1540858Y330658D01*
X1541025Y330367D01*
X1541067Y329950D01*
X1541025Y329533D01*
X1540858Y329242D01*
X1540650Y328992D01*
X1540400Y328825D01*
X1540067Y328700D01*
X1539233D01*
G01X1542333Y329075D02*
X1542583Y328867D01*
X1542875Y328742D01*
X1543250Y328700D01*
X1543625Y328783D01*
X1543917Y328950D01*
X1544125Y329242D01*
X1544167Y329575D01*
X1544083Y329908D01*
X1543875Y330117D01*
X1543583Y330283D01*
X1543292Y330325D01*
X1543000Y330283D01*
X1542625Y330117D01*
X1542750Y331200D01*
X1543875D01*
G01X1530417Y334792D02*
X1530167Y334917D01*
X1529875Y335000D01*
X1529542D01*
X1529167Y334875D01*
X1528875Y334667D01*
X1528667Y334417D01*
X1528500Y334000D01*
X1528458Y333625D01*
X1528542Y333250D01*
X1528667Y333000D01*
X1528917Y332750D01*
X1529208Y332583D01*
X1529500Y332500D01*
X1529792D01*
X1530083Y332583D01*
X1530333Y332708D01*
X1530542Y332875D01*
G01X1532600Y332500D02*
Y335000D01*
X1532100Y334500D01*
G01Y332500D02*
X1533100D01*
G01X1536200D02*
Y335000D01*
X1534658Y333208D01*
X1536742D01*
G01X1537550Y335000D02*
X1538133Y332500D01*
X1538800Y335000D01*
X1539467Y332500D01*
X1540050Y335000D01*
G01X1541108Y334583D02*
X1541358Y334833D01*
X1541650Y334958D01*
X1541983Y335000D01*
X1542400Y334917D01*
X1542692Y334708D01*
X1542775Y334458D01*
X1542733Y334208D01*
X1542567Y334000D01*
X1541733Y333583D01*
X1541358Y333292D01*
X1541108Y332875D01*
X1541025Y332500D01*
X1542775D01*
G01X1548772Y330321D02*
X1548522Y330446D01*
X1548230Y330529D01*
X1547897D01*
X1547522Y330404D01*
X1547230Y330196D01*
X1547022Y329946D01*
X1546855Y329529D01*
X1546813Y329154D01*
X1546897Y328779D01*
X1547022Y328529D01*
X1547272Y328279D01*
X1547563Y328112D01*
X1547855Y328029D01*
X1548147D01*
X1548438Y328112D01*
X1548688Y328237D01*
X1548897Y328404D01*
G01X1550872Y328029D02*
X1550955Y328571D01*
X1551080Y329029D01*
X1551247Y329446D01*
X1551455Y329904D01*
X1551788Y330529D01*
X1550122D01*
G01X1553138Y328029D02*
Y330529D01*
X1553972D01*
X1554305Y330404D01*
X1554555Y330237D01*
X1554763Y329987D01*
X1554930Y329696D01*
X1554972Y329279D01*
X1554930Y328862D01*
X1554763Y328571D01*
X1554555Y328321D01*
X1554305Y328154D01*
X1553972Y328029D01*
X1553138D01*
G01X1557655D02*
Y330529D01*
X1556113Y328737D01*
X1558197D01*
G01X1551647Y283642D02*
X1551397Y283767D01*
X1551105Y283850D01*
X1550772D01*
X1550397Y283725D01*
X1550105Y283517D01*
X1549897Y283267D01*
X1549730Y282850D01*
X1549688Y282475D01*
X1549772Y282100D01*
X1549897Y281850D01*
X1550147Y281600D01*
X1550438Y281433D01*
X1550730Y281350D01*
X1551022D01*
X1551313Y281433D01*
X1551563Y281558D01*
X1551772Y281725D01*
G01X1553747Y281350D02*
X1553830Y281892D01*
X1553955Y282350D01*
X1554122Y282767D01*
X1554330Y283225D01*
X1554663Y283850D01*
X1552997D01*
G01X1557763Y281350D02*
X1556097D01*
Y283850D01*
X1557763D01*
G01X1557097Y282642D02*
X1556097D01*
G01X1560030Y281350D02*
Y283850D01*
X1559530Y283350D01*
G01Y281350D02*
X1560530D01*
G01X1563130Y283850D02*
X1562797Y283767D01*
X1562547Y283558D01*
X1562380Y283308D01*
X1562255Y282975D01*
X1562213Y282600D01*
X1562255Y282225D01*
X1562380Y281892D01*
X1562547Y281642D01*
X1562797Y281433D01*
X1563130Y281350D01*
X1563463Y281433D01*
X1563713Y281642D01*
X1563880Y281892D01*
X1564005Y282225D01*
X1564047Y282600D01*
X1564005Y282975D01*
X1563880Y283308D01*
X1563713Y283558D01*
X1563463Y283767D01*
X1563130Y283850D01*
G01X1531472Y311137D02*
Y306687D01*
X1533972D01*
Y311137D01*
G01X1578037Y309993D02*
X1579930D01*
G01D02*
X1578037Y306714D01*
G01D02*
X1576144Y309993D01*
G01D02*
X1578037D01*
G01Y313582D02*
Y309993D01*
G01X1576144Y306714D02*
X1579930D01*
G01X1578037Y302291D02*
Y306714D01*
G01X1581044Y286993D02*
X1582836D01*
X1583211Y287160D01*
X1583461Y287493D01*
X1583544Y287910D01*
X1583461Y288327D01*
X1583211Y288660D01*
X1582836Y288827D01*
X1581044D01*
G01X1583544Y291010D02*
X1583502Y291302D01*
X1583377Y291635D01*
X1583169Y291843D01*
X1582877Y291927D01*
X1582586Y291843D01*
X1582336Y291593D01*
X1582211Y291218D01*
Y290802D01*
X1582127Y290552D01*
X1581919Y290343D01*
X1581627Y290260D01*
X1581336Y290385D01*
X1581127Y290677D01*
X1581044Y291010D01*
X1581127Y291343D01*
X1581336Y291635D01*
X1581627Y291760D01*
X1581919Y291677D01*
X1582127Y291468D01*
X1582211Y291218D01*
Y290802D01*
X1582336Y290427D01*
X1582586Y290177D01*
X1582877Y290093D01*
X1583169Y290177D01*
X1583377Y290385D01*
X1583502Y290718D01*
X1583544Y291010D01*
G01Y294943D02*
Y293277D01*
X1581044D01*
Y294943D01*
G01X1582252Y294277D02*
Y293277D01*
G01X1581461Y296418D02*
X1581211Y296668D01*
X1581086Y296960D01*
X1581044Y297293D01*
X1581127Y297710D01*
X1581336Y298002D01*
X1581586Y298085D01*
X1581836Y298043D01*
X1582044Y297877D01*
X1582461Y297043D01*
X1582752Y296668D01*
X1583169Y296418D01*
X1583544Y296335D01*
Y298085D01*
G01X1567447Y292974D02*
Y290474D01*
G01X1569697Y297724D02*
X1572947D01*
Y294224D01*
G01X1569697Y285724D02*
X1572947D01*
Y289224D01*
G01X1563840Y337320D02*
X1563507Y337362D01*
X1563215Y337528D01*
X1562965Y337778D01*
X1562798Y338070D01*
X1562715Y338403D01*
Y338737D01*
X1562798Y339070D01*
X1562965Y339362D01*
X1563215Y339612D01*
X1563507Y339778D01*
X1563840Y339820D01*
X1564173Y339778D01*
X1564465Y339612D01*
X1564715Y339362D01*
X1564882Y339070D01*
X1564965Y338737D01*
Y338403D01*
X1564882Y338070D01*
X1564715Y337778D01*
X1564465Y337528D01*
X1564173Y337362D01*
X1563840Y337320D01*
G01X1564173Y337987D02*
X1564673Y337320D01*
G01X1566940D02*
X1567232Y337362D01*
X1567565Y337487D01*
X1567773Y337695D01*
X1567857Y337987D01*
X1567773Y338278D01*
X1567523Y338528D01*
X1567148Y338653D01*
X1566732D01*
X1566482Y338737D01*
X1566273Y338945D01*
X1566190Y339237D01*
X1566315Y339528D01*
X1566607Y339737D01*
X1566940Y339820D01*
X1567273Y339737D01*
X1567565Y339528D01*
X1567690Y339237D01*
X1567607Y338945D01*
X1567398Y338737D01*
X1567148Y338653D01*
X1566732D01*
X1566357Y338528D01*
X1566107Y338278D01*
X1566023Y337987D01*
X1566107Y337695D01*
X1566315Y337487D01*
X1566648Y337362D01*
X1566940Y337320D01*
G01X1569123D02*
Y339820D01*
X1569957D01*
X1570290Y339695D01*
X1570540Y339528D01*
X1570748Y339278D01*
X1570915Y338987D01*
X1570957Y338570D01*
X1570915Y338153D01*
X1570748Y337862D01*
X1570540Y337612D01*
X1570290Y337445D01*
X1569957Y337320D01*
X1569123D01*
G01X1572348Y339403D02*
X1572598Y339653D01*
X1572890Y339778D01*
X1573223Y339820D01*
X1573640Y339737D01*
X1573932Y339528D01*
X1574015Y339278D01*
X1573973Y339028D01*
X1573807Y338820D01*
X1572973Y338403D01*
X1572598Y338112D01*
X1572348Y337695D01*
X1572265Y337320D01*
X1574015D01*
G01X1562581Y328176D02*
Y324926D01*
X1566081D01*
G01X1574581Y328176D02*
Y324926D01*
X1571081D01*
G01X1569831Y330426D02*
X1567331D01*
G01X1550176Y310919D02*
X1547676D01*
Y311960D01*
X1547801Y312294D01*
X1547968Y312502D01*
X1548301Y312585D01*
X1548634Y312502D01*
X1548843Y312252D01*
X1548968Y311960D01*
Y310919D01*
G01Y311960D02*
X1550176Y312585D01*
G01Y314769D02*
X1549634Y314852D01*
X1549176Y314977D01*
X1548759Y315144D01*
X1548301Y315352D01*
X1547676Y315685D01*
Y314019D01*
G01X1550176Y317035D02*
X1547676D01*
Y317869D01*
X1547801Y318202D01*
X1547968Y318452D01*
X1548218Y318660D01*
X1548509Y318827D01*
X1548926Y318869D01*
X1549343Y318827D01*
X1549634Y318660D01*
X1549884Y318452D01*
X1550051Y318202D01*
X1550176Y317869D01*
Y317035D01*
G01X1549676Y320135D02*
X1549968Y320385D01*
X1550134Y320719D01*
X1550176Y321094D01*
X1550134Y321427D01*
X1549926Y321760D01*
X1549676Y321969D01*
X1549426Y322010D01*
X1549134Y321927D01*
X1548926Y321635D01*
X1548843Y321344D01*
Y320969D01*
G01Y321344D02*
X1548718Y321594D01*
X1548509Y321802D01*
X1548259Y321885D01*
X1548009Y321802D01*
X1547801Y321594D01*
X1547676Y321219D01*
X1547718Y320844D01*
X1547884Y320469D01*
G01X1549676Y323235D02*
X1549968Y323485D01*
X1550134Y323819D01*
X1550176Y324194D01*
X1550134Y324527D01*
X1549926Y324860D01*
X1549676Y325069D01*
X1549426Y325110D01*
X1549134Y325027D01*
X1548926Y324735D01*
X1548843Y324444D01*
Y324069D01*
G01Y324444D02*
X1548718Y324694D01*
X1548509Y324902D01*
X1548259Y324985D01*
X1548009Y324902D01*
X1547801Y324694D01*
X1547676Y324319D01*
X1547718Y323944D01*
X1547884Y323569D01*
G01X1539300Y311400D02*
X1543300D01*
Y318800D01*
G01X1548133Y350600D02*
Y357600D01*
X1551600Y351767D01*
X1555067Y357600D01*
Y350600D01*
G01X1542200Y349300D02*
X1529400D01*
G01X1563400Y342600D02*
Y358299D01*
X1563399Y358300D01*
X1554500D01*
G01X1550800D02*
X1546201D01*
X1546200Y358299D01*
Y349301D01*
X1546199Y349300D01*
X1544800D01*
G01X1586400Y399267D02*
X1583900D01*
Y400308D01*
X1584025Y400642D01*
X1584192Y400850D01*
X1584525Y400933D01*
X1584858Y400850D01*
X1585067Y400600D01*
X1585192Y400308D01*
Y399267D01*
G01Y400308D02*
X1586400Y400933D01*
G01Y403200D02*
X1586358Y403492D01*
X1586233Y403825D01*
X1586025Y404033D01*
X1585733Y404117D01*
X1585442Y404033D01*
X1585192Y403783D01*
X1585067Y403408D01*
Y402992D01*
X1584983Y402742D01*
X1584775Y402533D01*
X1584483Y402450D01*
X1584192Y402575D01*
X1583983Y402867D01*
X1583900Y403200D01*
X1583983Y403533D01*
X1584192Y403825D01*
X1584483Y403950D01*
X1584775Y403867D01*
X1584983Y403658D01*
X1585067Y403408D01*
Y402992D01*
X1585192Y402617D01*
X1585442Y402367D01*
X1585733Y402283D01*
X1586025Y402367D01*
X1586233Y402575D01*
X1586358Y402908D01*
X1586400Y403200D01*
G01X1584108Y407217D02*
X1583983Y406967D01*
X1583900Y406675D01*
Y406342D01*
X1584025Y405967D01*
X1584233Y405675D01*
X1584483Y405467D01*
X1584900Y405300D01*
X1585275Y405258D01*
X1585650Y405342D01*
X1585900Y405467D01*
X1586150Y405717D01*
X1586317Y406008D01*
X1586400Y406300D01*
Y406592D01*
X1586317Y406883D01*
X1586192Y407133D01*
X1586025Y407342D01*
G01X1584317Y408608D02*
X1584067Y408858D01*
X1583942Y409150D01*
X1583900Y409483D01*
X1583983Y409900D01*
X1584192Y410192D01*
X1584442Y410275D01*
X1584692Y410233D01*
X1584900Y410067D01*
X1585317Y409233D01*
X1585608Y408858D01*
X1586025Y408608D01*
X1586400Y408525D01*
Y410275D01*
G01X1585900Y411583D02*
X1586192Y411833D01*
X1586358Y412167D01*
X1586400Y412542D01*
X1586358Y412875D01*
X1586150Y413208D01*
X1585900Y413417D01*
X1585650Y413458D01*
X1585358Y413375D01*
X1585150Y413083D01*
X1585067Y412792D01*
Y412417D01*
G01Y412792D02*
X1584942Y413042D01*
X1584733Y413250D01*
X1584483Y413333D01*
X1584233Y413250D01*
X1584025Y413042D01*
X1583900Y412667D01*
X1583942Y412292D01*
X1584108Y411917D01*
G01X1586400Y381567D02*
X1583900D01*
Y382608D01*
X1584025Y382942D01*
X1584192Y383150D01*
X1584525Y383233D01*
X1584858Y383150D01*
X1585067Y382900D01*
X1585192Y382608D01*
Y381567D01*
G01Y382608D02*
X1586400Y383233D01*
G01X1584317Y384708D02*
X1584067Y384958D01*
X1583942Y385250D01*
X1583900Y385583D01*
X1583983Y386000D01*
X1584192Y386292D01*
X1584442Y386375D01*
X1584692Y386333D01*
X1584900Y386167D01*
X1585317Y385333D01*
X1585608Y384958D01*
X1586025Y384708D01*
X1586400Y384625D01*
Y386375D01*
G01Y387642D02*
X1583900D01*
X1586400Y389558D01*
X1583900D01*
G01X1586400Y391700D02*
X1583900D01*
X1584400Y391200D01*
G01X1586400D02*
Y392200D01*
G01X1584317Y394008D02*
X1584067Y394258D01*
X1583942Y394550D01*
X1583900Y394883D01*
X1583983Y395300D01*
X1584192Y395592D01*
X1584442Y395675D01*
X1584692Y395633D01*
X1584900Y395467D01*
X1585317Y394633D01*
X1585608Y394258D01*
X1586025Y394008D01*
X1586400Y393925D01*
Y395675D01*
G01X1572747Y343621D02*
Y346121D01*
X1573788D01*
X1574122Y345996D01*
X1574330Y345829D01*
X1574413Y345496D01*
X1574330Y345163D01*
X1574080Y344954D01*
X1573788Y344829D01*
X1572747D01*
G01X1573788D02*
X1574413Y343621D01*
G01X1575888Y345704D02*
X1576138Y345954D01*
X1576430Y346079D01*
X1576763Y346121D01*
X1577180Y346038D01*
X1577472Y345829D01*
X1577555Y345579D01*
X1577513Y345329D01*
X1577347Y345121D01*
X1576513Y344704D01*
X1576138Y344413D01*
X1575888Y343996D01*
X1575805Y343621D01*
X1577555D01*
G01X1578947D02*
Y346121D01*
X1579947D01*
X1580280Y345996D01*
X1580530Y345704D01*
X1580613Y345371D01*
X1580530Y345038D01*
X1580322Y344788D01*
X1579947Y344663D01*
X1578947D01*
G01X1582880Y343621D02*
Y346121D01*
X1582380Y345621D01*
G01Y343621D02*
X1583380D01*
G01X1585897D02*
X1585980Y344163D01*
X1586105Y344621D01*
X1586272Y345038D01*
X1586480Y345496D01*
X1586813Y346121D01*
X1585147D01*
G01X1588108Y392067D02*
X1587983Y391817D01*
X1587900Y391525D01*
Y391192D01*
X1588025Y390817D01*
X1588233Y390525D01*
X1588483Y390317D01*
X1588900Y390150D01*
X1589275Y390108D01*
X1589650Y390192D01*
X1589900Y390317D01*
X1590150Y390567D01*
X1590317Y390858D01*
X1590400Y391150D01*
Y391442D01*
X1590317Y391733D01*
X1590192Y391983D01*
X1590025Y392192D01*
G01X1590400Y394250D02*
X1590358Y394542D01*
X1590233Y394875D01*
X1590025Y395083D01*
X1589733Y395167D01*
X1589442Y395083D01*
X1589192Y394833D01*
X1589067Y394458D01*
Y394042D01*
X1588983Y393792D01*
X1588775Y393583D01*
X1588483Y393500D01*
X1588192Y393625D01*
X1587983Y393917D01*
X1587900Y394250D01*
X1587983Y394583D01*
X1588192Y394875D01*
X1588483Y395000D01*
X1588775Y394917D01*
X1588983Y394708D01*
X1589067Y394458D01*
Y394042D01*
X1589192Y393667D01*
X1589442Y393417D01*
X1589733Y393333D01*
X1590025Y393417D01*
X1590233Y393625D01*
X1590358Y393958D01*
X1590400Y394250D01*
G01X1588108Y398267D02*
X1587983Y398017D01*
X1587900Y397725D01*
Y397392D01*
X1588025Y397017D01*
X1588233Y396725D01*
X1588483Y396517D01*
X1588900Y396350D01*
X1589275Y396308D01*
X1589650Y396392D01*
X1589900Y396517D01*
X1590150Y396767D01*
X1590317Y397058D01*
X1590400Y397350D01*
Y397642D01*
X1590317Y397933D01*
X1590192Y398183D01*
X1590025Y398392D01*
G01X1590400Y400450D02*
X1587900D01*
X1588400Y399950D01*
G01X1590400D02*
Y400950D01*
G01X1548152Y360482D02*
X1547997Y360635D01*
X1547738Y360750D01*
X1547377Y360827D01*
X1547067Y360750D01*
X1546860Y360597D01*
X1546705Y360328D01*
Y359293D01*
X1549805D01*
Y360558D01*
X1549598Y360827D01*
X1549288Y360980D01*
X1548927Y361057D01*
X1548565Y360980D01*
X1548255Y360750D01*
X1548152Y360482D01*
Y359293D01*
G01X1549805Y362432D02*
X1546705D01*
Y363198D01*
X1546860Y363505D01*
X1547067Y363735D01*
X1547377Y363927D01*
X1547738Y364080D01*
X1548255Y364118D01*
X1548772Y364080D01*
X1549133Y363927D01*
X1549443Y363735D01*
X1549650Y363505D01*
X1549805Y363198D01*
Y362432D01*
G01X1544088Y360385D02*
X1543933Y360538D01*
X1543674Y360653D01*
X1543313Y360730D01*
X1543003Y360653D01*
X1542796Y360500D01*
X1542641Y360231D01*
Y359196D01*
X1545741D01*
Y360461D01*
X1545534Y360730D01*
X1545224Y360883D01*
X1544863Y360960D01*
X1544501Y360883D01*
X1544191Y360653D01*
X1544088Y360385D01*
Y359196D01*
G01Y363485D02*
X1543933Y363638D01*
X1543674Y363753D01*
X1543313Y363830D01*
X1543003Y363753D01*
X1542796Y363600D01*
X1542641Y363331D01*
Y362296D01*
X1545741D01*
Y363561D01*
X1545534Y363830D01*
X1545224Y363983D01*
X1544863Y364060D01*
X1544501Y363983D01*
X1544191Y363753D01*
X1544088Y363485D01*
Y362296D01*
G01X1541774Y359023D02*
X1538674Y359981D01*
X1541774Y360939D01*
G01X1540689Y360594D02*
Y359368D01*
G01X1541774Y363081D02*
X1540379D01*
X1538674Y362314D01*
G01Y363848D02*
X1540379Y363081D01*
G01X1538097Y359120D02*
X1534997Y360078D01*
X1538097Y361036D01*
G01X1537012Y360691D02*
Y359465D01*
G01X1534997Y362220D02*
X1538097Y363178D01*
X1534997Y364136D01*
G01X1534226Y359120D02*
X1531126Y360078D01*
X1534226Y361036D01*
G01X1533141Y360691D02*
Y359465D01*
G01X1534226Y362411D02*
X1531126D01*
Y363370D01*
X1531281Y363676D01*
X1531488Y363868D01*
X1531901Y363945D01*
X1532314Y363868D01*
X1532573Y363638D01*
X1532728Y363370D01*
Y362411D01*
G01Y363370D02*
X1534226Y363945D01*
G01X1573027Y360257D02*
X1572872Y360410D01*
X1572613Y360525D01*
X1572252Y360602D01*
X1571942Y360525D01*
X1571735Y360372D01*
X1571580Y360103D01*
Y359068D01*
X1574680D01*
Y360333D01*
X1574473Y360602D01*
X1574163Y360755D01*
X1573802Y360832D01*
X1573440Y360755D01*
X1573130Y360525D01*
X1573027Y360257D01*
Y359068D01*
G01X1571580Y362207D02*
X1573802D01*
X1574267Y362360D01*
X1574577Y362667D01*
X1574680Y363050D01*
X1574577Y363433D01*
X1574267Y363740D01*
X1573802Y363893D01*
X1571580D01*
G01X1564977Y360447D02*
X1564822Y360600D01*
X1564563Y360715D01*
X1564202Y360792D01*
X1563892Y360715D01*
X1563685Y360562D01*
X1563530Y360293D01*
Y359258D01*
X1566630D01*
Y360523D01*
X1566423Y360792D01*
X1566113Y360945D01*
X1565752Y361022D01*
X1565390Y360945D01*
X1565080Y360715D01*
X1564977Y360447D01*
Y359258D01*
G01X1566630Y362358D02*
X1563530D01*
X1566630Y364122D01*
X1563530D01*
G01X1568987Y360287D02*
X1568832Y360440D01*
X1568573Y360555D01*
X1568212Y360632D01*
X1567902Y360555D01*
X1567695Y360402D01*
X1567540Y360133D01*
Y359098D01*
X1570640D01*
Y360363D01*
X1570433Y360632D01*
X1570123Y360785D01*
X1569762Y360862D01*
X1569400Y360785D01*
X1569090Y360555D01*
X1568987Y360287D01*
Y359098D01*
G01X1570640Y362313D02*
X1567540D01*
Y363272D01*
X1567695Y363578D01*
X1567902Y363770D01*
X1568315Y363847D01*
X1568728Y363770D01*
X1568987Y363540D01*
X1569142Y363272D01*
Y362313D01*
G01Y363272D02*
X1570640Y363847D01*
G01X1560875Y360482D02*
X1560720Y360635D01*
X1560461Y360750D01*
X1560100Y360827D01*
X1559790Y360750D01*
X1559583Y360597D01*
X1559428Y360328D01*
Y359293D01*
X1562528D01*
Y360558D01*
X1562321Y360827D01*
X1562011Y360980D01*
X1561650Y361057D01*
X1561288Y360980D01*
X1560978Y360750D01*
X1560875Y360482D01*
Y359293D01*
G01X1559428Y362508D02*
X1562528D01*
Y364042D01*
G01X1556811Y360385D02*
X1556656Y360538D01*
X1556397Y360653D01*
X1556036Y360730D01*
X1555726Y360653D01*
X1555519Y360500D01*
X1555364Y360231D01*
Y359196D01*
X1558464D01*
Y360461D01*
X1558257Y360730D01*
X1557947Y360883D01*
X1557586Y360960D01*
X1557224Y360883D01*
X1556914Y360653D01*
X1556811Y360385D01*
Y359196D01*
G01X1557844Y362411D02*
X1558154Y362603D01*
X1558361Y362833D01*
X1558464Y363101D01*
X1558361Y363408D01*
X1558154Y363638D01*
X1557844Y363868D01*
X1557431Y363945D01*
X1555364D01*
G01X1552409Y360530D02*
X1552254Y360683D01*
X1551995Y360798D01*
X1551634Y360875D01*
X1551324Y360798D01*
X1551117Y360645D01*
X1550962Y360376D01*
Y359341D01*
X1554062D01*
Y360606D01*
X1553855Y360875D01*
X1553545Y361028D01*
X1553184Y361105D01*
X1552822Y361028D01*
X1552512Y360798D01*
X1552409Y360530D01*
Y359341D01*
G01X1554062Y362595D02*
X1550962D01*
Y364051D01*
G01X1552460Y363515D02*
Y362595D01*
G01X1580608Y360483D02*
X1580453Y360253D01*
X1580350Y359985D01*
Y359678D01*
X1580505Y359333D01*
X1580763Y359065D01*
X1581073Y358873D01*
X1581590Y358720D01*
X1582055Y358682D01*
X1582520Y358758D01*
X1582830Y358873D01*
X1583140Y359103D01*
X1583347Y359372D01*
X1583450Y359640D01*
Y359908D01*
X1583347Y360177D01*
X1583192Y360407D01*
X1582985Y360598D01*
G01X1583450Y361782D02*
X1580350Y362740D01*
X1583450Y363698D01*
G01X1582365Y363353D02*
Y362127D01*
G01X1577227Y360007D02*
X1577072Y360160D01*
X1576813Y360275D01*
X1576452Y360352D01*
X1576142Y360275D01*
X1575935Y360122D01*
X1575780Y359853D01*
Y358818D01*
X1578880D01*
Y360083D01*
X1578673Y360352D01*
X1578363Y360505D01*
X1578002Y360582D01*
X1577640Y360505D01*
X1577330Y360275D01*
X1577227Y360007D01*
Y358818D01*
G01X1575780Y361650D02*
X1578880Y362187D01*
X1575780Y362800D01*
X1578880Y363413D01*
X1575780Y363950D01*
G01X1584400Y465367D02*
X1586267Y458367D01*
X1588400Y465367D01*
X1590533Y458367D01*
X1592400Y465367D01*
G01X1592900Y467000D02*
X1583500D01*
Y463600D01*
G01Y461600D02*
Y457300D01*
X1603700D01*
Y454200D01*
G01X1583297Y441473D02*
Y443973D01*
X1584338D01*
X1584672Y443848D01*
X1584880Y443681D01*
X1584963Y443348D01*
X1584880Y443015D01*
X1584630Y442806D01*
X1584338Y442681D01*
X1583297D01*
G01X1584338D02*
X1584963Y441473D01*
G01X1587230D02*
X1587522Y441515D01*
X1587855Y441640D01*
X1588063Y441848D01*
X1588147Y442140D01*
X1588063Y442431D01*
X1587813Y442681D01*
X1587438Y442806D01*
X1587022D01*
X1586772Y442890D01*
X1586563Y443098D01*
X1586480Y443390D01*
X1586605Y443681D01*
X1586897Y443890D01*
X1587230Y443973D01*
X1587563Y443890D01*
X1587855Y443681D01*
X1587980Y443390D01*
X1587897Y443098D01*
X1587688Y442890D01*
X1587438Y442806D01*
X1587022D01*
X1586647Y442681D01*
X1586397Y442431D01*
X1586313Y442140D01*
X1586397Y441848D01*
X1586605Y441640D01*
X1586938Y441515D01*
X1587230Y441473D01*
G01X1590663Y442806D02*
X1590830Y442931D01*
X1590955Y443140D01*
X1591038Y443431D01*
X1590955Y443681D01*
X1590788Y443848D01*
X1590497Y443973D01*
X1589372D01*
Y441473D01*
X1590747D01*
X1591038Y441640D01*
X1591205Y441890D01*
X1591288Y442181D01*
X1591205Y442473D01*
X1590955Y442723D01*
X1590663Y442806D01*
X1589372D01*
G01X1592513Y441973D02*
X1592763Y441681D01*
X1593097Y441515D01*
X1593472Y441473D01*
X1593805Y441515D01*
X1594138Y441723D01*
X1594347Y441973D01*
X1594388Y442223D01*
X1594305Y442515D01*
X1594013Y442723D01*
X1593722Y442806D01*
X1593347D01*
G01X1593722D02*
X1593972Y442931D01*
X1594180Y443140D01*
X1594263Y443390D01*
X1594180Y443640D01*
X1593972Y443848D01*
X1593597Y443973D01*
X1593222Y443931D01*
X1592847Y443765D01*
G01X1596530Y443973D02*
X1596197Y443890D01*
X1595947Y443681D01*
X1595780Y443431D01*
X1595655Y443098D01*
X1595613Y442723D01*
X1595655Y442348D01*
X1595780Y442015D01*
X1595947Y441765D01*
X1596197Y441556D01*
X1596530Y441473D01*
X1596863Y441556D01*
X1597113Y441765D01*
X1597280Y442015D01*
X1597405Y442348D01*
X1597447Y442723D01*
X1597405Y443098D01*
X1597280Y443431D01*
X1597113Y443681D01*
X1596863Y443890D01*
X1596530Y443973D01*
G01X1583367Y444967D02*
Y447467D01*
X1584408D01*
X1584742Y447342D01*
X1584950Y447175D01*
X1585033Y446842D01*
X1584950Y446509D01*
X1584700Y446300D01*
X1584408Y446175D01*
X1583367D01*
G01X1584408D02*
X1585033Y444967D01*
G01X1586508Y447050D02*
X1586758Y447300D01*
X1587050Y447425D01*
X1587383Y447467D01*
X1587800Y447384D01*
X1588092Y447175D01*
X1588175Y446925D01*
X1588133Y446675D01*
X1587967Y446467D01*
X1587133Y446050D01*
X1586758Y445759D01*
X1586508Y445342D01*
X1586425Y444967D01*
X1588175D01*
G01X1589483Y445342D02*
X1589733Y445134D01*
X1590025Y445009D01*
X1590400Y444967D01*
X1590775Y445050D01*
X1591067Y445217D01*
X1591275Y445509D01*
X1591317Y445842D01*
X1591233Y446175D01*
X1591025Y446384D01*
X1590733Y446550D01*
X1590442Y446592D01*
X1590150Y446550D01*
X1589775Y446384D01*
X1589900Y447467D01*
X1591025D01*
G01X1592250D02*
X1592833Y444967D01*
X1593500Y447467D01*
X1594167Y444967D01*
X1594750Y447467D01*
G01X1596600Y444967D02*
Y447467D01*
X1596100Y446967D01*
G01Y444967D02*
X1597100D01*
G01X1600200D02*
Y447467D01*
X1598658Y445675D01*
X1600742D01*
G01X1602800Y447467D02*
X1602467Y447384D01*
X1602217Y447175D01*
X1602050Y446925D01*
X1601925Y446592D01*
X1601883Y446217D01*
X1601925Y445842D01*
X1602050Y445509D01*
X1602217Y445259D01*
X1602467Y445050D01*
X1602800Y444967D01*
X1603133Y445050D01*
X1603383Y445259D01*
X1603550Y445509D01*
X1603675Y445842D01*
X1603717Y446217D01*
X1603675Y446592D01*
X1603550Y446925D01*
X1603383Y447175D01*
X1603133Y447384D01*
X1602800Y447467D01*
G01X1590300Y406117D02*
X1587800D01*
Y407158D01*
X1587925Y407492D01*
X1588092Y407700D01*
X1588425Y407783D01*
X1588758Y407700D01*
X1588967Y407450D01*
X1589092Y407158D01*
Y406117D01*
G01Y407158D02*
X1590300Y407783D01*
G01X1588217Y409258D02*
X1587967Y409508D01*
X1587842Y409800D01*
X1587800Y410133D01*
X1587883Y410550D01*
X1588092Y410842D01*
X1588342Y410925D01*
X1588592Y410883D01*
X1588800Y410717D01*
X1589217Y409883D01*
X1589508Y409508D01*
X1589925Y409258D01*
X1590300Y409175D01*
Y410925D01*
G01Y412192D02*
X1587800D01*
X1590300Y414108D01*
X1587800D01*
G01X1590008Y415542D02*
X1590217Y415833D01*
X1590300Y416167D01*
X1590217Y416500D01*
X1589967Y416792D01*
X1589592Y417000D01*
X1589217Y417083D01*
X1588758D01*
X1588383Y417000D01*
X1588050Y416792D01*
X1587883Y416542D01*
X1587800Y416250D01*
X1587883Y415917D01*
X1588050Y415667D01*
X1588300Y415500D01*
X1588633Y415417D01*
X1588925Y415500D01*
X1589217Y415708D01*
X1589383Y415958D01*
X1589425Y416250D01*
X1589342Y416583D01*
X1589133Y416833D01*
X1588758Y417083D01*
G01X1583567Y421500D02*
Y424000D01*
X1584608D01*
X1584942Y423875D01*
X1585150Y423708D01*
X1585233Y423375D01*
X1585150Y423042D01*
X1584900Y422833D01*
X1584608Y422708D01*
X1583567D01*
G01X1584608D02*
X1585233Y421500D01*
G01X1587500D02*
X1587792Y421542D01*
X1588125Y421667D01*
X1588333Y421875D01*
X1588417Y422167D01*
X1588333Y422458D01*
X1588083Y422708D01*
X1587708Y422833D01*
X1587292D01*
X1587042Y422917D01*
X1586833Y423125D01*
X1586750Y423417D01*
X1586875Y423708D01*
X1587167Y423917D01*
X1587500Y424000D01*
X1587833Y423917D01*
X1588125Y423708D01*
X1588250Y423417D01*
X1588167Y423125D01*
X1587958Y422917D01*
X1587708Y422833D01*
X1587292D01*
X1586917Y422708D01*
X1586667Y422458D01*
X1586583Y422167D01*
X1586667Y421875D01*
X1586875Y421667D01*
X1587208Y421542D01*
X1587500Y421500D01*
G01X1591517Y423792D02*
X1591267Y423917D01*
X1590975Y424000D01*
X1590642D01*
X1590267Y423875D01*
X1589975Y423667D01*
X1589767Y423417D01*
X1589600Y423000D01*
X1589558Y422625D01*
X1589642Y422250D01*
X1589767Y422000D01*
X1590017Y421750D01*
X1590308Y421583D01*
X1590600Y421500D01*
X1590892D01*
X1591183Y421583D01*
X1591433Y421708D01*
X1591642Y421875D01*
G01X1593700Y421500D02*
Y424000D01*
X1593200Y423500D01*
G01Y421500D02*
X1594200D01*
G01X1596008Y423583D02*
X1596258Y423833D01*
X1596550Y423958D01*
X1596883Y424000D01*
X1597300Y423917D01*
X1597592Y423708D01*
X1597675Y423458D01*
X1597633Y423208D01*
X1597467Y423000D01*
X1596633Y422583D01*
X1596258Y422292D01*
X1596008Y421875D01*
X1595925Y421500D01*
X1597675D01*
G01X1583467Y428767D02*
Y431267D01*
X1584508D01*
X1584842Y431142D01*
X1585050Y430975D01*
X1585133Y430642D01*
X1585050Y430309D01*
X1584800Y430100D01*
X1584508Y429975D01*
X1583467D01*
G01X1584508D02*
X1585133Y428767D01*
G01X1586608Y430850D02*
X1586858Y431100D01*
X1587150Y431225D01*
X1587483Y431267D01*
X1587900Y431184D01*
X1588192Y430975D01*
X1588275Y430725D01*
X1588233Y430475D01*
X1588067Y430267D01*
X1587233Y429850D01*
X1586858Y429559D01*
X1586608Y429142D01*
X1586525Y428767D01*
X1588275D01*
G01X1589542D02*
Y431267D01*
X1591458Y428767D01*
Y431267D01*
G01X1592808Y430850D02*
X1593058Y431100D01*
X1593350Y431225D01*
X1593683Y431267D01*
X1594100Y431184D01*
X1594392Y430975D01*
X1594475Y430725D01*
X1594433Y430475D01*
X1594267Y430267D01*
X1593433Y429850D01*
X1593058Y429559D01*
X1592808Y429142D01*
X1592725Y428767D01*
X1594475D01*
G01X1596700D02*
X1596992Y428809D01*
X1597325Y428934D01*
X1597533Y429142D01*
X1597617Y429434D01*
X1597533Y429725D01*
X1597283Y429975D01*
X1596908Y430100D01*
X1596492D01*
X1596242Y430184D01*
X1596033Y430392D01*
X1595950Y430684D01*
X1596075Y430975D01*
X1596367Y431184D01*
X1596700Y431267D01*
X1597033Y431184D01*
X1597325Y430975D01*
X1597450Y430684D01*
X1597367Y430392D01*
X1597158Y430184D01*
X1596908Y430100D01*
X1596492D01*
X1596117Y429975D01*
X1595867Y429725D01*
X1595783Y429434D01*
X1595867Y429142D01*
X1596075Y428934D01*
X1596408Y428809D01*
X1596700Y428767D01*
G01X1584917Y434300D02*
Y436800D01*
X1585958D01*
X1586292Y436675D01*
X1586500Y436508D01*
X1586583Y436175D01*
X1586500Y435842D01*
X1586250Y435633D01*
X1585958Y435508D01*
X1584917D01*
G01X1585958D02*
X1586583Y434300D01*
G01X1588850D02*
X1589142Y434342D01*
X1589475Y434467D01*
X1589683Y434675D01*
X1589767Y434967D01*
X1589683Y435258D01*
X1589433Y435508D01*
X1589058Y435633D01*
X1588642D01*
X1588392Y435717D01*
X1588183Y435925D01*
X1588100Y436217D01*
X1588225Y436508D01*
X1588517Y436717D01*
X1588850Y436800D01*
X1589183Y436717D01*
X1589475Y436508D01*
X1589600Y436217D01*
X1589517Y435925D01*
X1589308Y435717D01*
X1589058Y435633D01*
X1588642D01*
X1588267Y435508D01*
X1588017Y435258D01*
X1587933Y434967D01*
X1588017Y434675D01*
X1588225Y434467D01*
X1588558Y434342D01*
X1588850Y434300D01*
G01X1592867Y436592D02*
X1592617Y436717D01*
X1592325Y436800D01*
X1591992D01*
X1591617Y436675D01*
X1591325Y436467D01*
X1591117Y436217D01*
X1590950Y435800D01*
X1590908Y435425D01*
X1590992Y435050D01*
X1591117Y434800D01*
X1591367Y434550D01*
X1591658Y434383D01*
X1591950Y434300D01*
X1592242D01*
X1592533Y434383D01*
X1592783Y434508D01*
X1592992Y434675D01*
G01X1595550Y434300D02*
Y436800D01*
X1594008Y435008D01*
X1596092D01*
G01X1583967Y425510D02*
Y428010D01*
X1585008D01*
X1585342Y427885D01*
X1585550Y427718D01*
X1585633Y427385D01*
X1585550Y427052D01*
X1585300Y426843D01*
X1585008Y426718D01*
X1583967D01*
G01X1585008D02*
X1585633Y425510D01*
G01X1587900D02*
X1588192Y425552D01*
X1588525Y425677D01*
X1588733Y425885D01*
X1588817Y426177D01*
X1588733Y426468D01*
X1588483Y426718D01*
X1588108Y426843D01*
X1587692D01*
X1587442Y426927D01*
X1587233Y427135D01*
X1587150Y427427D01*
X1587275Y427718D01*
X1587567Y427927D01*
X1587900Y428010D01*
X1588233Y427927D01*
X1588525Y427718D01*
X1588650Y427427D01*
X1588567Y427135D01*
X1588358Y426927D01*
X1588108Y426843D01*
X1587692D01*
X1587317Y426718D01*
X1587067Y426468D01*
X1586983Y426177D01*
X1587067Y425885D01*
X1587275Y425677D01*
X1587608Y425552D01*
X1587900Y425510D01*
G01X1591917Y427802D02*
X1591667Y427927D01*
X1591375Y428010D01*
X1591042D01*
X1590667Y427885D01*
X1590375Y427677D01*
X1590167Y427427D01*
X1590000Y427010D01*
X1589958Y426635D01*
X1590042Y426260D01*
X1590167Y426010D01*
X1590417Y425760D01*
X1590708Y425593D01*
X1591000Y425510D01*
X1591292D01*
X1591583Y425593D01*
X1591833Y425718D01*
X1592042Y425885D01*
G01X1594100Y425510D02*
Y428010D01*
X1593600Y427510D01*
G01Y425510D02*
X1594600D01*
G01X1597200D02*
Y428010D01*
X1596700Y427510D01*
G01Y425510D02*
X1597700D01*
G01X1583417Y438000D02*
Y440500D01*
X1584458D01*
X1584792Y440375D01*
X1585000Y440208D01*
X1585083Y439875D01*
X1585000Y439542D01*
X1584750Y439333D01*
X1584458Y439208D01*
X1583417D01*
G01X1584458D02*
X1585083Y438000D01*
G01X1587267D02*
X1587350Y438542D01*
X1587475Y439000D01*
X1587642Y439417D01*
X1587850Y439875D01*
X1588183Y440500D01*
X1586517D01*
G01X1589200D02*
X1589783Y438000D01*
X1590450Y440500D01*
X1591117Y438000D01*
X1591700Y440500D01*
G01X1593550Y438000D02*
Y440500D01*
X1593050Y440000D01*
G01Y438000D02*
X1594050D01*
G01X1596567D02*
X1596650Y438542D01*
X1596775Y439000D01*
X1596942Y439417D01*
X1597150Y439875D01*
X1597483Y440500D01*
X1595817D01*
G01X1550590Y526000D02*
X1552457Y519000D01*
X1554590Y526000D01*
X1556723Y519000D01*
X1558590Y526000D01*
G01X1563100Y500200D02*
X1549550D01*
G01X1567800Y502000D02*
Y500200D01*
X1565900D01*
G01X1549200Y541900D02*
X1567800D01*
Y524200D01*
G01Y519900D02*
Y504600D01*
G01X1546850Y500200D02*
X1533100D01*
G01X1585935Y497357D02*
X1583435D01*
Y498398D01*
X1583560Y498732D01*
X1583727Y498940D01*
X1584060Y499023D01*
X1584393Y498940D01*
X1584602Y498690D01*
X1584727Y498398D01*
Y497357D01*
G01Y498398D02*
X1585935Y499023D01*
G01Y501290D02*
X1585893Y501582D01*
X1585768Y501915D01*
X1585560Y502123D01*
X1585268Y502207D01*
X1584977Y502123D01*
X1584727Y501873D01*
X1584602Y501498D01*
Y501082D01*
X1584518Y500832D01*
X1584310Y500623D01*
X1584018Y500540D01*
X1583727Y500665D01*
X1583518Y500957D01*
X1583435Y501290D01*
X1583518Y501623D01*
X1583727Y501915D01*
X1584018Y502040D01*
X1584310Y501957D01*
X1584518Y501748D01*
X1584602Y501498D01*
Y501082D01*
X1584727Y500707D01*
X1584977Y500457D01*
X1585268Y500373D01*
X1585560Y500457D01*
X1585768Y500665D01*
X1585893Y500998D01*
X1585935Y501290D01*
G01X1584602Y504723D02*
X1584477Y504890D01*
X1584268Y505015D01*
X1583977Y505098D01*
X1583727Y505015D01*
X1583560Y504848D01*
X1583435Y504557D01*
Y503432D01*
X1585935D01*
Y504807D01*
X1585768Y505098D01*
X1585518Y505265D01*
X1585227Y505348D01*
X1584935Y505265D01*
X1584685Y505015D01*
X1584602Y504723D01*
Y503432D01*
G01X1585643Y506782D02*
X1585852Y507073D01*
X1585935Y507407D01*
X1585852Y507740D01*
X1585602Y508032D01*
X1585227Y508240D01*
X1584852Y508323D01*
X1584393D01*
X1584018Y508240D01*
X1583685Y508032D01*
X1583518Y507782D01*
X1583435Y507490D01*
X1583518Y507157D01*
X1583685Y506907D01*
X1583935Y506740D01*
X1584268Y506657D01*
X1584560Y506740D01*
X1584852Y506948D01*
X1585018Y507198D01*
X1585060Y507490D01*
X1584977Y507823D01*
X1584768Y508073D01*
X1584393Y508323D01*
G01X1586780Y481894D02*
X1584280D01*
Y482935D01*
X1584405Y483269D01*
X1584572Y483477D01*
X1584905Y483560D01*
X1585238Y483477D01*
X1585447Y483227D01*
X1585572Y482935D01*
Y481894D01*
G01Y482935D02*
X1586780Y483560D01*
G01Y485827D02*
X1586738Y486119D01*
X1586613Y486452D01*
X1586405Y486660D01*
X1586113Y486744D01*
X1585822Y486660D01*
X1585572Y486410D01*
X1585447Y486035D01*
Y485619D01*
X1585363Y485369D01*
X1585155Y485160D01*
X1584863Y485077D01*
X1584572Y485202D01*
X1584363Y485494D01*
X1584280Y485827D01*
X1584363Y486160D01*
X1584572Y486452D01*
X1584863Y486577D01*
X1585155Y486494D01*
X1585363Y486285D01*
X1585447Y486035D01*
Y485619D01*
X1585572Y485244D01*
X1585822Y484994D01*
X1586113Y484910D01*
X1586405Y484994D01*
X1586613Y485202D01*
X1586738Y485535D01*
X1586780Y485827D01*
G01X1585447Y489260D02*
X1585322Y489427D01*
X1585113Y489552D01*
X1584822Y489635D01*
X1584572Y489552D01*
X1584405Y489385D01*
X1584280Y489094D01*
Y487969D01*
X1586780D01*
Y489344D01*
X1586613Y489635D01*
X1586363Y489802D01*
X1586072Y489885D01*
X1585780Y489802D01*
X1585530Y489552D01*
X1585447Y489260D01*
Y487969D01*
G01X1586280Y491110D02*
X1586572Y491360D01*
X1586738Y491694D01*
X1586780Y492069D01*
X1586738Y492402D01*
X1586530Y492735D01*
X1586280Y492944D01*
X1586030Y492985D01*
X1585738Y492902D01*
X1585530Y492610D01*
X1585447Y492319D01*
Y491944D01*
G01Y492319D02*
X1585322Y492569D01*
X1585113Y492777D01*
X1584863Y492860D01*
X1584613Y492777D01*
X1584405Y492569D01*
X1584280Y492194D01*
X1584322Y491819D01*
X1584488Y491444D01*
G01X1584697Y494335D02*
X1584447Y494585D01*
X1584322Y494877D01*
X1584280Y495210D01*
X1584363Y495627D01*
X1584572Y495919D01*
X1584822Y496002D01*
X1585072Y495960D01*
X1585280Y495794D01*
X1585697Y494960D01*
X1585988Y494585D01*
X1586405Y494335D01*
X1586780Y494252D01*
Y496002D01*
G01X1537117Y525067D02*
Y527567D01*
X1538158D01*
X1538492Y527442D01*
X1538700Y527275D01*
X1538783Y526942D01*
X1538700Y526609D01*
X1538450Y526400D01*
X1538158Y526275D01*
X1537117D01*
G01X1538158D02*
X1538783Y525067D01*
G01X1541050D02*
X1541342Y525109D01*
X1541675Y525234D01*
X1541883Y525442D01*
X1541967Y525734D01*
X1541883Y526025D01*
X1541633Y526275D01*
X1541258Y526400D01*
X1540842D01*
X1540592Y526484D01*
X1540383Y526692D01*
X1540300Y526984D01*
X1540425Y527275D01*
X1540717Y527484D01*
X1541050Y527567D01*
X1541383Y527484D01*
X1541675Y527275D01*
X1541800Y526984D01*
X1541717Y526692D01*
X1541508Y526484D01*
X1541258Y526400D01*
X1540842D01*
X1540467Y526275D01*
X1540217Y526025D01*
X1540133Y525734D01*
X1540217Y525442D01*
X1540425Y525234D01*
X1540758Y525109D01*
X1541050Y525067D01*
G01X1545067Y527359D02*
X1544817Y527484D01*
X1544525Y527567D01*
X1544192D01*
X1543817Y527442D01*
X1543525Y527234D01*
X1543317Y526984D01*
X1543150Y526567D01*
X1543108Y526192D01*
X1543192Y525817D01*
X1543317Y525567D01*
X1543567Y525317D01*
X1543858Y525150D01*
X1544150Y525067D01*
X1544442D01*
X1544733Y525150D01*
X1544983Y525275D01*
X1545192Y525442D01*
G01X1547250Y525067D02*
Y527567D01*
X1546750Y527067D01*
G01Y525067D02*
X1547750D01*
G01X1551017Y511800D02*
Y514300D01*
X1552058D01*
X1552392Y514175D01*
X1552600Y514008D01*
X1552683Y513675D01*
X1552600Y513342D01*
X1552350Y513133D01*
X1552058Y513008D01*
X1551017D01*
G01X1552058D02*
X1552683Y511800D01*
G01X1554950D02*
X1555242Y511842D01*
X1555575Y511967D01*
X1555783Y512175D01*
X1555867Y512467D01*
X1555783Y512758D01*
X1555533Y513008D01*
X1555158Y513133D01*
X1554742D01*
X1554492Y513217D01*
X1554283Y513425D01*
X1554200Y513717D01*
X1554325Y514008D01*
X1554617Y514217D01*
X1554950Y514300D01*
X1555283Y514217D01*
X1555575Y514008D01*
X1555700Y513717D01*
X1555617Y513425D01*
X1555408Y513217D01*
X1555158Y513133D01*
X1554742D01*
X1554367Y513008D01*
X1554117Y512758D01*
X1554033Y512467D01*
X1554117Y512175D01*
X1554325Y511967D01*
X1554658Y511842D01*
X1554950Y511800D01*
G01X1558883D02*
X1557217D01*
Y514300D01*
X1558883D01*
G01X1558217Y513092D02*
X1557217D01*
G01X1560358Y513883D02*
X1560608Y514133D01*
X1560900Y514258D01*
X1561233Y514300D01*
X1561650Y514217D01*
X1561942Y514008D01*
X1562025Y513758D01*
X1561983Y513508D01*
X1561817Y513300D01*
X1560983Y512883D01*
X1560608Y512592D01*
X1560358Y512175D01*
X1560275Y511800D01*
X1562025D01*
G01X1563458Y513883D02*
X1563708Y514133D01*
X1564000Y514258D01*
X1564333Y514300D01*
X1564750Y514217D01*
X1565042Y514008D01*
X1565125Y513758D01*
X1565083Y513508D01*
X1564917Y513300D01*
X1564083Y512883D01*
X1563708Y512592D01*
X1563458Y512175D01*
X1563375Y511800D01*
X1565125D01*
G01X1552567Y515300D02*
Y517800D01*
X1553608D01*
X1553942Y517675D01*
X1554150Y517508D01*
X1554233Y517175D01*
X1554150Y516842D01*
X1553900Y516633D01*
X1553608Y516508D01*
X1552567D01*
G01X1553608D02*
X1554233Y515300D01*
G01X1555708Y517383D02*
X1555958Y517633D01*
X1556250Y517758D01*
X1556583Y517800D01*
X1557000Y517717D01*
X1557292Y517508D01*
X1557375Y517258D01*
X1557333Y517008D01*
X1557167Y516800D01*
X1556333Y516383D01*
X1555958Y516092D01*
X1555708Y515675D01*
X1555625Y515300D01*
X1557375D01*
G01X1558767D02*
Y517800D01*
X1559808D01*
X1560142Y517675D01*
X1560350Y517508D01*
X1560433Y517175D01*
X1560350Y516842D01*
X1560100Y516633D01*
X1559808Y516508D01*
X1558767D01*
G01X1559808D02*
X1560433Y515300D01*
G01X1561783Y515675D02*
X1562033Y515467D01*
X1562325Y515342D01*
X1562700Y515300D01*
X1563075Y515383D01*
X1563367Y515550D01*
X1563575Y515842D01*
X1563617Y516175D01*
X1563533Y516508D01*
X1563325Y516717D01*
X1563033Y516883D01*
X1562742Y516925D01*
X1562450Y516883D01*
X1562075Y516717D01*
X1562200Y517800D01*
X1563325D01*
G01X1537117Y518167D02*
Y520667D01*
X1538158D01*
X1538492Y520542D01*
X1538700Y520375D01*
X1538783Y520042D01*
X1538700Y519709D01*
X1538450Y519500D01*
X1538158Y519375D01*
X1537117D01*
G01X1538158D02*
X1538783Y518167D01*
G01X1541050D02*
X1541342Y518209D01*
X1541675Y518334D01*
X1541883Y518542D01*
X1541967Y518834D01*
X1541883Y519125D01*
X1541633Y519375D01*
X1541258Y519500D01*
X1540842D01*
X1540592Y519584D01*
X1540383Y519792D01*
X1540300Y520084D01*
X1540425Y520375D01*
X1540717Y520584D01*
X1541050Y520667D01*
X1541383Y520584D01*
X1541675Y520375D01*
X1541800Y520084D01*
X1541717Y519792D01*
X1541508Y519584D01*
X1541258Y519500D01*
X1540842D01*
X1540467Y519375D01*
X1540217Y519125D01*
X1540133Y518834D01*
X1540217Y518542D01*
X1540425Y518334D01*
X1540758Y518209D01*
X1541050Y518167D01*
G01X1545067Y520459D02*
X1544817Y520584D01*
X1544525Y520667D01*
X1544192D01*
X1543817Y520542D01*
X1543525Y520334D01*
X1543317Y520084D01*
X1543150Y519667D01*
X1543108Y519292D01*
X1543192Y518917D01*
X1543317Y518667D01*
X1543567Y518417D01*
X1543858Y518250D01*
X1544150Y518167D01*
X1544442D01*
X1544733Y518250D01*
X1544983Y518375D01*
X1545192Y518542D01*
G01X1547167Y518167D02*
X1547250Y518709D01*
X1547375Y519167D01*
X1547542Y519584D01*
X1547750Y520042D01*
X1548083Y520667D01*
X1546417D01*
G01X1537117Y514767D02*
Y517267D01*
X1538158D01*
X1538492Y517142D01*
X1538700Y516975D01*
X1538783Y516642D01*
X1538700Y516309D01*
X1538450Y516100D01*
X1538158Y515975D01*
X1537117D01*
G01X1538158D02*
X1538783Y514767D01*
G01X1540258Y516850D02*
X1540508Y517100D01*
X1540800Y517225D01*
X1541133Y517267D01*
X1541550Y517184D01*
X1541842Y516975D01*
X1541925Y516725D01*
X1541883Y516475D01*
X1541717Y516267D01*
X1540883Y515850D01*
X1540508Y515559D01*
X1540258Y515142D01*
X1540175Y514767D01*
X1541925D01*
G01X1543192D02*
Y517267D01*
X1545108Y514767D01*
Y517267D01*
G01X1547250Y514767D02*
X1547542Y514809D01*
X1547875Y514934D01*
X1548083Y515142D01*
X1548167Y515434D01*
X1548083Y515725D01*
X1547833Y515975D01*
X1547458Y516100D01*
X1547042D01*
X1546792Y516184D01*
X1546583Y516392D01*
X1546500Y516684D01*
X1546625Y516975D01*
X1546917Y517184D01*
X1547250Y517267D01*
X1547583Y517184D01*
X1547875Y516975D01*
X1548000Y516684D01*
X1547917Y516392D01*
X1547708Y516184D01*
X1547458Y516100D01*
X1547042D01*
X1546667Y515975D01*
X1546417Y515725D01*
X1546333Y515434D01*
X1546417Y515142D01*
X1546625Y514934D01*
X1546958Y514809D01*
X1547250Y514767D01*
G01X1537067Y521600D02*
Y524100D01*
X1538108D01*
X1538442Y523975D01*
X1538650Y523808D01*
X1538733Y523475D01*
X1538650Y523142D01*
X1538400Y522933D01*
X1538108Y522808D01*
X1537067D01*
G01X1538108D02*
X1538733Y521600D01*
G01X1541000D02*
X1541292Y521642D01*
X1541625Y521767D01*
X1541833Y521975D01*
X1541917Y522267D01*
X1541833Y522558D01*
X1541583Y522808D01*
X1541208Y522933D01*
X1540792D01*
X1540542Y523017D01*
X1540333Y523225D01*
X1540250Y523517D01*
X1540375Y523808D01*
X1540667Y524017D01*
X1541000Y524100D01*
X1541333Y524017D01*
X1541625Y523808D01*
X1541750Y523517D01*
X1541667Y523225D01*
X1541458Y523017D01*
X1541208Y522933D01*
X1540792D01*
X1540417Y522808D01*
X1540167Y522558D01*
X1540083Y522267D01*
X1540167Y521975D01*
X1540375Y521767D01*
X1540708Y521642D01*
X1541000Y521600D01*
G01X1545017Y523892D02*
X1544767Y524017D01*
X1544475Y524100D01*
X1544142D01*
X1543767Y523975D01*
X1543475Y523767D01*
X1543267Y523517D01*
X1543100Y523100D01*
X1543058Y522725D01*
X1543142Y522350D01*
X1543267Y522100D01*
X1543517Y521850D01*
X1543808Y521683D01*
X1544100Y521600D01*
X1544392D01*
X1544683Y521683D01*
X1544933Y521808D01*
X1545142Y521975D01*
G01X1546492Y521892D02*
X1546783Y521683D01*
X1547117Y521600D01*
X1547450Y521683D01*
X1547742Y521933D01*
X1547950Y522308D01*
X1548033Y522683D01*
Y523142D01*
X1547950Y523517D01*
X1547742Y523850D01*
X1547492Y524017D01*
X1547200Y524100D01*
X1546867Y524017D01*
X1546617Y523850D01*
X1546450Y523600D01*
X1546367Y523267D01*
X1546450Y522975D01*
X1546658Y522683D01*
X1546908Y522517D01*
X1547200Y522475D01*
X1547533Y522558D01*
X1547783Y522767D01*
X1548033Y523142D01*
G01X1536826Y505643D02*
Y508143D01*
X1537867D01*
X1538201Y508018D01*
X1538409Y507851D01*
X1538492Y507518D01*
X1538409Y507185D01*
X1538159Y506976D01*
X1537867Y506851D01*
X1536826D01*
G01X1537867D02*
X1538492Y505643D01*
G01X1539967Y507726D02*
X1540217Y507976D01*
X1540509Y508101D01*
X1540842Y508143D01*
X1541259Y508060D01*
X1541551Y507851D01*
X1541634Y507601D01*
X1541592Y507351D01*
X1541426Y507143D01*
X1540592Y506726D01*
X1540217Y506435D01*
X1539967Y506018D01*
X1539884Y505643D01*
X1541634D01*
G01X1542901D02*
Y508143D01*
X1544817Y505643D01*
Y508143D01*
G01X1546042Y506018D02*
X1546292Y505810D01*
X1546584Y505685D01*
X1546959Y505643D01*
X1547334Y505726D01*
X1547626Y505893D01*
X1547834Y506185D01*
X1547876Y506518D01*
X1547792Y506851D01*
X1547584Y507060D01*
X1547292Y507226D01*
X1547001Y507268D01*
X1546709Y507226D01*
X1546334Y507060D01*
X1546459Y508143D01*
X1547584D01*
G01X1549167Y503167D02*
Y505667D01*
X1550208D01*
X1550542Y505542D01*
X1550750Y505375D01*
X1550833Y505042D01*
X1550750Y504709D01*
X1550500Y504500D01*
X1550208Y504375D01*
X1549167D01*
G01X1550208D02*
X1550833Y503167D01*
G01X1553100D02*
X1553392Y503209D01*
X1553725Y503334D01*
X1553933Y503542D01*
X1554017Y503834D01*
X1553933Y504125D01*
X1553683Y504375D01*
X1553308Y504500D01*
X1552892D01*
X1552642Y504584D01*
X1552433Y504792D01*
X1552350Y505084D01*
X1552475Y505375D01*
X1552767Y505584D01*
X1553100Y505667D01*
X1553433Y505584D01*
X1553725Y505375D01*
X1553850Y505084D01*
X1553767Y504792D01*
X1553558Y504584D01*
X1553308Y504500D01*
X1552892D01*
X1552517Y504375D01*
X1552267Y504125D01*
X1552183Y503834D01*
X1552267Y503542D01*
X1552475Y503334D01*
X1552808Y503209D01*
X1553100Y503167D01*
G01X1557117Y505459D02*
X1556867Y505584D01*
X1556575Y505667D01*
X1556242D01*
X1555867Y505542D01*
X1555575Y505334D01*
X1555367Y505084D01*
X1555200Y504667D01*
X1555158Y504292D01*
X1555242Y503917D01*
X1555367Y503667D01*
X1555617Y503417D01*
X1555908Y503250D01*
X1556200Y503167D01*
X1556492D01*
X1556783Y503250D01*
X1557033Y503375D01*
X1557242Y503542D01*
G01X1558508Y505250D02*
X1558758Y505500D01*
X1559050Y505625D01*
X1559383Y505667D01*
X1559800Y505584D01*
X1560092Y505375D01*
X1560175Y505125D01*
X1560133Y504875D01*
X1559967Y504667D01*
X1559133Y504250D01*
X1558758Y503959D01*
X1558508Y503542D01*
X1558425Y503167D01*
X1560175D01*
G01X1562400Y505667D02*
X1562067Y505584D01*
X1561817Y505375D01*
X1561650Y505125D01*
X1561525Y504792D01*
X1561483Y504417D01*
X1561525Y504042D01*
X1561650Y503709D01*
X1561817Y503459D01*
X1562067Y503250D01*
X1562400Y503167D01*
X1562733Y503250D01*
X1562983Y503459D01*
X1563150Y503709D01*
X1563275Y504042D01*
X1563317Y504417D01*
X1563275Y504792D01*
X1563150Y505125D01*
X1562983Y505375D01*
X1562733Y505584D01*
X1562400Y505667D01*
G01X1549267Y506667D02*
Y509167D01*
X1550308D01*
X1550642Y509042D01*
X1550850Y508875D01*
X1550933Y508542D01*
X1550850Y508209D01*
X1550600Y508000D01*
X1550308Y507875D01*
X1549267D01*
G01X1550308D02*
X1550933Y506667D01*
G01X1553200D02*
X1553492Y506709D01*
X1553825Y506834D01*
X1554033Y507042D01*
X1554117Y507334D01*
X1554033Y507625D01*
X1553783Y507875D01*
X1553408Y508000D01*
X1552992D01*
X1552742Y508084D01*
X1552533Y508292D01*
X1552450Y508584D01*
X1552575Y508875D01*
X1552867Y509084D01*
X1553200Y509167D01*
X1553533Y509084D01*
X1553825Y508875D01*
X1553950Y508584D01*
X1553867Y508292D01*
X1553658Y508084D01*
X1553408Y508000D01*
X1552992D01*
X1552617Y507875D01*
X1552367Y507625D01*
X1552283Y507334D01*
X1552367Y507042D01*
X1552575Y506834D01*
X1552908Y506709D01*
X1553200Y506667D01*
G01X1557217Y508959D02*
X1556967Y509084D01*
X1556675Y509167D01*
X1556342D01*
X1555967Y509042D01*
X1555675Y508834D01*
X1555467Y508584D01*
X1555300Y508167D01*
X1555258Y507792D01*
X1555342Y507417D01*
X1555467Y507167D01*
X1555717Y506917D01*
X1556008Y506750D01*
X1556300Y506667D01*
X1556592D01*
X1556883Y506750D01*
X1557133Y506875D01*
X1557342Y507042D01*
G01X1559400Y506667D02*
Y509167D01*
X1558900Y508667D01*
G01Y506667D02*
X1559900D01*
G01X1563000D02*
Y509167D01*
X1561458Y507375D01*
X1563542D01*
G01X1588970Y480927D02*
Y483427D01*
X1590011D01*
X1590345Y483302D01*
X1590553Y483135D01*
X1590636Y482802D01*
X1590553Y482469D01*
X1590303Y482260D01*
X1590011Y482135D01*
X1588970D01*
G01X1590011D02*
X1590636Y480927D01*
G01X1592903D02*
Y483427D01*
X1592403Y482927D01*
G01Y480927D02*
X1593403D01*
G01X1594753Y483427D02*
X1595336Y480927D01*
X1596003Y483427D01*
X1596670Y480927D01*
X1597253Y483427D01*
G01X1599103Y480927D02*
Y483427D01*
X1598603Y482927D01*
G01Y480927D02*
X1599603D01*
G01X1602120D02*
X1602203Y481469D01*
X1602328Y481927D01*
X1602495Y482344D01*
X1602703Y482802D01*
X1603036Y483427D01*
X1601370D01*
G01X1583460Y477637D02*
Y480137D01*
X1584501D01*
X1584835Y480012D01*
X1585043Y479845D01*
X1585126Y479512D01*
X1585043Y479179D01*
X1584793Y478970D01*
X1584501Y478845D01*
X1583460D01*
G01X1584501D02*
X1585126Y477637D01*
G01X1587393D02*
Y480137D01*
X1586893Y479637D01*
G01Y477637D02*
X1587893D01*
G01X1589243Y480137D02*
X1589826Y477637D01*
X1590493Y480137D01*
X1591160Y477637D01*
X1591743Y480137D01*
G01X1593593Y477637D02*
Y480137D01*
X1593093Y479637D01*
G01Y477637D02*
X1594093D01*
G01X1595901Y478679D02*
X1596193Y478970D01*
X1596443Y479137D01*
X1596776Y479220D01*
X1597068Y479137D01*
X1597276Y478970D01*
X1597443Y478720D01*
X1597485Y478429D01*
X1597443Y478179D01*
X1597276Y477929D01*
X1597026Y477720D01*
X1596735Y477637D01*
X1596401Y477720D01*
X1596110Y477970D01*
X1595943Y478345D01*
X1595901Y478762D01*
X1595985Y479304D01*
X1596110Y479595D01*
X1596318Y479887D01*
X1596610Y480095D01*
X1596901Y480137D01*
X1597193Y480054D01*
X1597401Y479845D01*
G01X1583967Y473967D02*
Y476467D01*
X1585008D01*
X1585342Y476342D01*
X1585550Y476175D01*
X1585633Y475842D01*
X1585550Y475509D01*
X1585300Y475300D01*
X1585008Y475175D01*
X1583967D01*
G01X1585008D02*
X1585633Y473967D01*
G01X1587900D02*
Y476467D01*
X1587400Y475967D01*
G01Y473967D02*
X1588400D01*
G01X1589750Y476467D02*
X1590333Y473967D01*
X1591000Y476467D01*
X1591667Y473967D01*
X1592250Y476467D01*
G01X1594100Y473967D02*
Y476467D01*
X1593600Y475967D01*
G01Y473967D02*
X1594600D01*
G01X1596492Y474259D02*
X1596783Y474050D01*
X1597117Y473967D01*
X1597450Y474050D01*
X1597742Y474300D01*
X1597950Y474675D01*
X1598033Y475050D01*
Y475509D01*
X1597950Y475884D01*
X1597742Y476217D01*
X1597492Y476384D01*
X1597200Y476467D01*
X1596867Y476384D01*
X1596617Y476217D01*
X1596450Y475967D01*
X1596367Y475634D01*
X1596450Y475342D01*
X1596658Y475050D01*
X1596908Y474884D01*
X1597200Y474842D01*
X1597533Y474925D01*
X1597783Y475134D01*
X1598033Y475509D01*
G01X1584328Y468469D02*
Y470969D01*
X1585369D01*
X1585703Y470844D01*
X1585911Y470677D01*
X1585994Y470344D01*
X1585911Y470011D01*
X1585661Y469802D01*
X1585369Y469677D01*
X1584328D01*
G01X1585369D02*
X1585994Y468469D01*
G01X1588261D02*
Y470969D01*
X1587761Y470469D01*
G01Y468469D02*
X1588761D01*
G01X1590111Y470969D02*
X1590694Y468469D01*
X1591361Y470969D01*
X1592028Y468469D01*
X1592611Y470969D01*
G01X1594461Y468469D02*
Y470969D01*
X1593961Y470469D01*
G01Y468469D02*
X1594961D01*
G01X1597561D02*
X1597853Y468511D01*
X1598186Y468636D01*
X1598394Y468844D01*
X1598478Y469136D01*
X1598394Y469427D01*
X1598144Y469677D01*
X1597769Y469802D01*
X1597353D01*
X1597103Y469886D01*
X1596894Y470094D01*
X1596811Y470386D01*
X1596936Y470677D01*
X1597228Y470886D01*
X1597561Y470969D01*
X1597894Y470886D01*
X1598186Y470677D01*
X1598311Y470386D01*
X1598228Y470094D01*
X1598019Y469886D01*
X1597769Y469802D01*
X1597353D01*
X1596978Y469677D01*
X1596728Y469427D01*
X1596644Y469136D01*
X1596728Y468844D01*
X1596936Y468636D01*
X1597269Y468511D01*
X1597561Y468469D01*
G01X1578694Y522888D02*
X1578569Y522638D01*
X1578486Y522346D01*
Y522013D01*
X1578611Y521638D01*
X1578819Y521346D01*
X1579069Y521138D01*
X1579486Y520971D01*
X1579861Y520929D01*
X1580236Y521013D01*
X1580486Y521138D01*
X1580736Y521388D01*
X1580903Y521679D01*
X1580986Y521971D01*
Y522263D01*
X1580903Y522554D01*
X1580778Y522804D01*
X1580611Y523013D01*
G01X1580986Y525071D02*
X1580944Y525363D01*
X1580819Y525696D01*
X1580611Y525904D01*
X1580319Y525988D01*
X1580028Y525904D01*
X1579778Y525654D01*
X1579653Y525279D01*
Y524863D01*
X1579569Y524613D01*
X1579361Y524404D01*
X1579069Y524321D01*
X1578778Y524446D01*
X1578569Y524738D01*
X1578486Y525071D01*
X1578569Y525404D01*
X1578778Y525696D01*
X1579069Y525821D01*
X1579361Y525738D01*
X1579569Y525529D01*
X1579653Y525279D01*
Y524863D01*
X1579778Y524488D01*
X1580028Y524238D01*
X1580319Y524154D01*
X1580611Y524238D01*
X1580819Y524446D01*
X1580944Y524779D01*
X1580986Y525071D01*
G01X1579653Y528504D02*
X1579528Y528671D01*
X1579319Y528796D01*
X1579028Y528879D01*
X1578778Y528796D01*
X1578611Y528629D01*
X1578486Y528338D01*
Y527213D01*
X1580986D01*
Y528588D01*
X1580819Y528879D01*
X1580569Y529046D01*
X1580278Y529129D01*
X1579986Y529046D01*
X1579736Y528796D01*
X1579653Y528504D01*
Y527213D01*
G01X1580486Y530354D02*
X1580778Y530604D01*
X1580944Y530938D01*
X1580986Y531313D01*
X1580944Y531646D01*
X1580736Y531979D01*
X1580486Y532188D01*
X1580236Y532229D01*
X1579944Y532146D01*
X1579736Y531854D01*
X1579653Y531563D01*
Y531188D01*
G01Y531563D02*
X1579528Y531813D01*
X1579319Y532021D01*
X1579069Y532104D01*
X1578819Y532021D01*
X1578611Y531813D01*
X1578486Y531438D01*
X1578528Y531063D01*
X1578694Y530688D01*
G01X1583455Y511845D02*
X1583330Y511595D01*
X1583247Y511303D01*
Y510970D01*
X1583372Y510595D01*
X1583580Y510303D01*
X1583830Y510095D01*
X1584247Y509928D01*
X1584622Y509886D01*
X1584997Y509970D01*
X1585247Y510095D01*
X1585497Y510345D01*
X1585664Y510636D01*
X1585747Y510928D01*
Y511220D01*
X1585664Y511511D01*
X1585539Y511761D01*
X1585372Y511970D01*
G01X1585747Y513945D02*
X1585205Y514028D01*
X1584747Y514153D01*
X1584330Y514320D01*
X1583872Y514528D01*
X1583247Y514861D01*
Y513195D01*
G01X1585747Y516211D02*
X1583247D01*
Y517045D01*
X1583372Y517378D01*
X1583539Y517628D01*
X1583789Y517836D01*
X1584080Y518003D01*
X1584497Y518045D01*
X1584914Y518003D01*
X1585205Y517836D01*
X1585455Y517628D01*
X1585622Y517378D01*
X1585747Y517045D01*
Y516211D01*
G01X1585247Y519311D02*
X1585539Y519561D01*
X1585705Y519895D01*
X1585747Y520270D01*
X1585705Y520603D01*
X1585497Y520936D01*
X1585247Y521145D01*
X1584997Y521186D01*
X1584705Y521103D01*
X1584497Y520811D01*
X1584414Y520520D01*
Y520145D01*
G01Y520520D02*
X1584289Y520770D01*
X1584080Y520978D01*
X1583830Y521061D01*
X1583580Y520978D01*
X1583372Y520770D01*
X1583247Y520395D01*
X1583289Y520020D01*
X1583455Y519645D01*
G01X1586933Y510342D02*
X1586808Y510092D01*
X1586725Y509800D01*
Y509467D01*
X1586850Y509092D01*
X1587058Y508800D01*
X1587308Y508592D01*
X1587725Y508425D01*
X1588100Y508383D01*
X1588475Y508467D01*
X1588725Y508592D01*
X1588975Y508842D01*
X1589142Y509133D01*
X1589225Y509425D01*
Y509717D01*
X1589142Y510008D01*
X1589017Y510258D01*
X1588850Y510467D01*
G01X1589225Y512525D02*
X1589183Y512817D01*
X1589058Y513150D01*
X1588850Y513358D01*
X1588558Y513442D01*
X1588267Y513358D01*
X1588017Y513108D01*
X1587892Y512733D01*
Y512317D01*
X1587808Y512067D01*
X1587600Y511858D01*
X1587308Y511775D01*
X1587017Y511900D01*
X1586808Y512192D01*
X1586725Y512525D01*
X1586808Y512858D01*
X1587017Y513150D01*
X1587308Y513275D01*
X1587600Y513192D01*
X1587808Y512983D01*
X1587892Y512733D01*
Y512317D01*
X1588017Y511942D01*
X1588267Y511692D01*
X1588558Y511608D01*
X1588850Y511692D01*
X1589058Y511900D01*
X1589183Y512233D01*
X1589225Y512525D01*
G01X1587892Y515958D02*
X1587767Y516125D01*
X1587558Y516250D01*
X1587267Y516333D01*
X1587017Y516250D01*
X1586850Y516083D01*
X1586725Y515792D01*
Y514667D01*
X1589225D01*
Y516042D01*
X1589058Y516333D01*
X1588808Y516500D01*
X1588517Y516583D01*
X1588225Y516500D01*
X1587975Y516250D01*
X1587892Y515958D01*
Y514667D01*
G01X1589225Y519225D02*
X1586725D01*
X1588517Y517683D01*
Y519767D01*
G01X1572794Y522588D02*
X1572669Y522338D01*
X1572586Y522046D01*
Y521713D01*
X1572711Y521338D01*
X1572919Y521046D01*
X1573169Y520838D01*
X1573586Y520671D01*
X1573961Y520629D01*
X1574336Y520713D01*
X1574586Y520838D01*
X1574836Y521088D01*
X1575003Y521379D01*
X1575086Y521671D01*
Y521963D01*
X1575003Y522254D01*
X1574878Y522504D01*
X1574711Y522713D01*
G01X1575086Y524771D02*
X1575044Y525063D01*
X1574919Y525396D01*
X1574711Y525604D01*
X1574419Y525688D01*
X1574128Y525604D01*
X1573878Y525354D01*
X1573753Y524979D01*
Y524563D01*
X1573669Y524313D01*
X1573461Y524104D01*
X1573169Y524021D01*
X1572878Y524146D01*
X1572669Y524438D01*
X1572586Y524771D01*
X1572669Y525104D01*
X1572878Y525396D01*
X1573169Y525521D01*
X1573461Y525438D01*
X1573669Y525229D01*
X1573753Y524979D01*
Y524563D01*
X1573878Y524188D01*
X1574128Y523938D01*
X1574419Y523854D01*
X1574711Y523938D01*
X1574919Y524146D01*
X1575044Y524479D01*
X1575086Y524771D01*
G01X1573753Y528204D02*
X1573628Y528371D01*
X1573419Y528496D01*
X1573128Y528579D01*
X1572878Y528496D01*
X1572711Y528329D01*
X1572586Y528038D01*
Y526913D01*
X1575086D01*
Y528288D01*
X1574919Y528579D01*
X1574669Y528746D01*
X1574378Y528829D01*
X1574086Y528746D01*
X1573836Y528496D01*
X1573753Y528204D01*
Y526913D01*
G01X1573003Y530179D02*
X1572753Y530429D01*
X1572628Y530721D01*
X1572586Y531054D01*
X1572669Y531471D01*
X1572878Y531763D01*
X1573128Y531846D01*
X1573378Y531804D01*
X1573586Y531638D01*
X1574003Y530804D01*
X1574294Y530429D01*
X1574711Y530179D01*
X1575086Y530096D01*
Y531846D01*
G01X1583400Y579800D02*
X1586300D01*
G01X1546800Y590600D02*
X1550800D01*
Y589500D01*
X1558000D01*
Y592600D01*
X1576600D01*
Y583500D01*
G01X1552496Y564500D02*
X1552246Y564625D01*
X1551954Y564708D01*
X1551621D01*
X1551246Y564583D01*
X1550954Y564375D01*
X1550746Y564125D01*
X1550579Y563708D01*
X1550537Y563333D01*
X1550621Y562958D01*
X1550746Y562708D01*
X1550996Y562458D01*
X1551287Y562291D01*
X1551579Y562208D01*
X1551871D01*
X1552162Y562291D01*
X1552412Y562416D01*
X1552621Y562583D01*
G01X1554679Y562208D02*
X1554971Y562250D01*
X1555304Y562375D01*
X1555512Y562583D01*
X1555596Y562875D01*
X1555512Y563166D01*
X1555262Y563416D01*
X1554887Y563541D01*
X1554471D01*
X1554221Y563625D01*
X1554012Y563833D01*
X1553929Y564125D01*
X1554054Y564416D01*
X1554346Y564625D01*
X1554679Y564708D01*
X1555012Y564625D01*
X1555304Y564416D01*
X1555429Y564125D01*
X1555346Y563833D01*
X1555137Y563625D01*
X1554887Y563541D01*
X1554471D01*
X1554096Y563416D01*
X1553846Y563166D01*
X1553762Y562875D01*
X1553846Y562583D01*
X1554054Y562375D01*
X1554387Y562250D01*
X1554679Y562208D01*
G01X1556737D02*
X1557779Y564708D01*
X1558821Y562208D01*
G01X1558446Y563083D02*
X1557112D01*
G01X1560879Y562208D02*
Y564708D01*
X1560379Y564208D01*
G01Y562208D02*
X1561379D01*
G01X1563062Y562708D02*
X1563312Y562416D01*
X1563646Y562250D01*
X1564021Y562208D01*
X1564354Y562250D01*
X1564687Y562458D01*
X1564896Y562708D01*
X1564937Y562958D01*
X1564854Y563250D01*
X1564562Y563458D01*
X1564271Y563541D01*
X1563896D01*
G01X1564271D02*
X1564521Y563666D01*
X1564729Y563875D01*
X1564812Y564125D01*
X1564729Y564375D01*
X1564521Y564583D01*
X1564146Y564708D01*
X1563771Y564666D01*
X1563396Y564500D01*
G01X1550467Y528200D02*
Y530700D01*
X1551508D01*
X1551842Y530575D01*
X1552050Y530408D01*
X1552133Y530075D01*
X1552050Y529742D01*
X1551800Y529533D01*
X1551508Y529408D01*
X1550467D01*
G01X1551508D02*
X1552133Y528200D01*
G01X1554400D02*
X1554692Y528242D01*
X1555025Y528367D01*
X1555233Y528575D01*
X1555317Y528867D01*
X1555233Y529158D01*
X1554983Y529408D01*
X1554608Y529533D01*
X1554192D01*
X1553942Y529617D01*
X1553733Y529825D01*
X1553650Y530117D01*
X1553775Y530408D01*
X1554067Y530617D01*
X1554400Y530700D01*
X1554733Y530617D01*
X1555025Y530408D01*
X1555150Y530117D01*
X1555067Y529825D01*
X1554858Y529617D01*
X1554608Y529533D01*
X1554192D01*
X1553817Y529408D01*
X1553567Y529158D01*
X1553483Y528867D01*
X1553567Y528575D01*
X1553775Y528367D01*
X1554108Y528242D01*
X1554400Y528200D01*
G01X1557833Y529533D02*
X1558000Y529658D01*
X1558125Y529867D01*
X1558208Y530158D01*
X1558125Y530408D01*
X1557958Y530575D01*
X1557667Y530700D01*
X1556542D01*
Y528200D01*
X1557917D01*
X1558208Y528367D01*
X1558375Y528617D01*
X1558458Y528908D01*
X1558375Y529200D01*
X1558125Y529450D01*
X1557833Y529533D01*
X1556542D01*
G01X1559683Y528700D02*
X1559933Y528408D01*
X1560267Y528242D01*
X1560642Y528200D01*
X1560975Y528242D01*
X1561308Y528450D01*
X1561517Y528700D01*
X1561558Y528950D01*
X1561475Y529242D01*
X1561183Y529450D01*
X1560892Y529533D01*
X1560517D01*
G01X1560892D02*
X1561142Y529658D01*
X1561350Y529867D01*
X1561433Y530117D01*
X1561350Y530367D01*
X1561142Y530575D01*
X1560767Y530700D01*
X1560392Y530658D01*
X1560017Y530492D01*
G01X1563700Y528200D02*
Y530700D01*
X1563200Y530200D01*
G01Y528200D02*
X1564200D01*
G01X1534117Y535267D02*
Y537767D01*
X1535158D01*
X1535492Y537642D01*
X1535700Y537475D01*
X1535783Y537142D01*
X1535700Y536809D01*
X1535450Y536600D01*
X1535158Y536475D01*
X1534117D01*
G01X1535158D02*
X1535783Y535267D01*
G01X1538050D02*
X1538342Y535309D01*
X1538675Y535434D01*
X1538883Y535642D01*
X1538967Y535934D01*
X1538883Y536225D01*
X1538633Y536475D01*
X1538258Y536600D01*
X1537842D01*
X1537592Y536684D01*
X1537383Y536892D01*
X1537300Y537184D01*
X1537425Y537475D01*
X1537717Y537684D01*
X1538050Y537767D01*
X1538383Y537684D01*
X1538675Y537475D01*
X1538800Y537184D01*
X1538717Y536892D01*
X1538508Y536684D01*
X1538258Y536600D01*
X1537842D01*
X1537467Y536475D01*
X1537217Y536225D01*
X1537133Y535934D01*
X1537217Y535642D01*
X1537425Y535434D01*
X1537758Y535309D01*
X1538050Y535267D01*
G01X1541483Y536600D02*
X1541650Y536725D01*
X1541775Y536934D01*
X1541858Y537225D01*
X1541775Y537475D01*
X1541608Y537642D01*
X1541317Y537767D01*
X1540192D01*
Y535267D01*
X1541567D01*
X1541858Y535434D01*
X1542025Y535684D01*
X1542108Y535975D01*
X1542025Y536267D01*
X1541775Y536517D01*
X1541483Y536600D01*
X1540192D01*
G01X1543458Y537350D02*
X1543708Y537600D01*
X1544000Y537725D01*
X1544333Y537767D01*
X1544750Y537684D01*
X1545042Y537475D01*
X1545125Y537225D01*
X1545083Y536975D01*
X1544917Y536767D01*
X1544083Y536350D01*
X1543708Y536059D01*
X1543458Y535642D01*
X1543375Y535267D01*
X1545125D01*
G01X1546642Y535559D02*
X1546933Y535350D01*
X1547267Y535267D01*
X1547600Y535350D01*
X1547892Y535600D01*
X1548100Y535975D01*
X1548183Y536350D01*
Y536809D01*
X1548100Y537184D01*
X1547892Y537517D01*
X1547642Y537684D01*
X1547350Y537767D01*
X1547017Y537684D01*
X1546767Y537517D01*
X1546600Y537267D01*
X1546517Y536934D01*
X1546600Y536642D01*
X1546808Y536350D01*
X1547058Y536184D01*
X1547350Y536142D01*
X1547683Y536225D01*
X1547933Y536434D01*
X1548183Y536809D01*
G01X1550667Y537100D02*
Y539600D01*
X1551708D01*
X1552042Y539475D01*
X1552250Y539308D01*
X1552333Y538975D01*
X1552250Y538642D01*
X1552000Y538433D01*
X1551708Y538308D01*
X1550667D01*
G01X1551708D02*
X1552333Y537100D01*
G01X1554600D02*
X1554892Y537142D01*
X1555225Y537267D01*
X1555433Y537475D01*
X1555517Y537767D01*
X1555433Y538058D01*
X1555183Y538308D01*
X1554808Y538433D01*
X1554392D01*
X1554142Y538517D01*
X1553933Y538725D01*
X1553850Y539017D01*
X1553975Y539308D01*
X1554267Y539517D01*
X1554600Y539600D01*
X1554933Y539517D01*
X1555225Y539308D01*
X1555350Y539017D01*
X1555267Y538725D01*
X1555058Y538517D01*
X1554808Y538433D01*
X1554392D01*
X1554017Y538308D01*
X1553767Y538058D01*
X1553683Y537767D01*
X1553767Y537475D01*
X1553975Y537267D01*
X1554308Y537142D01*
X1554600Y537100D01*
G01X1558033Y538433D02*
X1558200Y538558D01*
X1558325Y538767D01*
X1558408Y539058D01*
X1558325Y539308D01*
X1558158Y539475D01*
X1557867Y539600D01*
X1556742D01*
Y537100D01*
X1558117D01*
X1558408Y537267D01*
X1558575Y537517D01*
X1558658Y537808D01*
X1558575Y538100D01*
X1558325Y538350D01*
X1558033Y538433D01*
X1556742D01*
G01X1560008Y539183D02*
X1560258Y539433D01*
X1560550Y539558D01*
X1560883Y539600D01*
X1561300Y539517D01*
X1561592Y539308D01*
X1561675Y539058D01*
X1561633Y538808D01*
X1561467Y538600D01*
X1560633Y538183D01*
X1560258Y537892D01*
X1560008Y537475D01*
X1559925Y537100D01*
X1561675D01*
G01X1563900Y539600D02*
X1563567Y539517D01*
X1563317Y539308D01*
X1563150Y539058D01*
X1563025Y538725D01*
X1562983Y538350D01*
X1563025Y537975D01*
X1563150Y537642D01*
X1563317Y537392D01*
X1563567Y537183D01*
X1563900Y537100D01*
X1564233Y537183D01*
X1564483Y537392D01*
X1564650Y537642D01*
X1564775Y537975D01*
X1564817Y538350D01*
X1564775Y538725D01*
X1564650Y539058D01*
X1564483Y539308D01*
X1564233Y539517D01*
X1563900Y539600D01*
G01X1537067Y528600D02*
Y531100D01*
X1538108D01*
X1538442Y530975D01*
X1538650Y530808D01*
X1538733Y530475D01*
X1538650Y530142D01*
X1538400Y529933D01*
X1538108Y529808D01*
X1537067D01*
G01X1538108D02*
X1538733Y528600D01*
G01X1541000D02*
X1541292Y528642D01*
X1541625Y528767D01*
X1541833Y528975D01*
X1541917Y529267D01*
X1541833Y529558D01*
X1541583Y529808D01*
X1541208Y529933D01*
X1540792D01*
X1540542Y530017D01*
X1540333Y530225D01*
X1540250Y530517D01*
X1540375Y530808D01*
X1540667Y531017D01*
X1541000Y531100D01*
X1541333Y531017D01*
X1541625Y530808D01*
X1541750Y530517D01*
X1541667Y530225D01*
X1541458Y530017D01*
X1541208Y529933D01*
X1540792D01*
X1540417Y529808D01*
X1540167Y529558D01*
X1540083Y529267D01*
X1540167Y528975D01*
X1540375Y528767D01*
X1540708Y528642D01*
X1541000Y528600D01*
G01X1545017Y530892D02*
X1544767Y531017D01*
X1544475Y531100D01*
X1544142D01*
X1543767Y530975D01*
X1543475Y530767D01*
X1543267Y530517D01*
X1543100Y530100D01*
X1543058Y529725D01*
X1543142Y529350D01*
X1543267Y529100D01*
X1543517Y528850D01*
X1543808Y528683D01*
X1544100Y528600D01*
X1544392D01*
X1544683Y528683D01*
X1544933Y528808D01*
X1545142Y528975D01*
G01X1546408Y530683D02*
X1546658Y530933D01*
X1546950Y531058D01*
X1547283Y531100D01*
X1547700Y531017D01*
X1547992Y530808D01*
X1548075Y530558D01*
X1548033Y530308D01*
X1547867Y530100D01*
X1547033Y529683D01*
X1546658Y529392D01*
X1546408Y528975D01*
X1546325Y528600D01*
X1548075D01*
G01X1581300Y559117D02*
X1578800D01*
Y560158D01*
X1578925Y560492D01*
X1579092Y560700D01*
X1579425Y560783D01*
X1579758Y560700D01*
X1579967Y560450D01*
X1580092Y560158D01*
Y559117D01*
G01Y560158D02*
X1581300Y560783D01*
G01Y563050D02*
X1581258Y563342D01*
X1581133Y563675D01*
X1580925Y563883D01*
X1580633Y563967D01*
X1580342Y563883D01*
X1580092Y563633D01*
X1579967Y563258D01*
Y562842D01*
X1579883Y562592D01*
X1579675Y562383D01*
X1579383Y562300D01*
X1579092Y562425D01*
X1578883Y562717D01*
X1578800Y563050D01*
X1578883Y563383D01*
X1579092Y563675D01*
X1579383Y563800D01*
X1579675Y563717D01*
X1579883Y563508D01*
X1579967Y563258D01*
Y562842D01*
X1580092Y562467D01*
X1580342Y562217D01*
X1580633Y562133D01*
X1580925Y562217D01*
X1581133Y562425D01*
X1581258Y562758D01*
X1581300Y563050D01*
G01Y565108D02*
X1578800Y566150D01*
X1581300Y567192D01*
G01X1580425Y566817D02*
Y565483D01*
G01X1581300Y569167D02*
X1580758Y569250D01*
X1580300Y569375D01*
X1579883Y569542D01*
X1579425Y569750D01*
X1578800Y570083D01*
Y568417D01*
G01X1577300Y559117D02*
X1574800D01*
Y560158D01*
X1574925Y560492D01*
X1575092Y560700D01*
X1575425Y560783D01*
X1575758Y560700D01*
X1575967Y560450D01*
X1576092Y560158D01*
Y559117D01*
G01Y560158D02*
X1577300Y560783D01*
G01Y563050D02*
X1577258Y563342D01*
X1577133Y563675D01*
X1576925Y563883D01*
X1576633Y563967D01*
X1576342Y563883D01*
X1576092Y563633D01*
X1575967Y563258D01*
Y562842D01*
X1575883Y562592D01*
X1575675Y562383D01*
X1575383Y562300D01*
X1575092Y562425D01*
X1574883Y562717D01*
X1574800Y563050D01*
X1574883Y563383D01*
X1575092Y563675D01*
X1575383Y563800D01*
X1575675Y563717D01*
X1575883Y563508D01*
X1575967Y563258D01*
Y562842D01*
X1576092Y562467D01*
X1576342Y562217D01*
X1576633Y562133D01*
X1576925Y562217D01*
X1577133Y562425D01*
X1577258Y562758D01*
X1577300Y563050D01*
G01Y565108D02*
X1574800Y566150D01*
X1577300Y567192D01*
G01X1576425Y566817D02*
Y565483D01*
G01X1576258Y568458D02*
X1575967Y568750D01*
X1575800Y569000D01*
X1575717Y569333D01*
X1575800Y569625D01*
X1575967Y569833D01*
X1576217Y570000D01*
X1576508Y570042D01*
X1576758Y570000D01*
X1577008Y569833D01*
X1577217Y569583D01*
X1577300Y569292D01*
X1577217Y568958D01*
X1576967Y568667D01*
X1576592Y568500D01*
X1576175Y568458D01*
X1575633Y568542D01*
X1575342Y568667D01*
X1575050Y568875D01*
X1574842Y569167D01*
X1574800Y569458D01*
X1574883Y569750D01*
X1575092Y569958D01*
G01X1580974Y574199D02*
Y576699D01*
X1582015D01*
X1582349Y576574D01*
X1582557Y576407D01*
X1582640Y576074D01*
X1582557Y575741D01*
X1582307Y575532D01*
X1582015Y575407D01*
X1580974D01*
G01X1582015D02*
X1582640Y574199D01*
G01X1584115Y576282D02*
X1584365Y576532D01*
X1584657Y576657D01*
X1584990Y576699D01*
X1585407Y576616D01*
X1585699Y576407D01*
X1585782Y576157D01*
X1585740Y575907D01*
X1585574Y575699D01*
X1584740Y575282D01*
X1584365Y574991D01*
X1584115Y574574D01*
X1584032Y574199D01*
X1585782D01*
G01X1587174Y576699D02*
Y574199D01*
X1588840D01*
G01X1591107D02*
Y576699D01*
X1590607Y576199D01*
G01Y574199D02*
X1591607D01*
G01X1593415Y575241D02*
X1593707Y575532D01*
X1593957Y575699D01*
X1594290Y575782D01*
X1594582Y575699D01*
X1594790Y575532D01*
X1594957Y575282D01*
X1594999Y574991D01*
X1594957Y574741D01*
X1594790Y574491D01*
X1594540Y574282D01*
X1594249Y574199D01*
X1593915Y574282D01*
X1593624Y574532D01*
X1593457Y574907D01*
X1593415Y575324D01*
X1593499Y575866D01*
X1593624Y576157D01*
X1593832Y576449D01*
X1594124Y576657D01*
X1594415Y576699D01*
X1594707Y576616D01*
X1594915Y576407D01*
G01X1552200Y574435D02*
X1551950Y574560D01*
X1551658Y574643D01*
X1551325D01*
X1550950Y574518D01*
X1550658Y574310D01*
X1550450Y574060D01*
X1550283Y573643D01*
X1550241Y573268D01*
X1550325Y572893D01*
X1550450Y572643D01*
X1550700Y572393D01*
X1550991Y572226D01*
X1551283Y572143D01*
X1551575D01*
X1551866Y572226D01*
X1552116Y572351D01*
X1552325Y572518D01*
G01X1554300Y572143D02*
X1554383Y572685D01*
X1554508Y573143D01*
X1554675Y573560D01*
X1554883Y574018D01*
X1555216Y574643D01*
X1553550D01*
G01X1557816Y573476D02*
X1557983Y573601D01*
X1558108Y573810D01*
X1558191Y574101D01*
X1558108Y574351D01*
X1557941Y574518D01*
X1557650Y574643D01*
X1556525D01*
Y572143D01*
X1557900D01*
X1558191Y572310D01*
X1558358Y572560D01*
X1558441Y572851D01*
X1558358Y573143D01*
X1558108Y573393D01*
X1557816Y573476D01*
X1556525D01*
G01X1560583Y572143D02*
Y574643D01*
X1560083Y574143D01*
G01Y572143D02*
X1561083D01*
G01X1562975Y572435D02*
X1563266Y572226D01*
X1563600Y572143D01*
X1563933Y572226D01*
X1564225Y572476D01*
X1564433Y572851D01*
X1564516Y573226D01*
Y573685D01*
X1564433Y574060D01*
X1564225Y574393D01*
X1563975Y574560D01*
X1563683Y574643D01*
X1563350Y574560D01*
X1563100Y574393D01*
X1562933Y574143D01*
X1562850Y573810D01*
X1562933Y573518D01*
X1563141Y573226D01*
X1563391Y573060D01*
X1563683Y573018D01*
X1564016Y573101D01*
X1564266Y573310D01*
X1564516Y573685D01*
G01X1571008Y560867D02*
X1570883Y560617D01*
X1570800Y560325D01*
Y559992D01*
X1570925Y559617D01*
X1571133Y559325D01*
X1571383Y559117D01*
X1571800Y558950D01*
X1572175Y558908D01*
X1572550Y558992D01*
X1572800Y559117D01*
X1573050Y559367D01*
X1573217Y559658D01*
X1573300Y559950D01*
Y560242D01*
X1573217Y560533D01*
X1573092Y560783D01*
X1572925Y560992D01*
G01X1573300Y563050D02*
X1573258Y563342D01*
X1573133Y563675D01*
X1572925Y563883D01*
X1572633Y563967D01*
X1572342Y563883D01*
X1572092Y563633D01*
X1571967Y563258D01*
Y562842D01*
X1571883Y562592D01*
X1571675Y562383D01*
X1571383Y562300D01*
X1571092Y562425D01*
X1570883Y562717D01*
X1570800Y563050D01*
X1570883Y563383D01*
X1571092Y563675D01*
X1571383Y563800D01*
X1571675Y563717D01*
X1571883Y563508D01*
X1571967Y563258D01*
Y562842D01*
X1572092Y562467D01*
X1572342Y562217D01*
X1572633Y562133D01*
X1572925Y562217D01*
X1573133Y562425D01*
X1573258Y562758D01*
X1573300Y563050D01*
G01Y565108D02*
X1570800Y566150D01*
X1573300Y567192D01*
G01X1572425Y566817D02*
Y565483D01*
G01X1573008Y568542D02*
X1573217Y568833D01*
X1573300Y569167D01*
X1573217Y569500D01*
X1572967Y569792D01*
X1572592Y570000D01*
X1572217Y570083D01*
X1571758D01*
X1571383Y570000D01*
X1571050Y569792D01*
X1570883Y569542D01*
X1570800Y569250D01*
X1570883Y568917D01*
X1571050Y568667D01*
X1571300Y568500D01*
X1571633Y568417D01*
X1571925Y568500D01*
X1572217Y568708D01*
X1572383Y568958D01*
X1572425Y569250D01*
X1572342Y569583D01*
X1572133Y569833D01*
X1571758Y570083D01*
G01X1577172Y552090D02*
X1576922Y552215D01*
X1576630Y552298D01*
X1576297D01*
X1575922Y552173D01*
X1575630Y551965D01*
X1575422Y551715D01*
X1575255Y551298D01*
X1575213Y550923D01*
X1575297Y550548D01*
X1575422Y550298D01*
X1575672Y550048D01*
X1575963Y549881D01*
X1576255Y549798D01*
X1576547D01*
X1576838Y549881D01*
X1577088Y550006D01*
X1577297Y550173D01*
G01X1579355Y549798D02*
X1579647Y549840D01*
X1579980Y549965D01*
X1580188Y550173D01*
X1580272Y550465D01*
X1580188Y550756D01*
X1579938Y551006D01*
X1579563Y551131D01*
X1579147D01*
X1578897Y551215D01*
X1578688Y551423D01*
X1578605Y551715D01*
X1578730Y552006D01*
X1579022Y552215D01*
X1579355Y552298D01*
X1579688Y552215D01*
X1579980Y552006D01*
X1580105Y551715D01*
X1580022Y551423D01*
X1579813Y551215D01*
X1579563Y551131D01*
X1579147D01*
X1578772Y551006D01*
X1578522Y550756D01*
X1578438Y550465D01*
X1578522Y550173D01*
X1578730Y549965D01*
X1579063Y549840D01*
X1579355Y549798D01*
G01X1581413D02*
X1582455Y552298D01*
X1583497Y549798D01*
G01X1583122Y550673D02*
X1581788D01*
G01X1585555Y549798D02*
Y552298D01*
X1585055Y551798D01*
G01Y549798D02*
X1586055D01*
G01X1587738Y550173D02*
X1587988Y549965D01*
X1588280Y549840D01*
X1588655Y549798D01*
X1589030Y549881D01*
X1589322Y550048D01*
X1589530Y550340D01*
X1589572Y550673D01*
X1589488Y551006D01*
X1589280Y551215D01*
X1588988Y551381D01*
X1588697Y551423D01*
X1588405Y551381D01*
X1588030Y551215D01*
X1588155Y552298D01*
X1589280D01*
G01X1569400Y561200D02*
X1546825D01*
G01X1569400Y543200D02*
X1546828D01*
G01X1569400D02*
Y545895D01*
G01Y561200D02*
Y558502D01*
G01X1534036Y558500D02*
Y562062D01*
X1546832D01*
Y558500D01*
G01X1534036Y545900D02*
Y542109D01*
X1546832D01*
Y545900D01*
G01X1583800Y596200D02*
X1581300D01*
Y608300D01*
X1578900D01*
G01X1546150Y593450D02*
Y617550D01*
X1570250D01*
Y593450D01*
X1546150D01*
G01X1549170Y595461D02*
X1548161D01*
Y596643D01*
G01X1568239Y596533D02*
Y595461D01*
G01X1566993Y615539D02*
X1568239D01*
Y614357D01*
G01X1548161Y614341D02*
Y615539D01*
X1549309D01*
G01X1568239Y595461D02*
X1567126D01*
G01X1600184Y-19209D02*
X1597684D01*
Y-18168D01*
X1597809Y-17834D01*
X1597976Y-17626D01*
X1598309Y-17543D01*
X1598642Y-17626D01*
X1598851Y-17876D01*
X1598976Y-18168D01*
Y-19209D01*
G01Y-18168D02*
X1600184Y-17543D01*
G01Y-15276D02*
X1600142Y-14984D01*
X1600017Y-14651D01*
X1599809Y-14443D01*
X1599517Y-14359D01*
X1599226Y-14443D01*
X1598976Y-14693D01*
X1598851Y-15068D01*
Y-15484D01*
X1598767Y-15734D01*
X1598559Y-15943D01*
X1598267Y-16026D01*
X1597976Y-15901D01*
X1597767Y-15609D01*
X1597684Y-15276D01*
X1597767Y-14943D01*
X1597976Y-14651D01*
X1598267Y-14526D01*
X1598559Y-14609D01*
X1598767Y-14818D01*
X1598851Y-15068D01*
Y-15484D01*
X1598976Y-15859D01*
X1599226Y-16109D01*
X1599517Y-16193D01*
X1599809Y-16109D01*
X1600017Y-15901D01*
X1600142Y-15568D01*
X1600184Y-15276D01*
G01X1598934Y-11926D02*
Y-11093D01*
X1599684D01*
X1599934Y-11343D01*
X1600101Y-11634D01*
X1600184Y-12051D01*
X1600101Y-12468D01*
X1599934Y-12759D01*
X1599684Y-13009D01*
X1599392Y-13176D01*
X1599059Y-13259D01*
X1598767D01*
X1598517Y-13176D01*
X1598226Y-13009D01*
X1597976Y-12759D01*
X1597809Y-12509D01*
X1597684Y-12176D01*
Y-11884D01*
X1597767Y-11551D01*
X1597934Y-11301D01*
G01X1600184Y-9076D02*
X1597684D01*
X1598184Y-9576D01*
G01X1600184D02*
Y-8576D01*
G01X1599684Y-6893D02*
X1599976Y-6643D01*
X1600142Y-6309D01*
X1600184Y-5934D01*
X1600142Y-5601D01*
X1599934Y-5268D01*
X1599684Y-5059D01*
X1599434Y-5018D01*
X1599142Y-5101D01*
X1598934Y-5393D01*
X1598851Y-5684D01*
Y-6059D01*
G01Y-5684D02*
X1598726Y-5434D01*
X1598517Y-5226D01*
X1598267Y-5143D01*
X1598017Y-5226D01*
X1597809Y-5434D01*
X1597684Y-5809D01*
X1597726Y-6184D01*
X1597892Y-6559D01*
G01X1596702Y-18927D02*
X1594202D01*
Y-17886D01*
X1594327Y-17552D01*
X1594494Y-17344D01*
X1594827Y-17261D01*
X1595160Y-17344D01*
X1595369Y-17594D01*
X1595494Y-17886D01*
Y-18927D01*
G01Y-17886D02*
X1596702Y-17261D01*
G01Y-14994D02*
X1596660Y-14702D01*
X1596535Y-14369D01*
X1596327Y-14161D01*
X1596035Y-14077D01*
X1595744Y-14161D01*
X1595494Y-14411D01*
X1595369Y-14786D01*
Y-15202D01*
X1595285Y-15452D01*
X1595077Y-15661D01*
X1594785Y-15744D01*
X1594494Y-15619D01*
X1594285Y-15327D01*
X1594202Y-14994D01*
X1594285Y-14661D01*
X1594494Y-14369D01*
X1594785Y-14244D01*
X1595077Y-14327D01*
X1595285Y-14536D01*
X1595369Y-14786D01*
Y-15202D01*
X1595494Y-15577D01*
X1595744Y-15827D01*
X1596035Y-15911D01*
X1596327Y-15827D01*
X1596535Y-15619D01*
X1596660Y-15286D01*
X1596702Y-14994D01*
G01X1595452Y-11644D02*
Y-10811D01*
X1596202D01*
X1596452Y-11061D01*
X1596619Y-11352D01*
X1596702Y-11769D01*
X1596619Y-12186D01*
X1596452Y-12477D01*
X1596202Y-12727D01*
X1595910Y-12894D01*
X1595577Y-12977D01*
X1595285D01*
X1595035Y-12894D01*
X1594744Y-12727D01*
X1594494Y-12477D01*
X1594327Y-12227D01*
X1594202Y-11894D01*
Y-11602D01*
X1594285Y-11269D01*
X1594452Y-11019D01*
G01X1596702Y-8877D02*
X1596160Y-8794D01*
X1595702Y-8669D01*
X1595285Y-8502D01*
X1594827Y-8294D01*
X1594202Y-7961D01*
Y-9627D01*
G01X1599306Y9353D02*
Y7561D01*
X1599473Y7186D01*
X1599806Y6936D01*
X1600223Y6853D01*
X1600640Y6936D01*
X1600973Y7186D01*
X1601140Y7561D01*
Y9353D01*
G01X1603323Y6853D02*
Y9353D01*
X1602823Y8853D01*
G01Y6853D02*
X1603823D01*
G01X1605590Y9353D02*
Y6853D01*
X1607256D01*
G01X1609523D02*
Y9353D01*
X1609023Y8853D01*
G01Y6853D02*
X1610023D01*
G01X1612623Y9353D02*
X1612290Y9270D01*
X1612040Y9061D01*
X1611873Y8811D01*
X1611748Y8478D01*
X1611706Y8103D01*
X1611748Y7728D01*
X1611873Y7395D01*
X1612040Y7145D01*
X1612290Y6936D01*
X1612623Y6853D01*
X1612956Y6936D01*
X1613206Y7145D01*
X1613373Y7395D01*
X1613498Y7728D01*
X1613540Y8103D01*
X1613498Y8478D01*
X1613373Y8811D01*
X1613206Y9061D01*
X1612956Y9270D01*
X1612623Y9353D01*
G01X1693685Y-19311D02*
X1600969D01*
Y4508D01*
X1693685D01*
Y-19311D01*
G01X1599950Y49000D02*
X1603050D01*
G01X1599950Y48118D02*
Y49882D01*
G01X1600208Y52943D02*
X1600053Y52713D01*
X1599950Y52445D01*
Y52138D01*
X1600105Y51793D01*
X1600363Y51525D01*
X1600673Y51333D01*
X1601190Y51180D01*
X1601655Y51142D01*
X1602120Y51218D01*
X1602430Y51333D01*
X1602740Y51563D01*
X1602947Y51832D01*
X1603050Y52100D01*
Y52368D01*
X1602947Y52637D01*
X1602792Y52867D01*
X1602585Y53058D01*
G01X1603050Y54357D02*
X1599950D01*
G01Y55813D02*
X1601862Y54357D01*
G01X1603050Y56043D02*
X1600983Y55008D01*
G01X1637373Y41442D02*
X1638983Y44542D01*
G01X1637373D02*
X1638983Y41442D01*
G01X1640550Y44025D02*
X1640780Y44335D01*
X1641048Y44490D01*
X1641355Y44542D01*
X1641738Y44439D01*
X1642006Y44180D01*
X1642083Y43870D01*
X1642045Y43560D01*
X1641891Y43302D01*
X1641125Y42785D01*
X1640780Y42424D01*
X1640550Y41907D01*
X1640473Y41442D01*
X1642083D01*
G01X1644838D02*
Y44542D01*
X1643420Y42320D01*
X1645336D01*
G01X1649773Y41855D02*
X1650080Y41597D01*
X1650425Y41442D01*
X1650731D01*
X1651038Y41597D01*
X1651268Y41855D01*
X1651383Y42217D01*
X1651306Y42579D01*
X1651115Y42889D01*
X1650770Y43095D01*
X1650310Y43199D01*
X1650041Y43405D01*
X1649926Y43767D01*
X1650003Y44129D01*
X1650195Y44387D01*
X1650463Y44542D01*
X1650731D01*
X1651000Y44439D01*
X1651230Y44180D01*
G01X1652835Y44542D02*
Y42320D01*
X1652988Y41855D01*
X1653295Y41545D01*
X1653678Y41442D01*
X1654061Y41545D01*
X1654368Y41855D01*
X1654521Y42320D01*
Y44542D01*
G01X1656011Y41442D02*
Y44542D01*
X1656931D01*
X1657238Y44387D01*
X1657468Y44025D01*
X1657545Y43612D01*
X1657468Y43199D01*
X1657276Y42889D01*
X1656931Y42734D01*
X1656011D01*
G01X1660645Y41442D02*
X1659111D01*
Y44542D01*
X1660645D01*
G01X1660031Y43044D02*
X1659111D01*
G01X1662211Y41442D02*
Y44542D01*
X1663170D01*
X1663476Y44387D01*
X1663668Y44180D01*
X1663745Y43767D01*
X1663668Y43354D01*
X1663438Y43095D01*
X1663170Y42940D01*
X1662211D01*
G01X1663170D02*
X1663745Y41442D01*
G01X1665273Y41855D02*
X1665580Y41597D01*
X1665925Y41442D01*
X1666231D01*
X1666538Y41597D01*
X1666768Y41855D01*
X1666883Y42217D01*
X1666806Y42579D01*
X1666615Y42889D01*
X1666270Y43095D01*
X1665810Y43199D01*
X1665541Y43405D01*
X1665426Y43767D01*
X1665503Y44129D01*
X1665695Y44387D01*
X1665963Y44542D01*
X1666231D01*
X1666500Y44439D01*
X1666730Y44180D01*
G01X1668411Y44542D02*
Y41442D01*
X1669945D01*
G01X1672278D02*
X1671971Y41494D01*
X1671703Y41700D01*
X1671473Y42010D01*
X1671320Y42372D01*
X1671243Y42785D01*
Y43199D01*
X1671320Y43612D01*
X1671473Y43974D01*
X1671703Y44284D01*
X1671971Y44490D01*
X1672278Y44542D01*
X1672585Y44490D01*
X1672853Y44284D01*
X1673083Y43974D01*
X1673236Y43612D01*
X1673313Y43199D01*
Y42785D01*
X1673236Y42372D01*
X1673083Y42010D01*
X1672853Y41700D01*
X1672585Y41494D01*
X1672278Y41442D01*
G01X1675378Y44542D02*
Y41442D01*
G01X1674496Y44542D02*
X1676260D01*
G01X1606137Y48970D02*
X1609470Y55970D01*
X1612803Y48970D01*
G01X1611603Y51420D02*
X1607337D01*
G01X1621003Y55387D02*
X1620203Y55737D01*
X1619270Y55970D01*
X1618203D01*
X1617003Y55620D01*
X1616070Y55037D01*
X1615403Y54337D01*
X1614870Y53170D01*
X1614737Y52120D01*
X1615003Y51070D01*
X1615403Y50370D01*
X1616203Y49670D01*
X1617137Y49203D01*
X1618070Y48970D01*
X1619003D01*
X1619937Y49203D01*
X1620737Y49553D01*
X1621403Y50020D01*
G01X1595500Y49130D02*
Y49897D01*
X1596430D01*
X1596740Y49667D01*
X1596947Y49398D01*
X1597050Y49015D01*
X1596947Y48632D01*
X1596740Y48363D01*
X1596430Y48133D01*
X1596068Y47980D01*
X1595655Y47903D01*
X1595293D01*
X1594983Y47980D01*
X1594622Y48133D01*
X1594312Y48363D01*
X1594105Y48593D01*
X1593950Y48900D01*
Y49168D01*
X1594053Y49475D01*
X1594260Y49705D01*
G01X1597050Y51118D02*
X1593950D01*
X1597050Y52882D01*
X1593950D01*
G01X1597050Y54257D02*
X1593950D01*
Y55023D01*
X1594105Y55330D01*
X1594312Y55560D01*
X1594622Y55752D01*
X1594983Y55905D01*
X1595500Y55943D01*
X1596017Y55905D01*
X1596378Y55752D01*
X1596688Y55560D01*
X1596895Y55330D01*
X1597050Y55023D01*
Y54257D01*
G01X1593462Y38700D02*
X1590900D01*
G01X1619500Y80900D02*
X1615600D01*
Y71800D01*
X1605900D01*
G01X1626200Y96900D02*
X1633400D01*
Y80900D01*
X1622500D01*
G01X1618000Y38700D02*
X1609900D01*
G01X1598500Y46800D02*
X1604500D01*
Y59400D01*
X1598500D01*
G01X1603200Y38700D02*
X1600500D01*
G01X1640854Y80647D02*
X1638354D01*
Y81688D01*
X1638479Y82022D01*
X1638646Y82230D01*
X1638979Y82313D01*
X1639312Y82230D01*
X1639521Y81980D01*
X1639646Y81688D01*
Y80647D01*
G01Y81688D02*
X1640854Y82313D01*
G01Y84580D02*
X1638354D01*
X1638854Y84080D01*
G01X1640854D02*
Y85080D01*
G01X1638354Y86763D02*
X1640146D01*
X1640521Y86930D01*
X1640771Y87263D01*
X1640854Y87680D01*
X1640771Y88097D01*
X1640521Y88430D01*
X1640146Y88597D01*
X1638354D01*
G01X1640854Y90780D02*
X1638354D01*
X1638854Y90280D01*
G01X1640854D02*
Y91280D01*
G01X1638771Y93088D02*
X1638521Y93338D01*
X1638396Y93630D01*
X1638354Y93963D01*
X1638437Y94380D01*
X1638646Y94672D01*
X1638896Y94755D01*
X1639146Y94713D01*
X1639354Y94547D01*
X1639771Y93713D01*
X1640062Y93338D01*
X1640479Y93088D01*
X1640854Y93005D01*
Y94755D01*
G01X1647090Y49807D02*
X1644590D01*
Y50848D01*
X1644715Y51182D01*
X1644882Y51390D01*
X1645215Y51473D01*
X1645548Y51390D01*
X1645757Y51140D01*
X1645882Y50848D01*
Y49807D01*
G01Y50848D02*
X1647090Y51473D01*
G01Y53740D02*
X1644590D01*
X1645090Y53240D01*
G01X1647090D02*
Y54240D01*
G01X1644590Y55923D02*
X1646382D01*
X1646757Y56090D01*
X1647007Y56423D01*
X1647090Y56840D01*
X1647007Y57257D01*
X1646757Y57590D01*
X1646382Y57757D01*
X1644590D01*
G01X1647090Y59940D02*
X1644590D01*
X1645090Y59440D01*
G01X1647090D02*
Y60440D01*
G01Y63040D02*
X1644590D01*
X1645090Y62540D01*
G01X1647090D02*
Y63540D01*
G01X1650490Y49807D02*
X1647990D01*
Y50848D01*
X1648115Y51182D01*
X1648282Y51390D01*
X1648615Y51473D01*
X1648948Y51390D01*
X1649157Y51140D01*
X1649282Y50848D01*
Y49807D01*
G01Y50848D02*
X1650490Y51473D01*
G01Y53740D02*
X1647990D01*
X1648490Y53240D01*
G01X1650490D02*
Y54240D01*
G01X1647990Y55923D02*
X1649782D01*
X1650157Y56090D01*
X1650407Y56423D01*
X1650490Y56840D01*
X1650407Y57257D01*
X1650157Y57590D01*
X1649782Y57757D01*
X1647990D01*
G01X1650490Y59940D02*
X1650448Y60232D01*
X1650323Y60565D01*
X1650115Y60773D01*
X1649823Y60857D01*
X1649532Y60773D01*
X1649282Y60523D01*
X1649157Y60148D01*
Y59732D01*
X1649073Y59482D01*
X1648865Y59273D01*
X1648573Y59190D01*
X1648282Y59315D01*
X1648073Y59607D01*
X1647990Y59940D01*
X1648073Y60273D01*
X1648282Y60565D01*
X1648573Y60690D01*
X1648865Y60607D01*
X1649073Y60398D01*
X1649157Y60148D01*
Y59732D01*
X1649282Y59357D01*
X1649532Y59107D01*
X1649823Y59023D01*
X1650115Y59107D01*
X1650323Y59315D01*
X1650448Y59648D01*
X1650490Y59940D01*
G01X1626957Y76392D02*
X1626707Y76517D01*
X1626415Y76600D01*
X1626082D01*
X1625707Y76475D01*
X1625415Y76267D01*
X1625207Y76017D01*
X1625040Y75600D01*
X1624998Y75225D01*
X1625082Y74850D01*
X1625207Y74600D01*
X1625457Y74350D01*
X1625748Y74183D01*
X1626040Y74100D01*
X1626332D01*
X1626623Y74183D01*
X1626873Y74308D01*
X1627082Y74475D01*
G01X1628432Y74392D02*
X1628723Y74183D01*
X1629057Y74100D01*
X1629390Y74183D01*
X1629682Y74433D01*
X1629890Y74808D01*
X1629973Y75183D01*
Y75642D01*
X1629890Y76017D01*
X1629682Y76350D01*
X1629432Y76517D01*
X1629140Y76600D01*
X1628807Y76517D01*
X1628557Y76350D01*
X1628390Y76100D01*
X1628307Y75767D01*
X1628390Y75475D01*
X1628598Y75183D01*
X1628848Y75017D01*
X1629140Y74975D01*
X1629473Y75058D01*
X1629723Y75267D01*
X1629973Y75642D01*
G01X1632490Y75350D02*
X1633323D01*
Y74600D01*
X1633073Y74350D01*
X1632782Y74183D01*
X1632365Y74100D01*
X1631948Y74183D01*
X1631657Y74350D01*
X1631407Y74600D01*
X1631240Y74892D01*
X1631157Y75225D01*
Y75517D01*
X1631240Y75767D01*
X1631407Y76058D01*
X1631657Y76308D01*
X1631907Y76475D01*
X1632240Y76600D01*
X1632532D01*
X1632865Y76517D01*
X1633115Y76350D01*
G01X1635340Y74100D02*
Y76600D01*
X1634840Y76100D01*
G01Y74100D02*
X1635840D01*
G01X1638440D02*
X1638732Y74142D01*
X1639065Y74267D01*
X1639273Y74475D01*
X1639357Y74767D01*
X1639273Y75058D01*
X1639023Y75308D01*
X1638648Y75433D01*
X1638232D01*
X1637982Y75517D01*
X1637773Y75725D01*
X1637690Y76017D01*
X1637815Y76308D01*
X1638107Y76517D01*
X1638440Y76600D01*
X1638773Y76517D01*
X1639065Y76308D01*
X1639190Y76017D01*
X1639107Y75725D01*
X1638898Y75517D01*
X1638648Y75433D01*
X1638232D01*
X1637857Y75308D01*
X1637607Y75058D01*
X1637523Y74767D01*
X1637607Y74475D01*
X1637815Y74267D01*
X1638148Y74142D01*
X1638440Y74100D01*
G01X1642090Y49832D02*
X1642298Y50165D01*
X1642423Y50540D01*
Y50874D01*
X1642298Y51207D01*
X1642090Y51457D01*
X1641798Y51582D01*
X1641506Y51499D01*
X1641256Y51290D01*
X1641090Y50915D01*
X1641006Y50415D01*
X1640840Y50124D01*
X1640548Y49999D01*
X1640256Y50082D01*
X1640048Y50290D01*
X1639923Y50582D01*
Y50874D01*
X1640006Y51165D01*
X1640215Y51415D01*
G01X1642423Y53807D02*
X1642381Y54099D01*
X1642256Y54432D01*
X1642048Y54640D01*
X1641756Y54724D01*
X1641465Y54640D01*
X1641215Y54390D01*
X1641090Y54015D01*
Y53599D01*
X1641006Y53349D01*
X1640798Y53140D01*
X1640506Y53057D01*
X1640215Y53182D01*
X1640006Y53474D01*
X1639923Y53807D01*
X1640006Y54140D01*
X1640215Y54432D01*
X1640506Y54557D01*
X1640798Y54474D01*
X1641006Y54265D01*
X1641090Y54015D01*
Y53599D01*
X1641215Y53224D01*
X1641465Y52974D01*
X1641756Y52890D01*
X1642048Y52974D01*
X1642256Y53182D01*
X1642381Y53515D01*
X1642423Y53807D01*
G01Y57740D02*
Y56074D01*
X1639923D01*
Y57740D01*
G01X1641131Y57074D02*
Y56074D01*
G01X1642423Y60007D02*
X1639923D01*
X1640423Y59507D01*
G01X1642423D02*
Y60507D01*
G01X1625600Y47650D02*
Y64350D01*
G01X1638400D02*
Y47650D01*
G01X1625600Y64350D02*
X1628243D01*
G01X1638400D02*
X1635753D01*
G01X1638400Y47650D02*
X1635756D01*
G01X1625600D02*
X1628244D01*
G01X1597390Y139915D02*
X1594890D01*
Y140956D01*
X1595015Y141290D01*
X1595182Y141498D01*
X1595515Y141581D01*
X1595848Y141498D01*
X1596057Y141248D01*
X1596182Y140956D01*
Y139915D01*
G01Y140956D02*
X1597390Y141581D01*
G01Y143848D02*
X1597348Y144140D01*
X1597223Y144473D01*
X1597015Y144681D01*
X1596723Y144765D01*
X1596432Y144681D01*
X1596182Y144431D01*
X1596057Y144056D01*
Y143640D01*
X1595973Y143390D01*
X1595765Y143181D01*
X1595473Y143098D01*
X1595182Y143223D01*
X1594973Y143515D01*
X1594890Y143848D01*
X1594973Y144181D01*
X1595182Y144473D01*
X1595473Y144598D01*
X1595765Y144515D01*
X1595973Y144306D01*
X1596057Y144056D01*
Y143640D01*
X1596182Y143265D01*
X1596432Y143015D01*
X1596723Y142931D01*
X1597015Y143015D01*
X1597223Y143223D01*
X1597348Y143556D01*
X1597390Y143848D01*
G01X1595098Y147865D02*
X1594973Y147615D01*
X1594890Y147323D01*
Y146990D01*
X1595015Y146615D01*
X1595223Y146323D01*
X1595473Y146115D01*
X1595890Y145948D01*
X1596265Y145906D01*
X1596640Y145990D01*
X1596890Y146115D01*
X1597140Y146365D01*
X1597307Y146656D01*
X1597390Y146948D01*
Y147240D01*
X1597307Y147531D01*
X1597182Y147781D01*
X1597015Y147990D01*
G01X1597390Y150048D02*
X1594890D01*
X1595390Y149548D01*
G01X1597390D02*
Y150548D01*
G01X1597015Y152231D02*
X1597223Y152481D01*
X1597348Y152773D01*
X1597390Y153148D01*
X1597307Y153523D01*
X1597140Y153815D01*
X1596848Y154023D01*
X1596515Y154065D01*
X1596182Y153981D01*
X1595973Y153773D01*
X1595807Y153481D01*
X1595765Y153190D01*
X1595807Y152898D01*
X1595973Y152523D01*
X1594890Y152648D01*
Y153773D01*
G01X1597045Y123067D02*
X1594545D01*
Y124108D01*
X1594670Y124442D01*
X1594837Y124650D01*
X1595170Y124733D01*
X1595503Y124650D01*
X1595712Y124400D01*
X1595837Y124108D01*
Y123067D01*
G01Y124108D02*
X1597045Y124733D01*
G01X1594962Y126208D02*
X1594712Y126458D01*
X1594587Y126750D01*
X1594545Y127083D01*
X1594628Y127500D01*
X1594837Y127792D01*
X1595087Y127875D01*
X1595337Y127833D01*
X1595545Y127667D01*
X1595962Y126833D01*
X1596253Y126458D01*
X1596670Y126208D01*
X1597045Y126125D01*
Y127875D01*
G01X1594545Y129183D02*
X1596337D01*
X1596712Y129350D01*
X1596962Y129683D01*
X1597045Y130100D01*
X1596962Y130517D01*
X1596712Y130850D01*
X1596337Y131017D01*
X1594545D01*
G01X1596545Y132283D02*
X1596837Y132533D01*
X1597003Y132867D01*
X1597045Y133242D01*
X1597003Y133575D01*
X1596795Y133908D01*
X1596545Y134117D01*
X1596295Y134158D01*
X1596003Y134075D01*
X1595795Y133783D01*
X1595712Y133492D01*
Y133117D01*
G01Y133492D02*
X1595587Y133742D01*
X1595378Y133950D01*
X1595128Y134033D01*
X1594878Y133950D01*
X1594670Y133742D01*
X1594545Y133367D01*
X1594587Y132992D01*
X1594753Y132617D01*
G01X1597045Y136800D02*
X1594545D01*
X1596337Y135258D01*
Y137342D01*
G01X1673190Y100136D02*
Y174940D01*
X1598386D01*
Y100136D01*
X1673190D01*
G01X1621600Y198800D02*
X1596401D01*
X1596400Y198799D01*
Y193801D01*
X1596399Y193800D01*
X1589101D01*
X1589100Y193799D01*
Y191871D01*
G01X1623210Y186590D02*
X1627091D01*
Y187449D01*
X1634880D01*
G01X1629106Y199297D02*
X1632954D01*
G01X1605200Y184300D02*
Y186499D01*
X1605201Y186500D01*
X1614999D01*
X1615000Y186501D01*
G01X1638769Y196945D02*
X1642361D01*
Y193603D01*
X1646045D01*
Y194884D01*
X1648169D01*
G01X1681910Y187600D02*
X1643400D01*
G01X1628333Y216967D02*
X1625833D01*
Y218008D01*
X1625958Y218342D01*
X1626125Y218550D01*
X1626458Y218633D01*
X1626791Y218550D01*
X1627000Y218300D01*
X1627125Y218008D01*
Y216967D01*
G01Y218008D02*
X1628333Y218633D01*
G01Y220900D02*
X1628291Y221192D01*
X1628166Y221525D01*
X1627958Y221733D01*
X1627666Y221817D01*
X1627375Y221733D01*
X1627125Y221483D01*
X1627000Y221108D01*
Y220692D01*
X1626916Y220442D01*
X1626708Y220233D01*
X1626416Y220150D01*
X1626125Y220275D01*
X1625916Y220567D01*
X1625833Y220900D01*
X1625916Y221233D01*
X1626125Y221525D01*
X1626416Y221650D01*
X1626708Y221567D01*
X1626916Y221358D01*
X1627000Y221108D01*
Y220692D01*
X1627125Y220317D01*
X1627375Y220067D01*
X1627666Y219983D01*
X1627958Y220067D01*
X1628166Y220275D01*
X1628291Y220608D01*
X1628333Y220900D01*
G01Y223083D02*
X1625833D01*
Y223917D01*
X1625958Y224250D01*
X1626125Y224500D01*
X1626375Y224708D01*
X1626666Y224875D01*
X1627083Y224917D01*
X1627500Y224875D01*
X1627791Y224708D01*
X1628041Y224500D01*
X1628208Y224250D01*
X1628333Y223917D01*
Y223083D01*
G01X1626250Y226308D02*
X1626000Y226558D01*
X1625875Y226850D01*
X1625833Y227183D01*
X1625916Y227600D01*
X1626125Y227892D01*
X1626375Y227975D01*
X1626625Y227933D01*
X1626833Y227767D01*
X1627250Y226933D01*
X1627541Y226558D01*
X1627958Y226308D01*
X1628333Y226225D01*
Y227975D01*
G01Y230700D02*
X1625833D01*
X1627625Y229158D01*
Y231242D01*
G01X1632762Y211907D02*
Y214407D01*
X1633803D01*
X1634137Y214282D01*
X1634345Y214115D01*
X1634428Y213782D01*
X1634345Y213449D01*
X1634095Y213240D01*
X1633803Y213115D01*
X1632762D01*
G01X1633803D02*
X1634428Y211907D01*
G01X1636695D02*
X1636987Y211949D01*
X1637320Y212074D01*
X1637528Y212282D01*
X1637612Y212574D01*
X1637528Y212865D01*
X1637278Y213115D01*
X1636903Y213240D01*
X1636487D01*
X1636237Y213324D01*
X1636028Y213532D01*
X1635945Y213824D01*
X1636070Y214115D01*
X1636362Y214324D01*
X1636695Y214407D01*
X1637028Y214324D01*
X1637320Y214115D01*
X1637445Y213824D01*
X1637362Y213532D01*
X1637153Y213324D01*
X1636903Y213240D01*
X1636487D01*
X1636112Y213115D01*
X1635862Y212865D01*
X1635778Y212574D01*
X1635862Y212282D01*
X1636070Y212074D01*
X1636403Y211949D01*
X1636695Y211907D01*
G01X1640628D02*
X1638962D01*
Y214407D01*
X1640628D01*
G01X1639962Y213199D02*
X1638962D01*
G01X1642103Y213990D02*
X1642353Y214240D01*
X1642645Y214365D01*
X1642978Y214407D01*
X1643395Y214324D01*
X1643687Y214115D01*
X1643770Y213865D01*
X1643728Y213615D01*
X1643562Y213407D01*
X1642728Y212990D01*
X1642353Y212699D01*
X1642103Y212282D01*
X1642020Y211907D01*
X1643770D01*
G01X1645995Y214407D02*
X1645662Y214324D01*
X1645412Y214115D01*
X1645245Y213865D01*
X1645120Y213532D01*
X1645078Y213157D01*
X1645120Y212782D01*
X1645245Y212449D01*
X1645412Y212199D01*
X1645662Y211990D01*
X1645995Y211907D01*
X1646328Y211990D01*
X1646578Y212199D01*
X1646745Y212449D01*
X1646870Y212782D01*
X1646912Y213157D01*
X1646870Y213532D01*
X1646745Y213865D01*
X1646578Y214115D01*
X1646328Y214324D01*
X1645995Y214407D01*
G01X1615700Y199650D02*
X1604300D01*
Y219350D01*
X1615700D01*
Y199650D01*
G01X1612500Y199700D02*
Y204650D01*
X1607500D01*
Y199700D01*
G01X1639101Y198645D02*
X1638768Y198687D01*
X1638476Y198853D01*
X1638226Y199103D01*
X1638059Y199395D01*
X1637976Y199728D01*
Y200062D01*
X1638059Y200395D01*
X1638226Y200687D01*
X1638476Y200937D01*
X1638768Y201103D01*
X1639101Y201145D01*
X1639434Y201103D01*
X1639726Y200937D01*
X1639976Y200687D01*
X1640143Y200395D01*
X1640226Y200062D01*
Y199728D01*
X1640143Y199395D01*
X1639976Y199103D01*
X1639726Y198853D01*
X1639434Y198687D01*
X1639101Y198645D01*
G01X1639434Y199312D02*
X1639934Y198645D01*
G01X1642201D02*
Y201145D01*
X1641701Y200645D01*
G01Y198645D02*
X1642701D01*
G01X1644051Y201145D02*
X1644634Y198645D01*
X1645301Y201145D01*
X1645968Y198645D01*
X1646551Y201145D01*
G01X1648901Y198645D02*
Y201145D01*
X1647359Y199353D01*
X1649443D01*
G01X1650235Y204108D02*
Y200858D01*
X1653735D01*
G01X1628177Y202415D02*
X1625677D01*
Y203456D01*
X1625802Y203790D01*
X1625969Y203998D01*
X1626302Y204081D01*
X1626635Y203998D01*
X1626844Y203748D01*
X1626969Y203456D01*
Y202415D01*
G01Y203456D02*
X1628177Y204081D01*
G01Y206348D02*
X1625677D01*
X1626177Y205848D01*
G01X1628177D02*
Y206848D01*
G01X1625677Y208198D02*
X1628177Y208781D01*
X1625677Y209448D01*
X1628177Y210115D01*
X1625677Y210698D01*
G01X1627135Y211756D02*
X1626844Y212048D01*
X1626677Y212298D01*
X1626594Y212631D01*
X1626677Y212923D01*
X1626844Y213131D01*
X1627094Y213298D01*
X1627385Y213340D01*
X1627635Y213298D01*
X1627885Y213131D01*
X1628094Y212881D01*
X1628177Y212590D01*
X1628094Y212256D01*
X1627844Y211965D01*
X1627469Y211798D01*
X1627052Y211756D01*
X1626510Y211840D01*
X1626219Y211965D01*
X1625927Y212173D01*
X1625719Y212465D01*
X1625677Y212756D01*
X1625760Y213048D01*
X1625969Y213256D01*
G01X1632350Y199350D02*
X1636350D01*
Y206750D01*
G01X1627983Y179200D02*
Y177408D01*
X1628150Y177033D01*
X1628483Y176783D01*
X1628900Y176700D01*
X1629317Y176783D01*
X1629650Y177033D01*
X1629817Y177408D01*
Y179200D01*
G01X1631208Y178783D02*
X1631458Y179033D01*
X1631750Y179158D01*
X1632083Y179200D01*
X1632500Y179117D01*
X1632792Y178908D01*
X1632875Y178658D01*
X1632833Y178408D01*
X1632667Y178200D01*
X1631833Y177783D01*
X1631458Y177492D01*
X1631208Y177075D01*
X1631125Y176700D01*
X1632875D01*
G01X1634183Y177075D02*
X1634433Y176867D01*
X1634725Y176742D01*
X1635100Y176700D01*
X1635475Y176783D01*
X1635767Y176950D01*
X1635975Y177242D01*
X1636017Y177575D01*
X1635933Y177908D01*
X1635725Y178117D01*
X1635433Y178283D01*
X1635142Y178325D01*
X1634850Y178283D01*
X1634475Y178117D01*
X1634600Y179200D01*
X1635725D01*
G01X1636950D02*
X1637533Y176700D01*
X1638200Y179200D01*
X1638867Y176700D01*
X1639450Y179200D01*
G01X1641800Y176700D02*
Y179200D01*
X1640258Y177408D01*
X1642342D01*
G01X1627250Y277100D02*
Y274000D01*
G01X1626368Y277100D02*
X1628132D01*
G01X1629583Y274000D02*
Y277100D01*
X1630503D01*
X1630810Y276945D01*
X1631040Y276583D01*
X1631117Y276170D01*
X1631040Y275757D01*
X1630848Y275447D01*
X1630503Y275292D01*
X1629583D01*
G01X1632453Y274000D02*
Y277100D01*
X1633450Y274517D01*
X1634447Y277100D01*
Y274000D01*
G01X1635400Y272967D02*
X1637700D01*
G01X1638653Y274000D02*
Y277100D01*
X1639650Y274517D01*
X1640647Y277100D01*
Y274000D01*
G01X1642750D02*
X1642443Y274052D01*
X1642175Y274258D01*
X1641945Y274568D01*
X1641792Y274930D01*
X1641715Y275343D01*
Y275757D01*
X1641792Y276170D01*
X1641945Y276532D01*
X1642175Y276842D01*
X1642443Y277048D01*
X1642750Y277100D01*
X1643057Y277048D01*
X1643325Y276842D01*
X1643555Y276532D01*
X1643708Y276170D01*
X1643785Y275757D01*
Y275343D01*
X1643708Y274930D01*
X1643555Y274568D01*
X1643325Y274258D01*
X1643057Y274052D01*
X1642750Y274000D01*
G01X1645007D02*
Y277100D01*
X1645773D01*
X1646080Y276945D01*
X1646310Y276738D01*
X1646502Y276428D01*
X1646655Y276067D01*
X1646693Y275550D01*
X1646655Y275033D01*
X1646502Y274672D01*
X1646310Y274362D01*
X1646080Y274155D01*
X1645773Y274000D01*
X1645007D01*
G01X1648107Y277100D02*
Y274878D01*
X1648260Y274413D01*
X1648567Y274103D01*
X1648950Y274000D01*
X1649333Y274103D01*
X1649640Y274413D01*
X1649793Y274878D01*
Y277100D01*
G01X1651283D02*
Y274000D01*
X1652817D01*
G01X1655917D02*
X1654383D01*
Y277100D01*
X1655917D01*
G01X1655303Y275602D02*
X1654383D01*
G01X1647917Y249500D02*
Y252000D01*
X1648958D01*
X1649292Y251875D01*
X1649500Y251708D01*
X1649583Y251375D01*
X1649500Y251042D01*
X1649250Y250833D01*
X1648958Y250708D01*
X1647917D01*
G01X1648958D02*
X1649583Y249500D01*
G01X1651850D02*
X1652142Y249542D01*
X1652475Y249667D01*
X1652683Y249875D01*
X1652767Y250167D01*
X1652683Y250458D01*
X1652433Y250708D01*
X1652058Y250833D01*
X1651642D01*
X1651392Y250917D01*
X1651183Y251125D01*
X1651100Y251417D01*
X1651225Y251708D01*
X1651517Y251917D01*
X1651850Y252000D01*
X1652183Y251917D01*
X1652475Y251708D01*
X1652600Y251417D01*
X1652517Y251125D01*
X1652308Y250917D01*
X1652058Y250833D01*
X1651642D01*
X1651267Y250708D01*
X1651017Y250458D01*
X1650933Y250167D01*
X1651017Y249875D01*
X1651225Y249667D01*
X1651558Y249542D01*
X1651850Y249500D01*
G01X1655783D02*
X1654117D01*
Y252000D01*
X1655783D01*
G01X1655117Y250792D02*
X1654117D01*
G01X1658050Y249500D02*
Y252000D01*
X1657550Y251500D01*
G01Y249500D02*
X1658550D01*
G01X1649567Y229107D02*
Y231607D01*
X1650608D01*
X1650942Y231482D01*
X1651150Y231315D01*
X1651233Y230982D01*
X1651150Y230649D01*
X1650900Y230440D01*
X1650608Y230315D01*
X1649567D01*
G01X1650608D02*
X1651233Y229107D01*
G01X1653500D02*
X1653792Y229149D01*
X1654125Y229274D01*
X1654333Y229482D01*
X1654417Y229774D01*
X1654333Y230065D01*
X1654083Y230315D01*
X1653708Y230440D01*
X1653292D01*
X1653042Y230524D01*
X1652833Y230732D01*
X1652750Y231024D01*
X1652875Y231315D01*
X1653167Y231524D01*
X1653500Y231607D01*
X1653833Y231524D01*
X1654125Y231315D01*
X1654250Y231024D01*
X1654167Y230732D01*
X1653958Y230524D01*
X1653708Y230440D01*
X1653292D01*
X1652917Y230315D01*
X1652667Y230065D01*
X1652583Y229774D01*
X1652667Y229482D01*
X1652875Y229274D01*
X1653208Y229149D01*
X1653500Y229107D01*
G01X1657433D02*
X1655767D01*
Y231607D01*
X1657433D01*
G01X1656767Y230399D02*
X1655767D01*
G01X1659700Y229107D02*
Y231607D01*
X1659200Y231107D01*
G01Y229107D02*
X1660200D01*
G01X1662008Y230149D02*
X1662300Y230440D01*
X1662550Y230607D01*
X1662883Y230690D01*
X1663175Y230607D01*
X1663383Y230440D01*
X1663550Y230190D01*
X1663592Y229899D01*
X1663550Y229649D01*
X1663383Y229399D01*
X1663133Y229190D01*
X1662842Y229107D01*
X1662508Y229190D01*
X1662217Y229440D01*
X1662050Y229815D01*
X1662008Y230232D01*
X1662092Y230774D01*
X1662217Y231065D01*
X1662425Y231357D01*
X1662717Y231565D01*
X1663008Y231607D01*
X1663300Y231524D01*
X1663508Y231315D01*
G01X1647917Y253000D02*
Y255500D01*
X1648958D01*
X1649292Y255375D01*
X1649500Y255208D01*
X1649583Y254875D01*
X1649500Y254542D01*
X1649250Y254333D01*
X1648958Y254208D01*
X1647917D01*
G01X1648958D02*
X1649583Y253000D01*
G01X1651850D02*
X1652142Y253042D01*
X1652475Y253167D01*
X1652683Y253375D01*
X1652767Y253667D01*
X1652683Y253958D01*
X1652433Y254208D01*
X1652058Y254333D01*
X1651642D01*
X1651392Y254417D01*
X1651183Y254625D01*
X1651100Y254917D01*
X1651225Y255208D01*
X1651517Y255417D01*
X1651850Y255500D01*
X1652183Y255417D01*
X1652475Y255208D01*
X1652600Y254917D01*
X1652517Y254625D01*
X1652308Y254417D01*
X1652058Y254333D01*
X1651642D01*
X1651267Y254208D01*
X1651017Y253958D01*
X1650933Y253667D01*
X1651017Y253375D01*
X1651225Y253167D01*
X1651558Y253042D01*
X1651850Y253000D01*
G01X1653700Y255500D02*
X1654283Y253000D01*
X1654950Y255500D01*
X1655617Y253000D01*
X1656200Y255500D01*
G01X1658050Y253000D02*
Y255500D01*
X1657550Y255000D01*
G01Y253000D02*
X1658550D01*
G01X1597344Y268558D02*
Y271058D01*
X1598385D01*
X1598719Y270933D01*
X1598927Y270766D01*
X1599010Y270433D01*
X1598927Y270100D01*
X1598677Y269891D01*
X1598385Y269766D01*
X1597344D01*
G01X1598385D02*
X1599010Y268558D01*
G01X1601277D02*
X1601569Y268600D01*
X1601902Y268725D01*
X1602110Y268933D01*
X1602194Y269225D01*
X1602110Y269516D01*
X1601860Y269766D01*
X1601485Y269891D01*
X1601069D01*
X1600819Y269975D01*
X1600610Y270183D01*
X1600527Y270475D01*
X1600652Y270766D01*
X1600944Y270975D01*
X1601277Y271058D01*
X1601610Y270975D01*
X1601902Y270766D01*
X1602027Y270475D01*
X1601944Y270183D01*
X1601735Y269975D01*
X1601485Y269891D01*
X1601069D01*
X1600694Y269766D01*
X1600444Y269516D01*
X1600360Y269225D01*
X1600444Y268933D01*
X1600652Y268725D01*
X1600985Y268600D01*
X1601277Y268558D01*
G01X1603460D02*
Y271058D01*
X1604294D01*
X1604627Y270933D01*
X1604877Y270766D01*
X1605085Y270516D01*
X1605252Y270225D01*
X1605294Y269808D01*
X1605252Y269391D01*
X1605085Y269100D01*
X1604877Y268850D01*
X1604627Y268683D01*
X1604294Y268558D01*
X1603460D01*
G01X1606560Y269058D02*
X1606810Y268766D01*
X1607144Y268600D01*
X1607519Y268558D01*
X1607852Y268600D01*
X1608185Y268808D01*
X1608394Y269058D01*
X1608435Y269308D01*
X1608352Y269600D01*
X1608060Y269808D01*
X1607769Y269891D01*
X1607394D01*
G01X1607769D02*
X1608019Y270016D01*
X1608227Y270225D01*
X1608310Y270475D01*
X1608227Y270725D01*
X1608019Y270933D01*
X1607644Y271058D01*
X1607269Y271016D01*
X1606894Y270850D01*
G01X1609660Y268933D02*
X1609910Y268725D01*
X1610202Y268600D01*
X1610577Y268558D01*
X1610952Y268641D01*
X1611244Y268808D01*
X1611452Y269100D01*
X1611494Y269433D01*
X1611410Y269766D01*
X1611202Y269975D01*
X1610910Y270141D01*
X1610619Y270183D01*
X1610327Y270141D01*
X1609952Y269975D01*
X1610077Y271058D01*
X1611202D01*
G01X1605008Y272078D02*
Y274578D01*
X1606049D01*
X1606383Y274453D01*
X1606591Y274286D01*
X1606674Y273953D01*
X1606591Y273620D01*
X1606341Y273411D01*
X1606049Y273286D01*
X1605008D01*
G01X1606049D02*
X1606674Y272078D01*
G01X1608941D02*
X1609233Y272120D01*
X1609566Y272245D01*
X1609774Y272453D01*
X1609858Y272745D01*
X1609774Y273036D01*
X1609524Y273286D01*
X1609149Y273411D01*
X1608733D01*
X1608483Y273495D01*
X1608274Y273703D01*
X1608191Y273995D01*
X1608316Y274286D01*
X1608608Y274495D01*
X1608941Y274578D01*
X1609274Y274495D01*
X1609566Y274286D01*
X1609691Y273995D01*
X1609608Y273703D01*
X1609399Y273495D01*
X1609149Y273411D01*
X1608733D01*
X1608358Y273286D01*
X1608108Y273036D01*
X1608024Y272745D01*
X1608108Y272453D01*
X1608316Y272245D01*
X1608649Y272120D01*
X1608941Y272078D01*
G01X1612874D02*
X1611208D01*
Y274578D01*
X1612874D01*
G01X1612208Y273370D02*
X1611208D01*
G01X1615141Y272078D02*
Y274578D01*
X1614641Y274078D01*
G01Y272078D02*
X1615641D01*
G01X1617324Y272578D02*
X1617574Y272286D01*
X1617908Y272120D01*
X1618283Y272078D01*
X1618616Y272120D01*
X1618949Y272328D01*
X1619158Y272578D01*
X1619199Y272828D01*
X1619116Y273120D01*
X1618824Y273328D01*
X1618533Y273411D01*
X1618158D01*
G01X1618533D02*
X1618783Y273536D01*
X1618991Y273745D01*
X1619074Y273995D01*
X1618991Y274245D01*
X1618783Y274453D01*
X1618408Y274578D01*
X1618033Y274536D01*
X1617658Y274370D01*
G01X1605008Y275478D02*
Y277978D01*
X1606049D01*
X1606383Y277853D01*
X1606591Y277686D01*
X1606674Y277353D01*
X1606591Y277020D01*
X1606341Y276811D01*
X1606049Y276686D01*
X1605008D01*
G01X1606049D02*
X1606674Y275478D01*
G01X1608941D02*
X1609233Y275520D01*
X1609566Y275645D01*
X1609774Y275853D01*
X1609858Y276145D01*
X1609774Y276436D01*
X1609524Y276686D01*
X1609149Y276811D01*
X1608733D01*
X1608483Y276895D01*
X1608274Y277103D01*
X1608191Y277395D01*
X1608316Y277686D01*
X1608608Y277895D01*
X1608941Y277978D01*
X1609274Y277895D01*
X1609566Y277686D01*
X1609691Y277395D01*
X1609608Y277103D01*
X1609399Y276895D01*
X1609149Y276811D01*
X1608733D01*
X1608358Y276686D01*
X1608108Y276436D01*
X1608024Y276145D01*
X1608108Y275853D01*
X1608316Y275645D01*
X1608649Y275520D01*
X1608941Y275478D01*
G01X1612874D02*
X1611208D01*
Y277978D01*
X1612874D01*
G01X1612208Y276770D02*
X1611208D01*
G01X1614349Y276520D02*
X1614641Y276811D01*
X1614891Y276978D01*
X1615224Y277061D01*
X1615516Y276978D01*
X1615724Y276811D01*
X1615891Y276561D01*
X1615933Y276270D01*
X1615891Y276020D01*
X1615724Y275770D01*
X1615474Y275561D01*
X1615183Y275478D01*
X1614849Y275561D01*
X1614558Y275811D01*
X1614391Y276186D01*
X1614349Y276603D01*
X1614433Y277145D01*
X1614558Y277436D01*
X1614766Y277728D01*
X1615058Y277936D01*
X1615349Y277978D01*
X1615641Y277895D01*
X1615849Y277686D01*
G01X1605008Y278878D02*
Y281378D01*
X1606049D01*
X1606383Y281253D01*
X1606591Y281086D01*
X1606674Y280753D01*
X1606591Y280420D01*
X1606341Y280211D01*
X1606049Y280086D01*
X1605008D01*
G01X1606049D02*
X1606674Y278878D01*
G01X1608941D02*
X1609233Y278920D01*
X1609566Y279045D01*
X1609774Y279253D01*
X1609858Y279545D01*
X1609774Y279836D01*
X1609524Y280086D01*
X1609149Y280211D01*
X1608733D01*
X1608483Y280295D01*
X1608274Y280503D01*
X1608191Y280795D01*
X1608316Y281086D01*
X1608608Y281295D01*
X1608941Y281378D01*
X1609274Y281295D01*
X1609566Y281086D01*
X1609691Y280795D01*
X1609608Y280503D01*
X1609399Y280295D01*
X1609149Y280211D01*
X1608733D01*
X1608358Y280086D01*
X1608108Y279836D01*
X1608024Y279545D01*
X1608108Y279253D01*
X1608316Y279045D01*
X1608649Y278920D01*
X1608941Y278878D01*
G01X1612874D02*
X1611208D01*
Y281378D01*
X1612874D01*
G01X1612208Y280170D02*
X1611208D01*
G01X1615641Y278878D02*
Y281378D01*
X1614099Y279586D01*
X1616183D01*
G01X1603406Y273890D02*
X1600906D01*
Y274931D01*
X1601031Y275265D01*
X1601198Y275473D01*
X1601531Y275556D01*
X1601864Y275473D01*
X1602073Y275223D01*
X1602198Y274931D01*
Y273890D01*
G01Y274931D02*
X1603406Y275556D01*
G01Y277823D02*
X1603364Y278115D01*
X1603239Y278448D01*
X1603031Y278656D01*
X1602739Y278740D01*
X1602448Y278656D01*
X1602198Y278406D01*
X1602073Y278031D01*
Y277615D01*
X1601989Y277365D01*
X1601781Y277156D01*
X1601489Y277073D01*
X1601198Y277198D01*
X1600989Y277490D01*
X1600906Y277823D01*
X1600989Y278156D01*
X1601198Y278448D01*
X1601489Y278573D01*
X1601781Y278490D01*
X1601989Y278281D01*
X1602073Y278031D01*
Y277615D01*
X1602198Y277240D01*
X1602448Y276990D01*
X1602739Y276906D01*
X1603031Y276990D01*
X1603239Y277198D01*
X1603364Y277531D01*
X1603406Y277823D01*
G01Y281756D02*
Y280090D01*
X1600906D01*
Y281756D01*
G01X1602114Y281090D02*
Y280090D01*
G01X1601323Y283231D02*
X1601073Y283481D01*
X1600948Y283773D01*
X1600906Y284106D01*
X1600989Y284523D01*
X1601198Y284815D01*
X1601448Y284898D01*
X1601698Y284856D01*
X1601906Y284690D01*
X1602323Y283856D01*
X1602614Y283481D01*
X1603031Y283231D01*
X1603406Y283148D01*
Y284898D01*
G01X1608967Y227867D02*
Y230367D01*
X1610008D01*
X1610342Y230242D01*
X1610550Y230075D01*
X1610633Y229742D01*
X1610550Y229409D01*
X1610300Y229200D01*
X1610008Y229075D01*
X1608967D01*
G01X1610008D02*
X1610633Y227867D01*
G01X1612900D02*
X1613192Y227909D01*
X1613525Y228034D01*
X1613733Y228242D01*
X1613817Y228534D01*
X1613733Y228825D01*
X1613483Y229075D01*
X1613108Y229200D01*
X1612692D01*
X1612442Y229284D01*
X1612233Y229492D01*
X1612150Y229784D01*
X1612275Y230075D01*
X1612567Y230284D01*
X1612900Y230367D01*
X1613233Y230284D01*
X1613525Y230075D01*
X1613650Y229784D01*
X1613567Y229492D01*
X1613358Y229284D01*
X1613108Y229200D01*
X1612692D01*
X1612317Y229075D01*
X1612067Y228825D01*
X1611983Y228534D01*
X1612067Y228242D01*
X1612275Y228034D01*
X1612608Y227909D01*
X1612900Y227867D01*
G01X1615083D02*
Y230367D01*
X1615917D01*
X1616250Y230242D01*
X1616500Y230075D01*
X1616708Y229825D01*
X1616875Y229534D01*
X1616917Y229117D01*
X1616875Y228700D01*
X1616708Y228409D01*
X1616500Y228159D01*
X1616250Y227992D01*
X1615917Y227867D01*
X1615083D01*
G01X1618308Y229950D02*
X1618558Y230200D01*
X1618850Y230325D01*
X1619183Y230367D01*
X1619600Y230284D01*
X1619892Y230075D01*
X1619975Y229825D01*
X1619933Y229575D01*
X1619767Y229367D01*
X1618933Y228950D01*
X1618558Y228659D01*
X1618308Y228242D01*
X1618225Y227867D01*
X1619975D01*
G01X1621283Y228367D02*
X1621533Y228075D01*
X1621867Y227909D01*
X1622242Y227867D01*
X1622575Y227909D01*
X1622908Y228117D01*
X1623117Y228367D01*
X1623158Y228617D01*
X1623075Y228909D01*
X1622783Y229117D01*
X1622492Y229200D01*
X1622117D01*
G01X1622492D02*
X1622742Y229325D01*
X1622950Y229534D01*
X1623033Y229784D01*
X1622950Y230034D01*
X1622742Y230242D01*
X1622367Y230367D01*
X1621992Y230325D01*
X1621617Y230159D01*
G01X1608990Y239343D02*
X1609258Y239704D01*
X1609488Y239911D01*
X1609795Y240014D01*
X1610063Y239911D01*
X1610255Y239704D01*
X1610408Y239394D01*
X1610446Y239033D01*
X1610408Y238723D01*
X1610255Y238413D01*
X1610025Y238154D01*
X1609756Y238051D01*
X1609450Y238154D01*
X1609181Y238464D01*
X1609028Y238929D01*
X1608990Y239446D01*
X1609066Y240118D01*
X1609181Y240479D01*
X1609373Y240841D01*
X1609641Y241099D01*
X1609910Y241151D01*
X1610178Y241048D01*
X1610370Y240789D01*
G01X1637611Y255811D02*
X1637688Y256483D01*
X1637803Y257051D01*
X1637956Y257568D01*
X1638148Y258136D01*
X1638455Y258911D01*
X1636921D01*
G01X1637950Y235467D02*
Y238567D01*
X1637490Y237947D01*
G01Y235467D02*
X1638410D01*
G01X1641050D02*
Y238567D01*
X1640590Y237947D01*
G01Y235467D02*
X1641510D01*
G01X1641600Y262417D02*
X1641850Y262625D01*
X1642017Y262875D01*
X1642100Y263167D01*
X1642017Y263500D01*
X1641850Y263750D01*
X1641600Y264000D01*
X1641267Y264083D01*
X1639600D01*
G01X1642100Y266350D02*
X1642058Y266642D01*
X1641933Y266975D01*
X1641725Y267183D01*
X1641433Y267267D01*
X1641142Y267183D01*
X1640892Y266933D01*
X1640767Y266558D01*
Y266142D01*
X1640683Y265892D01*
X1640475Y265683D01*
X1640183Y265600D01*
X1639892Y265725D01*
X1639683Y266017D01*
X1639600Y266350D01*
X1639683Y266683D01*
X1639892Y266975D01*
X1640183Y267100D01*
X1640475Y267017D01*
X1640683Y266808D01*
X1640767Y266558D01*
Y266142D01*
X1640892Y265767D01*
X1641142Y265517D01*
X1641433Y265433D01*
X1641725Y265517D01*
X1641933Y265725D01*
X1642058Y266058D01*
X1642100Y266350D01*
G01Y270283D02*
Y268617D01*
X1639600D01*
Y270283D01*
G01X1640808Y269617D02*
Y268617D01*
G01X1642100Y272550D02*
X1639600D01*
X1640100Y272050D01*
G01X1642100D02*
Y273050D01*
G01X1593408Y242167D02*
X1593283Y241917D01*
X1593200Y241625D01*
Y241292D01*
X1593325Y240917D01*
X1593533Y240625D01*
X1593783Y240417D01*
X1594200Y240250D01*
X1594575Y240208D01*
X1594950Y240292D01*
X1595200Y240417D01*
X1595450Y240667D01*
X1595617Y240958D01*
X1595700Y241250D01*
Y241542D01*
X1595617Y241833D01*
X1595492Y242083D01*
X1595325Y242292D01*
G01X1595700Y244350D02*
X1595658Y244642D01*
X1595533Y244975D01*
X1595325Y245183D01*
X1595033Y245267D01*
X1594742Y245183D01*
X1594492Y244933D01*
X1594367Y244558D01*
Y244142D01*
X1594283Y243892D01*
X1594075Y243683D01*
X1593783Y243600D01*
X1593492Y243725D01*
X1593283Y244017D01*
X1593200Y244350D01*
X1593283Y244683D01*
X1593492Y244975D01*
X1593783Y245100D01*
X1594075Y245017D01*
X1594283Y244808D01*
X1594367Y244558D01*
Y244142D01*
X1594492Y243767D01*
X1594742Y243517D01*
X1595033Y243433D01*
X1595325Y243517D01*
X1595533Y243725D01*
X1595658Y244058D01*
X1595700Y244350D01*
G01Y248283D02*
Y246617D01*
X1593200D01*
Y248283D01*
G01X1594408Y247617D02*
Y246617D01*
G01X1595700Y251050D02*
X1593200D01*
X1594992Y249508D01*
Y251592D01*
G01X1591965Y234947D02*
Y252947D01*
G01X1633717Y314400D02*
Y316900D01*
X1634758D01*
X1635092Y316775D01*
X1635300Y316608D01*
X1635383Y316275D01*
X1635300Y315942D01*
X1635050Y315733D01*
X1634758Y315608D01*
X1633717D01*
G01X1634758D02*
X1635383Y314400D01*
G01X1636858Y316483D02*
X1637108Y316733D01*
X1637400Y316858D01*
X1637733Y316900D01*
X1638150Y316817D01*
X1638442Y316608D01*
X1638525Y316358D01*
X1638483Y316108D01*
X1638317Y315900D01*
X1637483Y315483D01*
X1637108Y315192D01*
X1636858Y314775D01*
X1636775Y314400D01*
X1638525D01*
G01X1639917D02*
Y316900D01*
X1640917D01*
X1641250Y316775D01*
X1641500Y316483D01*
X1641583Y316150D01*
X1641500Y315817D01*
X1641292Y315567D01*
X1640917Y315442D01*
X1639917D01*
G01X1643850Y314400D02*
X1644142Y314442D01*
X1644475Y314567D01*
X1644683Y314775D01*
X1644767Y315067D01*
X1644683Y315358D01*
X1644433Y315608D01*
X1644058Y315733D01*
X1643642D01*
X1643392Y315817D01*
X1643183Y316025D01*
X1643100Y316317D01*
X1643225Y316608D01*
X1643517Y316817D01*
X1643850Y316900D01*
X1644183Y316817D01*
X1644475Y316608D01*
X1644600Y316317D01*
X1644517Y316025D01*
X1644308Y315817D01*
X1644058Y315733D01*
X1643642D01*
X1643267Y315608D01*
X1643017Y315358D01*
X1642933Y315067D01*
X1643017Y314775D01*
X1643225Y314567D01*
X1643558Y314442D01*
X1643850Y314400D01*
G01X1605008Y282278D02*
Y284778D01*
X1606049D01*
X1606383Y284653D01*
X1606591Y284486D01*
X1606674Y284153D01*
X1606591Y283820D01*
X1606341Y283611D01*
X1606049Y283486D01*
X1605008D01*
G01X1606049D02*
X1606674Y282278D01*
G01X1608941D02*
X1609233Y282320D01*
X1609566Y282445D01*
X1609774Y282653D01*
X1609858Y282945D01*
X1609774Y283236D01*
X1609524Y283486D01*
X1609149Y283611D01*
X1608733D01*
X1608483Y283695D01*
X1608274Y283903D01*
X1608191Y284195D01*
X1608316Y284486D01*
X1608608Y284695D01*
X1608941Y284778D01*
X1609274Y284695D01*
X1609566Y284486D01*
X1609691Y284195D01*
X1609608Y283903D01*
X1609399Y283695D01*
X1609149Y283611D01*
X1608733D01*
X1608358Y283486D01*
X1608108Y283236D01*
X1608024Y282945D01*
X1608108Y282653D01*
X1608316Y282445D01*
X1608649Y282320D01*
X1608941Y282278D01*
G01X1612874D02*
X1611208D01*
Y284778D01*
X1612874D01*
G01X1612208Y283570D02*
X1611208D01*
G01X1615141Y282278D02*
Y284778D01*
X1614641Y284278D01*
G01Y282278D02*
X1615641D01*
G01X1618241Y284778D02*
X1617908Y284695D01*
X1617658Y284486D01*
X1617491Y284236D01*
X1617366Y283903D01*
X1617324Y283528D01*
X1617366Y283153D01*
X1617491Y282820D01*
X1617658Y282570D01*
X1617908Y282361D01*
X1618241Y282278D01*
X1618574Y282361D01*
X1618824Y282570D01*
X1618991Y282820D01*
X1619116Y283153D01*
X1619158Y283528D01*
X1619116Y283903D01*
X1618991Y284236D01*
X1618824Y284486D01*
X1618574Y284695D01*
X1618241Y284778D01*
G01X1596506Y334113D02*
X1594006D01*
Y335154D01*
X1594131Y335488D01*
X1594298Y335696D01*
X1594631Y335779D01*
X1594964Y335696D01*
X1595173Y335446D01*
X1595298Y335154D01*
Y334113D01*
G01Y335154D02*
X1596506Y335779D01*
G01X1594423Y337254D02*
X1594173Y337504D01*
X1594048Y337796D01*
X1594006Y338129D01*
X1594089Y338546D01*
X1594298Y338838D01*
X1594548Y338921D01*
X1594798Y338879D01*
X1595006Y338713D01*
X1595423Y337879D01*
X1595714Y337504D01*
X1596131Y337254D01*
X1596506Y337171D01*
Y338921D01*
G01Y340313D02*
X1594006D01*
Y341313D01*
X1594131Y341646D01*
X1594423Y341896D01*
X1594756Y341979D01*
X1595089Y341896D01*
X1595339Y341688D01*
X1595464Y341313D01*
Y340313D01*
G01X1596506Y344246D02*
X1594006D01*
X1594506Y343746D01*
G01X1596506D02*
Y344746D01*
G01Y347846D02*
X1594006D01*
X1595798Y346304D01*
Y348388D01*
G01X1596714Y318179D02*
X1594214D01*
Y319220D01*
X1594339Y319554D01*
X1594506Y319762D01*
X1594839Y319845D01*
X1595172Y319762D01*
X1595381Y319512D01*
X1595506Y319220D01*
Y318179D01*
G01Y319220D02*
X1596714Y319845D01*
G01X1594631Y321320D02*
X1594381Y321570D01*
X1594256Y321862D01*
X1594214Y322195D01*
X1594297Y322612D01*
X1594506Y322904D01*
X1594756Y322987D01*
X1595006Y322945D01*
X1595214Y322779D01*
X1595631Y321945D01*
X1595922Y321570D01*
X1596339Y321320D01*
X1596714Y321237D01*
Y322987D01*
G01Y324379D02*
X1594214D01*
Y325379D01*
X1594339Y325712D01*
X1594631Y325962D01*
X1594964Y326045D01*
X1595297Y325962D01*
X1595547Y325754D01*
X1595672Y325379D01*
Y324379D01*
G01X1596714Y328312D02*
X1594214D01*
X1594714Y327812D01*
G01X1596714D02*
Y328812D01*
G01X1595672Y330620D02*
X1595381Y330912D01*
X1595214Y331162D01*
X1595131Y331495D01*
X1595214Y331787D01*
X1595381Y331995D01*
X1595631Y332162D01*
X1595922Y332204D01*
X1596172Y332162D01*
X1596422Y331995D01*
X1596631Y331745D01*
X1596714Y331454D01*
X1596631Y331120D01*
X1596381Y330829D01*
X1596006Y330662D01*
X1595589Y330620D01*
X1595047Y330704D01*
X1594756Y330829D01*
X1594464Y331037D01*
X1594256Y331329D01*
X1594214Y331620D01*
X1594297Y331912D01*
X1594506Y332120D01*
G01X1606652Y327477D02*
X1604152D01*
Y328518D01*
X1604277Y328852D01*
X1604444Y329060D01*
X1604777Y329143D01*
X1605110Y329060D01*
X1605319Y328810D01*
X1605444Y328518D01*
Y327477D01*
G01Y328518D02*
X1606652Y329143D01*
G01X1604569Y330618D02*
X1604319Y330868D01*
X1604194Y331160D01*
X1604152Y331493D01*
X1604235Y331910D01*
X1604444Y332202D01*
X1604694Y332285D01*
X1604944Y332243D01*
X1605152Y332077D01*
X1605569Y331243D01*
X1605860Y330868D01*
X1606277Y330618D01*
X1606652Y330535D01*
Y332285D01*
G01Y333677D02*
X1604152D01*
Y334677D01*
X1604277Y335010D01*
X1604569Y335260D01*
X1604902Y335343D01*
X1605235Y335260D01*
X1605485Y335052D01*
X1605610Y334677D01*
Y333677D01*
G01X1606652Y337610D02*
X1604152D01*
X1604652Y337110D01*
G01X1606652D02*
Y338110D01*
G01X1606277Y339793D02*
X1606485Y340043D01*
X1606610Y340335D01*
X1606652Y340710D01*
X1606569Y341085D01*
X1606402Y341377D01*
X1606110Y341585D01*
X1605777Y341627D01*
X1605444Y341543D01*
X1605235Y341335D01*
X1605069Y341043D01*
X1605027Y340752D01*
X1605069Y340460D01*
X1605235Y340085D01*
X1604152Y340210D01*
Y341335D01*
G01X1592693Y302617D02*
X1590193D01*
Y303658D01*
X1590318Y303992D01*
X1590485Y304200D01*
X1590818Y304283D01*
X1591151Y304200D01*
X1591360Y303950D01*
X1591485Y303658D01*
Y302617D01*
G01Y303658D02*
X1592693Y304283D01*
G01Y306550D02*
X1592651Y306842D01*
X1592526Y307175D01*
X1592318Y307383D01*
X1592026Y307467D01*
X1591735Y307383D01*
X1591485Y307133D01*
X1591360Y306758D01*
Y306342D01*
X1591276Y306092D01*
X1591068Y305883D01*
X1590776Y305800D01*
X1590485Y305925D01*
X1590276Y306217D01*
X1590193Y306550D01*
X1590276Y306883D01*
X1590485Y307175D01*
X1590776Y307300D01*
X1591068Y307217D01*
X1591276Y307008D01*
X1591360Y306758D01*
Y306342D01*
X1591485Y305967D01*
X1591735Y305717D01*
X1592026Y305633D01*
X1592318Y305717D01*
X1592526Y305925D01*
X1592651Y306258D01*
X1592693Y306550D01*
G01Y310483D02*
Y308817D01*
X1590193D01*
Y310483D01*
G01X1591401Y309817D02*
Y308817D01*
G01X1592693Y312667D02*
X1592151Y312750D01*
X1591693Y312875D01*
X1591276Y313042D01*
X1590818Y313250D01*
X1590193Y313583D01*
Y311917D01*
G01X1604983Y285726D02*
Y288226D01*
X1606024D01*
X1606358Y288101D01*
X1606566Y287934D01*
X1606649Y287601D01*
X1606566Y287268D01*
X1606316Y287059D01*
X1606024Y286934D01*
X1604983D01*
G01X1606024D02*
X1606649Y285726D01*
G01X1608916D02*
X1609208Y285768D01*
X1609541Y285893D01*
X1609749Y286101D01*
X1609833Y286393D01*
X1609749Y286684D01*
X1609499Y286934D01*
X1609124Y287059D01*
X1608708D01*
X1608458Y287143D01*
X1608249Y287351D01*
X1608166Y287643D01*
X1608291Y287934D01*
X1608583Y288143D01*
X1608916Y288226D01*
X1609249Y288143D01*
X1609541Y287934D01*
X1609666Y287643D01*
X1609583Y287351D01*
X1609374Y287143D01*
X1609124Y287059D01*
X1608708D01*
X1608333Y286934D01*
X1608083Y286684D01*
X1607999Y286393D01*
X1608083Y286101D01*
X1608291Y285893D01*
X1608624Y285768D01*
X1608916Y285726D01*
G01X1612849D02*
X1611183D01*
Y288226D01*
X1612849D01*
G01X1612183Y287018D02*
X1611183D01*
G01X1614408Y286018D02*
X1614699Y285809D01*
X1615033Y285726D01*
X1615366Y285809D01*
X1615658Y286059D01*
X1615866Y286434D01*
X1615949Y286809D01*
Y287268D01*
X1615866Y287643D01*
X1615658Y287976D01*
X1615408Y288143D01*
X1615116Y288226D01*
X1614783Y288143D01*
X1614533Y287976D01*
X1614366Y287726D01*
X1614283Y287393D01*
X1614366Y287101D01*
X1614574Y286809D01*
X1614824Y286643D01*
X1615116Y286601D01*
X1615449Y286684D01*
X1615699Y286893D01*
X1615949Y287268D01*
G01X1598453Y326872D02*
X1600245D01*
X1600620Y327039D01*
X1600870Y327372D01*
X1600953Y327789D01*
X1600870Y328206D01*
X1600620Y328539D01*
X1600245Y328706D01*
X1598453D01*
G01X1598870Y330097D02*
X1598620Y330347D01*
X1598495Y330639D01*
X1598453Y330972D01*
X1598536Y331389D01*
X1598745Y331681D01*
X1598995Y331764D01*
X1599245Y331722D01*
X1599453Y331556D01*
X1599870Y330722D01*
X1600161Y330347D01*
X1600578Y330097D01*
X1600953Y330014D01*
Y331764D01*
G01Y333156D02*
X1598453D01*
Y334156D01*
X1598578Y334489D01*
X1598870Y334739D01*
X1599203Y334822D01*
X1599536Y334739D01*
X1599786Y334531D01*
X1599911Y334156D01*
Y333156D01*
G01X1600953Y337089D02*
X1598453D01*
X1598953Y336589D01*
G01X1600953D02*
Y337589D01*
G01X1637329Y322567D02*
X1637079Y322692D01*
X1636787Y322775D01*
X1636454D01*
X1636079Y322650D01*
X1635787Y322442D01*
X1635579Y322192D01*
X1635412Y321775D01*
X1635370Y321400D01*
X1635454Y321025D01*
X1635579Y320775D01*
X1635829Y320525D01*
X1636120Y320358D01*
X1636412Y320275D01*
X1636704D01*
X1636995Y320358D01*
X1637245Y320483D01*
X1637454Y320650D01*
G01X1639512Y320275D02*
X1639804Y320317D01*
X1640137Y320442D01*
X1640345Y320650D01*
X1640429Y320942D01*
X1640345Y321233D01*
X1640095Y321483D01*
X1639720Y321608D01*
X1639304D01*
X1639054Y321692D01*
X1638845Y321900D01*
X1638762Y322192D01*
X1638887Y322483D01*
X1639179Y322692D01*
X1639512Y322775D01*
X1639845Y322692D01*
X1640137Y322483D01*
X1640262Y322192D01*
X1640179Y321900D01*
X1639970Y321692D01*
X1639720Y321608D01*
X1639304D01*
X1638929Y321483D01*
X1638679Y321233D01*
X1638595Y320942D01*
X1638679Y320650D01*
X1638887Y320442D01*
X1639220Y320317D01*
X1639512Y320275D01*
G01X1641695D02*
Y322775D01*
X1642529D01*
X1642862Y322650D01*
X1643112Y322483D01*
X1643320Y322233D01*
X1643487Y321942D01*
X1643529Y321525D01*
X1643487Y321108D01*
X1643320Y320817D01*
X1643112Y320567D01*
X1642862Y320400D01*
X1642529Y320275D01*
X1641695D01*
G01X1644795Y320775D02*
X1645045Y320483D01*
X1645379Y320317D01*
X1645754Y320275D01*
X1646087Y320317D01*
X1646420Y320525D01*
X1646629Y320775D01*
X1646670Y321025D01*
X1646587Y321317D01*
X1646295Y321525D01*
X1646004Y321608D01*
X1645629D01*
G01X1646004D02*
X1646254Y321733D01*
X1646462Y321942D01*
X1646545Y322192D01*
X1646462Y322442D01*
X1646254Y322650D01*
X1645879Y322775D01*
X1645504Y322733D01*
X1645129Y322567D01*
G01X1615142Y341667D02*
X1615017Y341417D01*
X1614934Y341125D01*
Y340792D01*
X1615059Y340417D01*
X1615267Y340125D01*
X1615517Y339917D01*
X1615934Y339750D01*
X1616309Y339708D01*
X1616684Y339792D01*
X1616934Y339917D01*
X1617184Y340167D01*
X1617351Y340458D01*
X1617434Y340750D01*
Y341042D01*
X1617351Y341333D01*
X1617226Y341583D01*
X1617059Y341792D01*
G01X1615351Y343058D02*
X1615101Y343308D01*
X1614976Y343600D01*
X1614934Y343933D01*
X1615017Y344350D01*
X1615226Y344642D01*
X1615476Y344725D01*
X1615726Y344683D01*
X1615934Y344517D01*
X1616351Y343683D01*
X1616642Y343308D01*
X1617059Y343058D01*
X1617434Y342975D01*
Y344725D01*
G01Y346117D02*
X1614934D01*
Y347158D01*
X1615059Y347492D01*
X1615226Y347700D01*
X1615559Y347783D01*
X1615892Y347700D01*
X1616101Y347450D01*
X1616226Y347158D01*
Y346117D01*
G01Y347158D02*
X1617434Y347783D01*
G01X1616392Y349258D02*
X1616101Y349550D01*
X1615934Y349800D01*
X1615851Y350133D01*
X1615934Y350425D01*
X1616101Y350633D01*
X1616351Y350800D01*
X1616642Y350842D01*
X1616892Y350800D01*
X1617142Y350633D01*
X1617351Y350383D01*
X1617434Y350092D01*
X1617351Y349758D01*
X1617101Y349467D01*
X1616726Y349300D01*
X1616309Y349258D01*
X1615767Y349342D01*
X1615476Y349467D01*
X1615184Y349675D01*
X1614976Y349967D01*
X1614934Y350258D01*
X1615017Y350550D01*
X1615226Y350758D01*
G01X1600249Y320517D02*
X1599999Y320642D01*
X1599707Y320725D01*
X1599374D01*
X1598999Y320600D01*
X1598707Y320392D01*
X1598499Y320142D01*
X1598332Y319725D01*
X1598290Y319350D01*
X1598374Y318975D01*
X1598499Y318725D01*
X1598749Y318475D01*
X1599040Y318308D01*
X1599332Y318225D01*
X1599624D01*
X1599915Y318308D01*
X1600165Y318433D01*
X1600374Y318600D01*
G01X1601640Y320308D02*
X1601890Y320558D01*
X1602182Y320683D01*
X1602515Y320725D01*
X1602932Y320642D01*
X1603224Y320433D01*
X1603307Y320183D01*
X1603265Y319933D01*
X1603099Y319725D01*
X1602265Y319308D01*
X1601890Y319017D01*
X1601640Y318600D01*
X1601557Y318225D01*
X1603307D01*
G01X1604699D02*
Y320725D01*
X1605699D01*
X1606032Y320600D01*
X1606282Y320308D01*
X1606365Y319975D01*
X1606282Y319642D01*
X1606074Y319392D01*
X1605699Y319267D01*
X1604699D01*
G01X1607924Y318517D02*
X1608215Y318308D01*
X1608549Y318225D01*
X1608882Y318308D01*
X1609174Y318558D01*
X1609382Y318933D01*
X1609465Y319308D01*
Y319767D01*
X1609382Y320142D01*
X1609174Y320475D01*
X1608924Y320642D01*
X1608632Y320725D01*
X1608299Y320642D01*
X1608049Y320475D01*
X1607882Y320225D01*
X1607799Y319892D01*
X1607882Y319600D01*
X1608090Y319308D01*
X1608340Y319142D01*
X1608632Y319100D01*
X1608965Y319183D01*
X1609215Y319392D01*
X1609465Y319767D01*
G01X1594650Y302514D02*
X1594525Y302264D01*
X1594442Y301972D01*
Y301639D01*
X1594567Y301264D01*
X1594775Y300972D01*
X1595025Y300764D01*
X1595442Y300597D01*
X1595817Y300555D01*
X1596192Y300639D01*
X1596442Y300764D01*
X1596692Y301014D01*
X1596859Y301305D01*
X1596942Y301597D01*
Y301889D01*
X1596859Y302180D01*
X1596734Y302430D01*
X1596567Y302639D01*
G01X1596942Y303864D02*
X1594442D01*
Y304905D01*
X1594567Y305239D01*
X1594734Y305447D01*
X1595067Y305530D01*
X1595400Y305447D01*
X1595609Y305197D01*
X1595734Y304905D01*
Y303864D01*
G01Y304905D02*
X1596942Y305530D01*
G01Y307797D02*
X1596900Y308089D01*
X1596775Y308422D01*
X1596567Y308630D01*
X1596275Y308714D01*
X1595984Y308630D01*
X1595734Y308380D01*
X1595609Y308005D01*
Y307589D01*
X1595525Y307339D01*
X1595317Y307130D01*
X1595025Y307047D01*
X1594734Y307172D01*
X1594525Y307464D01*
X1594442Y307797D01*
X1594525Y308130D01*
X1594734Y308422D01*
X1595025Y308547D01*
X1595317Y308464D01*
X1595525Y308255D01*
X1595609Y308005D01*
Y307589D01*
X1595734Y307214D01*
X1595984Y306964D01*
X1596275Y306880D01*
X1596567Y306964D01*
X1596775Y307172D01*
X1596900Y307505D01*
X1596942Y307797D01*
G01Y311730D02*
Y310064D01*
X1594442D01*
Y311730D01*
G01X1595650Y311064D02*
Y310064D01*
G01X1596942Y313997D02*
X1594442D01*
X1594942Y313497D01*
G01X1596942D02*
Y314497D01*
G01X1622691Y333023D02*
Y331231D01*
X1622858Y330856D01*
X1623191Y330606D01*
X1623608Y330523D01*
X1624025Y330606D01*
X1624358Y330856D01*
X1624525Y331231D01*
Y333023D01*
G01X1626708Y330523D02*
X1627000Y330565D01*
X1627333Y330690D01*
X1627541Y330898D01*
X1627625Y331190D01*
X1627541Y331481D01*
X1627291Y331731D01*
X1626916Y331856D01*
X1626500D01*
X1626250Y331940D01*
X1626041Y332148D01*
X1625958Y332440D01*
X1626083Y332731D01*
X1626375Y332940D01*
X1626708Y333023D01*
X1627041Y332940D01*
X1627333Y332731D01*
X1627458Y332440D01*
X1627375Y332148D01*
X1627166Y331940D01*
X1626916Y331856D01*
X1626500D01*
X1626125Y331731D01*
X1625875Y331481D01*
X1625791Y331190D01*
X1625875Y330898D01*
X1626083Y330690D01*
X1626416Y330565D01*
X1626708Y330523D01*
G01X1630641D02*
X1628975D01*
Y333023D01*
X1630641D01*
G01X1629975Y331815D02*
X1628975D01*
G01X1632908Y330523D02*
Y333023D01*
X1632408Y332523D01*
G01Y330523D02*
X1633408D01*
G01X1639688Y337594D02*
Y335961D01*
X1639042D01*
G01X1625967D02*
X1625318D01*
Y337594D01*
G01X1610767Y324000D02*
Y326500D01*
X1611808D01*
X1612142Y326375D01*
X1612350Y326208D01*
X1612433Y325875D01*
X1612350Y325542D01*
X1612100Y325333D01*
X1611808Y325208D01*
X1610767D01*
G01X1611808D02*
X1612433Y324000D01*
G01X1613617D02*
Y326500D01*
X1614700Y324417D01*
X1615783Y326500D01*
Y324000D01*
G01X1617800D02*
X1618092Y324042D01*
X1618425Y324167D01*
X1618633Y324375D01*
X1618717Y324667D01*
X1618633Y324958D01*
X1618383Y325208D01*
X1618008Y325333D01*
X1617592D01*
X1617342Y325417D01*
X1617133Y325625D01*
X1617050Y325917D01*
X1617175Y326208D01*
X1617467Y326417D01*
X1617800Y326500D01*
X1618133Y326417D01*
X1618425Y326208D01*
X1618550Y325917D01*
X1618467Y325625D01*
X1618258Y325417D01*
X1618008Y325333D01*
X1617592D01*
X1617217Y325208D01*
X1616967Y324958D01*
X1616883Y324667D01*
X1616967Y324375D01*
X1617175Y324167D01*
X1617508Y324042D01*
X1617800Y324000D01*
G01X1619983D02*
Y326500D01*
X1620817D01*
X1621150Y326375D01*
X1621400Y326208D01*
X1621608Y325958D01*
X1621775Y325667D01*
X1621817Y325250D01*
X1621775Y324833D01*
X1621608Y324542D01*
X1621400Y324292D01*
X1621150Y324125D01*
X1620817Y324000D01*
X1619983D01*
G01X1624000D02*
Y326500D01*
X1623500Y326000D01*
G01Y324000D02*
X1624500D01*
G01X1642826Y392840D02*
Y395340D01*
X1643867D01*
X1644201Y395215D01*
X1644409Y395048D01*
X1644492Y394715D01*
X1644409Y394382D01*
X1644159Y394173D01*
X1643867Y394048D01*
X1642826D01*
G01X1643867D02*
X1644492Y392840D01*
G01X1646051Y393132D02*
X1646342Y392923D01*
X1646676Y392840D01*
X1647009Y392923D01*
X1647301Y393173D01*
X1647509Y393548D01*
X1647592Y393923D01*
Y394382D01*
X1647509Y394757D01*
X1647301Y395090D01*
X1647051Y395257D01*
X1646759Y395340D01*
X1646426Y395257D01*
X1646176Y395090D01*
X1646009Y394840D01*
X1645926Y394507D01*
X1646009Y394215D01*
X1646217Y393923D01*
X1646467Y393757D01*
X1646759Y393715D01*
X1647092Y393798D01*
X1647342Y394007D01*
X1647592Y394382D01*
G01X1648609Y395340D02*
X1649192Y392840D01*
X1649859Y395340D01*
X1650526Y392840D01*
X1651109Y395340D01*
G01X1652959Y392840D02*
Y395340D01*
X1652459Y394840D01*
G01Y392840D02*
X1653459D01*
G01X1655351Y393132D02*
X1655642Y392923D01*
X1655976Y392840D01*
X1656309Y392923D01*
X1656601Y393173D01*
X1656809Y393548D01*
X1656892Y393923D01*
Y394382D01*
X1656809Y394757D01*
X1656601Y395090D01*
X1656351Y395257D01*
X1656059Y395340D01*
X1655726Y395257D01*
X1655476Y395090D01*
X1655309Y394840D01*
X1655226Y394507D01*
X1655309Y394215D01*
X1655517Y393923D01*
X1655767Y393757D01*
X1656059Y393715D01*
X1656392Y393798D01*
X1656642Y394007D01*
X1656892Y394382D01*
G01X1642837Y389190D02*
Y391690D01*
X1643878D01*
X1644212Y391565D01*
X1644420Y391398D01*
X1644503Y391065D01*
X1644420Y390732D01*
X1644170Y390523D01*
X1643878Y390398D01*
X1642837D01*
G01X1643878D02*
X1644503Y389190D01*
G01X1645978Y390232D02*
X1646270Y390523D01*
X1646520Y390690D01*
X1646853Y390773D01*
X1647145Y390690D01*
X1647353Y390523D01*
X1647520Y390273D01*
X1647562Y389982D01*
X1647520Y389732D01*
X1647353Y389482D01*
X1647103Y389273D01*
X1646812Y389190D01*
X1646478Y389273D01*
X1646187Y389523D01*
X1646020Y389898D01*
X1645978Y390315D01*
X1646062Y390857D01*
X1646187Y391148D01*
X1646395Y391440D01*
X1646687Y391648D01*
X1646978Y391690D01*
X1647270Y391607D01*
X1647478Y391398D01*
G01X1648620Y391690D02*
X1649203Y389190D01*
X1649870Y391690D01*
X1650537Y389190D01*
X1651120Y391690D01*
G01X1652178Y391273D02*
X1652428Y391523D01*
X1652720Y391648D01*
X1653053Y391690D01*
X1653470Y391607D01*
X1653762Y391398D01*
X1653845Y391148D01*
X1653803Y390898D01*
X1653637Y390690D01*
X1652803Y390273D01*
X1652428Y389982D01*
X1652178Y389565D01*
X1652095Y389190D01*
X1653845D01*
G01X1655278Y390232D02*
X1655570Y390523D01*
X1655820Y390690D01*
X1656153Y390773D01*
X1656445Y390690D01*
X1656653Y390523D01*
X1656820Y390273D01*
X1656862Y389982D01*
X1656820Y389732D01*
X1656653Y389482D01*
X1656403Y389273D01*
X1656112Y389190D01*
X1655778Y389273D01*
X1655487Y389523D01*
X1655320Y389898D01*
X1655278Y390315D01*
X1655362Y390857D01*
X1655487Y391148D01*
X1655695Y391440D01*
X1655987Y391648D01*
X1656278Y391690D01*
X1656570Y391607D01*
X1656778Y391398D01*
G01X1639500Y382167D02*
X1637000D01*
Y383208D01*
X1637125Y383542D01*
X1637292Y383750D01*
X1637625Y383833D01*
X1637958Y383750D01*
X1638167Y383500D01*
X1638292Y383208D01*
Y382167D01*
G01Y383208D02*
X1639500Y383833D01*
G01X1637417Y385308D02*
X1637167Y385558D01*
X1637042Y385850D01*
X1637000Y386183D01*
X1637083Y386600D01*
X1637292Y386892D01*
X1637542Y386975D01*
X1637792Y386933D01*
X1638000Y386767D01*
X1638417Y385933D01*
X1638708Y385558D01*
X1639125Y385308D01*
X1639500Y385225D01*
Y386975D01*
G01Y388242D02*
X1637000D01*
X1639500Y390158D01*
X1637000D01*
G01X1637417Y391508D02*
X1637167Y391758D01*
X1637042Y392050D01*
X1637000Y392383D01*
X1637083Y392800D01*
X1637292Y393092D01*
X1637542Y393175D01*
X1637792Y393133D01*
X1638000Y392967D01*
X1638417Y392133D01*
X1638708Y391758D01*
X1639125Y391508D01*
X1639500Y391425D01*
Y393175D01*
G01X1639208Y394692D02*
X1639417Y394983D01*
X1639500Y395317D01*
X1639417Y395650D01*
X1639167Y395942D01*
X1638792Y396150D01*
X1638417Y396233D01*
X1637958D01*
X1637583Y396150D01*
X1637250Y395942D01*
X1637083Y395692D01*
X1637000Y395400D01*
X1637083Y395067D01*
X1637250Y394817D01*
X1637500Y394650D01*
X1637833Y394567D01*
X1638125Y394650D01*
X1638417Y394858D01*
X1638583Y395108D01*
X1638625Y395400D01*
X1638542Y395733D01*
X1638333Y395983D01*
X1637958Y396233D01*
G01X1637700Y401867D02*
X1635200D01*
Y402908D01*
X1635325Y403242D01*
X1635492Y403450D01*
X1635825Y403533D01*
X1636158Y403450D01*
X1636367Y403200D01*
X1636492Y402908D01*
Y401867D01*
G01Y402908D02*
X1637700Y403533D01*
G01Y405800D02*
X1637658Y406092D01*
X1637533Y406425D01*
X1637325Y406633D01*
X1637033Y406717D01*
X1636742Y406633D01*
X1636492Y406383D01*
X1636367Y406008D01*
Y405592D01*
X1636283Y405342D01*
X1636075Y405133D01*
X1635783Y405050D01*
X1635492Y405175D01*
X1635283Y405467D01*
X1635200Y405800D01*
X1635283Y406133D01*
X1635492Y406425D01*
X1635783Y406550D01*
X1636075Y406467D01*
X1636283Y406258D01*
X1636367Y406008D01*
Y405592D01*
X1636492Y405217D01*
X1636742Y404967D01*
X1637033Y404883D01*
X1637325Y404967D01*
X1637533Y405175D01*
X1637658Y405508D01*
X1637700Y405800D01*
G01X1635408Y409817D02*
X1635283Y409567D01*
X1635200Y409275D01*
Y408942D01*
X1635325Y408567D01*
X1635533Y408275D01*
X1635783Y408067D01*
X1636200Y407900D01*
X1636575Y407858D01*
X1636950Y407942D01*
X1637200Y408067D01*
X1637450Y408317D01*
X1637617Y408608D01*
X1637700Y408900D01*
Y409192D01*
X1637617Y409483D01*
X1637492Y409733D01*
X1637325Y409942D01*
G01X1635617Y411208D02*
X1635367Y411458D01*
X1635242Y411750D01*
X1635200Y412083D01*
X1635283Y412500D01*
X1635492Y412792D01*
X1635742Y412875D01*
X1635992Y412833D01*
X1636200Y412667D01*
X1636617Y411833D01*
X1636908Y411458D01*
X1637325Y411208D01*
X1637700Y411125D01*
Y412875D01*
G01Y415600D02*
X1635200D01*
X1636992Y414058D01*
Y416142D01*
G01X1620334Y354617D02*
X1617834D01*
Y355658D01*
X1617959Y355992D01*
X1618126Y356200D01*
X1618459Y356283D01*
X1618792Y356200D01*
X1619001Y355950D01*
X1619126Y355658D01*
Y354617D01*
G01Y355658D02*
X1620334Y356283D01*
G01Y358550D02*
X1620292Y358842D01*
X1620167Y359175D01*
X1619959Y359383D01*
X1619667Y359467D01*
X1619376Y359383D01*
X1619126Y359133D01*
X1619001Y358758D01*
Y358342D01*
X1618917Y358092D01*
X1618709Y357883D01*
X1618417Y357800D01*
X1618126Y357925D01*
X1617917Y358217D01*
X1617834Y358550D01*
X1617917Y358883D01*
X1618126Y359175D01*
X1618417Y359300D01*
X1618709Y359217D01*
X1618917Y359008D01*
X1619001Y358758D01*
Y358342D01*
X1619126Y357967D01*
X1619376Y357717D01*
X1619667Y357633D01*
X1619959Y357717D01*
X1620167Y357925D01*
X1620292Y358258D01*
X1620334Y358550D01*
G01Y362483D02*
Y360817D01*
X1617834D01*
Y362483D01*
G01X1619042Y361817D02*
Y360817D01*
G01X1619959Y363833D02*
X1620167Y364083D01*
X1620292Y364375D01*
X1620334Y364750D01*
X1620251Y365125D01*
X1620084Y365417D01*
X1619792Y365625D01*
X1619459Y365667D01*
X1619126Y365583D01*
X1618917Y365375D01*
X1618751Y365083D01*
X1618709Y364792D01*
X1618751Y364500D01*
X1618917Y364125D01*
X1617834Y364250D01*
Y365375D01*
G01X1641750Y402447D02*
X1639250D01*
Y403488D01*
X1639375Y403822D01*
X1639542Y404030D01*
X1639875Y404113D01*
X1640208Y404030D01*
X1640417Y403780D01*
X1640542Y403488D01*
Y402447D01*
G01Y403488D02*
X1641750Y404113D01*
G01Y406380D02*
X1639250D01*
X1639750Y405880D01*
G01X1641750D02*
Y406880D01*
G01X1639250Y408230D02*
X1641750Y408813D01*
X1639250Y409480D01*
X1641750Y410147D01*
X1639250Y410730D01*
G01X1641250Y411663D02*
X1641542Y411913D01*
X1641708Y412247D01*
X1641750Y412622D01*
X1641708Y412955D01*
X1641500Y413288D01*
X1641250Y413497D01*
X1641000Y413538D01*
X1640708Y413455D01*
X1640500Y413163D01*
X1640417Y412872D01*
Y412497D01*
G01Y412872D02*
X1640292Y413122D01*
X1640083Y413330D01*
X1639833Y413413D01*
X1639583Y413330D01*
X1639375Y413122D01*
X1639250Y412747D01*
X1639292Y412372D01*
X1639458Y411997D01*
G01X1639250Y415680D02*
X1639333Y415347D01*
X1639542Y415097D01*
X1639792Y414930D01*
X1640125Y414805D01*
X1640500Y414763D01*
X1640875Y414805D01*
X1641208Y414930D01*
X1641458Y415097D01*
X1641667Y415347D01*
X1641750Y415680D01*
X1641667Y416013D01*
X1641458Y416263D01*
X1641208Y416430D01*
X1640875Y416555D01*
X1640500Y416597D01*
X1640125Y416555D01*
X1639792Y416430D01*
X1639542Y416263D01*
X1639333Y416013D01*
X1639250Y415680D01*
G01X1616467Y382700D02*
Y385200D01*
X1617508D01*
X1617842Y385075D01*
X1618050Y384908D01*
X1618133Y384575D01*
X1618050Y384242D01*
X1617800Y384033D01*
X1617508Y383908D01*
X1616467D01*
G01X1617508D02*
X1618133Y382700D01*
G01X1619608Y384783D02*
X1619858Y385033D01*
X1620150Y385158D01*
X1620483Y385200D01*
X1620900Y385117D01*
X1621192Y384908D01*
X1621275Y384658D01*
X1621233Y384408D01*
X1621067Y384200D01*
X1620233Y383783D01*
X1619858Y383492D01*
X1619608Y383075D01*
X1619525Y382700D01*
X1621275D01*
G01X1622667D02*
Y385200D01*
X1623667D01*
X1624000Y385075D01*
X1624250Y384783D01*
X1624333Y384450D01*
X1624250Y384117D01*
X1624042Y383867D01*
X1623667Y383742D01*
X1622667D01*
G01X1626600Y382700D02*
Y385200D01*
X1626100Y384700D01*
G01Y382700D02*
X1627100D01*
G01X1628908Y384783D02*
X1629158Y385033D01*
X1629450Y385158D01*
X1629783Y385200D01*
X1630200Y385117D01*
X1630492Y384908D01*
X1630575Y384658D01*
X1630533Y384408D01*
X1630367Y384200D01*
X1629533Y383783D01*
X1629158Y383492D01*
X1628908Y383075D01*
X1628825Y382700D01*
X1630575D01*
G01X1629200Y395917D02*
X1626700D01*
Y396958D01*
X1626825Y397292D01*
X1626992Y397500D01*
X1627325Y397583D01*
X1627658Y397500D01*
X1627867Y397250D01*
X1627992Y396958D01*
Y395917D01*
G01Y396958D02*
X1629200Y397583D01*
G01Y399767D02*
X1628658Y399850D01*
X1628200Y399975D01*
X1627783Y400142D01*
X1627325Y400350D01*
X1626700Y400683D01*
Y399017D01*
G01Y401700D02*
X1629200Y402283D01*
X1626700Y402950D01*
X1629200Y403617D01*
X1626700Y404200D01*
G01X1629200Y406050D02*
X1626700D01*
X1627200Y405550D01*
G01X1629200D02*
Y406550D01*
G01Y409150D02*
X1626700D01*
X1627200Y408650D01*
G01X1629200D02*
Y409650D01*
G01X1634900Y382417D02*
X1632400D01*
Y383458D01*
X1632525Y383792D01*
X1632692Y384000D01*
X1633025Y384083D01*
X1633358Y384000D01*
X1633567Y383750D01*
X1633692Y383458D01*
Y382417D01*
G01Y383458D02*
X1634900Y384083D01*
G01Y386267D02*
X1634358Y386350D01*
X1633900Y386475D01*
X1633483Y386642D01*
X1633025Y386850D01*
X1632400Y387183D01*
Y385517D01*
G01Y388200D02*
X1634900Y388783D01*
X1632400Y389450D01*
X1634900Y390117D01*
X1632400Y390700D01*
G01X1634900Y392550D02*
X1632400D01*
X1632900Y392050D01*
G01X1634900D02*
Y393050D01*
G01X1632817Y394858D02*
X1632567Y395108D01*
X1632442Y395400D01*
X1632400Y395733D01*
X1632483Y396150D01*
X1632692Y396442D01*
X1632942Y396525D01*
X1633192Y396483D01*
X1633400Y396317D01*
X1633817Y395483D01*
X1634108Y395108D01*
X1634525Y394858D01*
X1634900Y394775D01*
Y396525D01*
G01X1614500Y384817D02*
X1612000D01*
Y385858D01*
X1612125Y386192D01*
X1612292Y386400D01*
X1612625Y386483D01*
X1612958Y386400D01*
X1613167Y386150D01*
X1613292Y385858D01*
Y384817D01*
G01Y385858D02*
X1614500Y386483D01*
G01Y388667D02*
X1613958Y388750D01*
X1613500Y388875D01*
X1613083Y389042D01*
X1612625Y389250D01*
X1612000Y389583D01*
Y387917D01*
G01Y390600D02*
X1614500Y391183D01*
X1612000Y391850D01*
X1614500Y392517D01*
X1612000Y393100D01*
G01X1614500Y394950D02*
X1612000D01*
X1612500Y394450D01*
G01X1614500D02*
Y395450D01*
G01X1613458Y397258D02*
X1613167Y397550D01*
X1613000Y397800D01*
X1612917Y398133D01*
X1613000Y398425D01*
X1613167Y398633D01*
X1613417Y398800D01*
X1613708Y398842D01*
X1613958Y398800D01*
X1614208Y398633D01*
X1614417Y398383D01*
X1614500Y398092D01*
X1614417Y397758D01*
X1614167Y397467D01*
X1613792Y397300D01*
X1613375Y397258D01*
X1612833Y397342D01*
X1612542Y397467D01*
X1612250Y397675D01*
X1612042Y397967D01*
X1612000Y398258D01*
X1612083Y398550D01*
X1612292Y398758D01*
G01X1633617Y376800D02*
Y379300D01*
X1634658D01*
X1634992Y379175D01*
X1635200Y379008D01*
X1635283Y378675D01*
X1635200Y378342D01*
X1634950Y378133D01*
X1634658Y378008D01*
X1633617D01*
G01X1634658D02*
X1635283Y376800D01*
G01X1637467D02*
X1637550Y377342D01*
X1637675Y377800D01*
X1637842Y378217D01*
X1638050Y378675D01*
X1638383Y379300D01*
X1636717D01*
G01X1639400D02*
X1639983Y376800D01*
X1640650Y379300D01*
X1641317Y376800D01*
X1641900Y379300D01*
G01X1643750Y376800D02*
Y379300D01*
X1643250Y378800D01*
G01Y376800D02*
X1644250D01*
G01X1646850D02*
X1647142Y376842D01*
X1647475Y376967D01*
X1647683Y377175D01*
X1647767Y377467D01*
X1647683Y377758D01*
X1647433Y378008D01*
X1647058Y378133D01*
X1646642D01*
X1646392Y378217D01*
X1646183Y378425D01*
X1646100Y378717D01*
X1646225Y379008D01*
X1646517Y379217D01*
X1646850Y379300D01*
X1647183Y379217D01*
X1647475Y379008D01*
X1647600Y378717D01*
X1647517Y378425D01*
X1647308Y378217D01*
X1647058Y378133D01*
X1646642D01*
X1646267Y378008D01*
X1646017Y377758D01*
X1645933Y377467D01*
X1646017Y377175D01*
X1646225Y376967D01*
X1646558Y376842D01*
X1646850Y376800D01*
G01X1612514Y371917D02*
X1612264Y372042D01*
X1611972Y372125D01*
X1611639D01*
X1611264Y372000D01*
X1610972Y371792D01*
X1610764Y371542D01*
X1610597Y371125D01*
X1610555Y370750D01*
X1610639Y370375D01*
X1610764Y370125D01*
X1611014Y369875D01*
X1611305Y369708D01*
X1611597Y369625D01*
X1611889D01*
X1612180Y369708D01*
X1612430Y369833D01*
X1612639Y370000D01*
G01X1614697Y369625D02*
X1614989Y369667D01*
X1615322Y369792D01*
X1615530Y370000D01*
X1615614Y370292D01*
X1615530Y370583D01*
X1615280Y370833D01*
X1614905Y370958D01*
X1614489D01*
X1614239Y371042D01*
X1614030Y371250D01*
X1613947Y371542D01*
X1614072Y371833D01*
X1614364Y372042D01*
X1614697Y372125D01*
X1615030Y372042D01*
X1615322Y371833D01*
X1615447Y371542D01*
X1615364Y371250D01*
X1615155Y371042D01*
X1614905Y370958D01*
X1614489D01*
X1614114Y370833D01*
X1613864Y370583D01*
X1613780Y370292D01*
X1613864Y370000D01*
X1614072Y369792D01*
X1614405Y369667D01*
X1614697Y369625D01*
G01X1618714Y371917D02*
X1618464Y372042D01*
X1618172Y372125D01*
X1617839D01*
X1617464Y372000D01*
X1617172Y371792D01*
X1616964Y371542D01*
X1616797Y371125D01*
X1616755Y370750D01*
X1616839Y370375D01*
X1616964Y370125D01*
X1617214Y369875D01*
X1617505Y369708D01*
X1617797Y369625D01*
X1618089D01*
X1618380Y369708D01*
X1618630Y369833D01*
X1618839Y370000D01*
G01X1619980D02*
X1620230Y369792D01*
X1620522Y369667D01*
X1620897Y369625D01*
X1621272Y369708D01*
X1621564Y369875D01*
X1621772Y370167D01*
X1621814Y370500D01*
X1621730Y370833D01*
X1621522Y371042D01*
X1621230Y371208D01*
X1620939Y371250D01*
X1620647Y371208D01*
X1620272Y371042D01*
X1620397Y372125D01*
X1621522D01*
G01X1596843Y362358D02*
X1596593Y362483D01*
X1596301Y362566D01*
X1595968D01*
X1595593Y362441D01*
X1595301Y362233D01*
X1595093Y361983D01*
X1594926Y361566D01*
X1594884Y361191D01*
X1594968Y360816D01*
X1595093Y360566D01*
X1595343Y360316D01*
X1595634Y360149D01*
X1595926Y360066D01*
X1596218D01*
X1596509Y360149D01*
X1596759Y360274D01*
X1596968Y360441D01*
G01X1599026Y360066D02*
X1599318Y360108D01*
X1599651Y360233D01*
X1599859Y360441D01*
X1599943Y360733D01*
X1599859Y361024D01*
X1599609Y361274D01*
X1599234Y361399D01*
X1598818D01*
X1598568Y361483D01*
X1598359Y361691D01*
X1598276Y361983D01*
X1598401Y362274D01*
X1598693Y362483D01*
X1599026Y362566D01*
X1599359Y362483D01*
X1599651Y362274D01*
X1599776Y361983D01*
X1599693Y361691D01*
X1599484Y361483D01*
X1599234Y361399D01*
X1598818D01*
X1598443Y361274D01*
X1598193Y361024D01*
X1598109Y360733D01*
X1598193Y360441D01*
X1598401Y360233D01*
X1598734Y360108D01*
X1599026Y360066D01*
G01X1603043Y362358D02*
X1602793Y362483D01*
X1602501Y362566D01*
X1602168D01*
X1601793Y362441D01*
X1601501Y362233D01*
X1601293Y361983D01*
X1601126Y361566D01*
X1601084Y361191D01*
X1601168Y360816D01*
X1601293Y360566D01*
X1601543Y360316D01*
X1601834Y360149D01*
X1602126Y360066D01*
X1602418D01*
X1602709Y360149D01*
X1602959Y360274D01*
X1603168Y360441D01*
G01X1604434Y361108D02*
X1604726Y361399D01*
X1604976Y361566D01*
X1605309Y361649D01*
X1605601Y361566D01*
X1605809Y361399D01*
X1605976Y361149D01*
X1606018Y360858D01*
X1605976Y360608D01*
X1605809Y360358D01*
X1605559Y360149D01*
X1605268Y360066D01*
X1604934Y360149D01*
X1604643Y360399D01*
X1604476Y360774D01*
X1604434Y361191D01*
X1604518Y361733D01*
X1604643Y362024D01*
X1604851Y362316D01*
X1605143Y362524D01*
X1605434Y362566D01*
X1605726Y362483D01*
X1605934Y362274D01*
G01X1598830Y382610D02*
Y383735D01*
X1597997Y385110D01*
G01X1599663D02*
X1598830Y383735D01*
G01X1601930Y382610D02*
X1602222Y382652D01*
X1602555Y382777D01*
X1602763Y382985D01*
X1602847Y383277D01*
X1602763Y383568D01*
X1602513Y383818D01*
X1602138Y383943D01*
X1601722D01*
X1601472Y384027D01*
X1601263Y384235D01*
X1601180Y384527D01*
X1601305Y384818D01*
X1601597Y385027D01*
X1601930Y385110D01*
X1602263Y385027D01*
X1602555Y384818D01*
X1602680Y384527D01*
X1602597Y384235D01*
X1602388Y384027D01*
X1602138Y383943D01*
X1601722D01*
X1601347Y383818D01*
X1601097Y383568D01*
X1601013Y383277D01*
X1601097Y382985D01*
X1601305Y382777D01*
X1601638Y382652D01*
X1601930Y382610D01*
G01X1605947Y384902D02*
X1605697Y385027D01*
X1605405Y385110D01*
X1605072D01*
X1604697Y384985D01*
X1604405Y384777D01*
X1604197Y384527D01*
X1604030Y384110D01*
X1603988Y383735D01*
X1604072Y383360D01*
X1604197Y383110D01*
X1604447Y382860D01*
X1604738Y382693D01*
X1605030Y382610D01*
X1605322D01*
X1605613Y382693D01*
X1605863Y382818D01*
X1606072Y382985D01*
G01X1608130Y382610D02*
Y385110D01*
X1607630Y384610D01*
G01Y382610D02*
X1608630D01*
G01X1644165Y371824D02*
X1643915Y371949D01*
X1643623Y372032D01*
X1643290D01*
X1642915Y371907D01*
X1642623Y371699D01*
X1642415Y371449D01*
X1642248Y371032D01*
X1642206Y370657D01*
X1642290Y370282D01*
X1642415Y370032D01*
X1642665Y369782D01*
X1642956Y369615D01*
X1643248Y369532D01*
X1643540D01*
X1643831Y369615D01*
X1644081Y369740D01*
X1644290Y369907D01*
G01X1646348Y369532D02*
X1646640Y369574D01*
X1646973Y369699D01*
X1647181Y369907D01*
X1647265Y370199D01*
X1647181Y370490D01*
X1646931Y370740D01*
X1646556Y370865D01*
X1646140D01*
X1645890Y370949D01*
X1645681Y371157D01*
X1645598Y371449D01*
X1645723Y371740D01*
X1646015Y371949D01*
X1646348Y372032D01*
X1646681Y371949D01*
X1646973Y371740D01*
X1647098Y371449D01*
X1647015Y371157D01*
X1646806Y370949D01*
X1646556Y370865D01*
X1646140D01*
X1645765Y370740D01*
X1645515Y370490D01*
X1645431Y370199D01*
X1645515Y369907D01*
X1645723Y369699D01*
X1646056Y369574D01*
X1646348Y369532D01*
G01X1650365Y371824D02*
X1650115Y371949D01*
X1649823Y372032D01*
X1649490D01*
X1649115Y371907D01*
X1648823Y371699D01*
X1648615Y371449D01*
X1648448Y371032D01*
X1648406Y370657D01*
X1648490Y370282D01*
X1648615Y370032D01*
X1648865Y369782D01*
X1649156Y369615D01*
X1649448Y369532D01*
X1649740D01*
X1650031Y369615D01*
X1650281Y369740D01*
X1650490Y369907D01*
G01X1652548Y369532D02*
Y372032D01*
X1652048Y371532D01*
G01Y369532D02*
X1653048D01*
G01X1654731Y369907D02*
X1654981Y369699D01*
X1655273Y369574D01*
X1655648Y369532D01*
X1656023Y369615D01*
X1656315Y369782D01*
X1656523Y370074D01*
X1656565Y370407D01*
X1656481Y370740D01*
X1656273Y370949D01*
X1655981Y371115D01*
X1655690Y371157D01*
X1655398Y371115D01*
X1655023Y370949D01*
X1655148Y372032D01*
X1656273D01*
G01X1644165Y375324D02*
X1643915Y375449D01*
X1643623Y375532D01*
X1643290D01*
X1642915Y375407D01*
X1642623Y375199D01*
X1642415Y374949D01*
X1642248Y374532D01*
X1642206Y374157D01*
X1642290Y373782D01*
X1642415Y373532D01*
X1642665Y373282D01*
X1642956Y373115D01*
X1643248Y373032D01*
X1643540D01*
X1643831Y373115D01*
X1644081Y373240D01*
X1644290Y373407D01*
G01X1646348Y373032D02*
X1646640Y373074D01*
X1646973Y373199D01*
X1647181Y373407D01*
X1647265Y373699D01*
X1647181Y373990D01*
X1646931Y374240D01*
X1646556Y374365D01*
X1646140D01*
X1645890Y374449D01*
X1645681Y374657D01*
X1645598Y374949D01*
X1645723Y375240D01*
X1646015Y375449D01*
X1646348Y375532D01*
X1646681Y375449D01*
X1646973Y375240D01*
X1647098Y374949D01*
X1647015Y374657D01*
X1646806Y374449D01*
X1646556Y374365D01*
X1646140D01*
X1645765Y374240D01*
X1645515Y373990D01*
X1645431Y373699D01*
X1645515Y373407D01*
X1645723Y373199D01*
X1646056Y373074D01*
X1646348Y373032D01*
G01X1650365Y375324D02*
X1650115Y375449D01*
X1649823Y375532D01*
X1649490D01*
X1649115Y375407D01*
X1648823Y375199D01*
X1648615Y374949D01*
X1648448Y374532D01*
X1648406Y374157D01*
X1648490Y373782D01*
X1648615Y373532D01*
X1648865Y373282D01*
X1649156Y373115D01*
X1649448Y373032D01*
X1649740D01*
X1650031Y373115D01*
X1650281Y373240D01*
X1650490Y373407D01*
G01X1652548Y373032D02*
Y375532D01*
X1652048Y375032D01*
G01Y373032D02*
X1653048D01*
G01X1656148D02*
Y375532D01*
X1654606Y373740D01*
X1656690D01*
G01X1589248Y377817D02*
X1589123Y377567D01*
X1589040Y377275D01*
Y376942D01*
X1589165Y376567D01*
X1589373Y376275D01*
X1589623Y376067D01*
X1590040Y375900D01*
X1590415Y375858D01*
X1590790Y375942D01*
X1591040Y376067D01*
X1591290Y376317D01*
X1591457Y376608D01*
X1591540Y376900D01*
Y377192D01*
X1591457Y377483D01*
X1591332Y377733D01*
X1591165Y377942D01*
G01X1591540Y380000D02*
X1591498Y380292D01*
X1591373Y380625D01*
X1591165Y380833D01*
X1590873Y380917D01*
X1590582Y380833D01*
X1590332Y380583D01*
X1590207Y380208D01*
Y379792D01*
X1590123Y379542D01*
X1589915Y379333D01*
X1589623Y379250D01*
X1589332Y379375D01*
X1589123Y379667D01*
X1589040Y380000D01*
X1589123Y380333D01*
X1589332Y380625D01*
X1589623Y380750D01*
X1589915Y380667D01*
X1590123Y380458D01*
X1590207Y380208D01*
Y379792D01*
X1590332Y379417D01*
X1590582Y379167D01*
X1590873Y379083D01*
X1591165Y379167D01*
X1591373Y379375D01*
X1591498Y379708D01*
X1591540Y380000D01*
G01X1589248Y384017D02*
X1589123Y383767D01*
X1589040Y383475D01*
Y383142D01*
X1589165Y382767D01*
X1589373Y382475D01*
X1589623Y382267D01*
X1590040Y382100D01*
X1590415Y382058D01*
X1590790Y382142D01*
X1591040Y382267D01*
X1591290Y382517D01*
X1591457Y382808D01*
X1591540Y383100D01*
Y383392D01*
X1591457Y383683D01*
X1591332Y383933D01*
X1591165Y384142D01*
G01X1589457Y385408D02*
X1589207Y385658D01*
X1589082Y385950D01*
X1589040Y386283D01*
X1589123Y386700D01*
X1589332Y386992D01*
X1589582Y387075D01*
X1589832Y387033D01*
X1590040Y386867D01*
X1590457Y386033D01*
X1590748Y385658D01*
X1591165Y385408D01*
X1591540Y385325D01*
Y387075D01*
G01X1614667Y380492D02*
X1614417Y380617D01*
X1614125Y380700D01*
X1613792D01*
X1613417Y380575D01*
X1613125Y380367D01*
X1612917Y380117D01*
X1612750Y379700D01*
X1612708Y379325D01*
X1612792Y378950D01*
X1612917Y378700D01*
X1613167Y378450D01*
X1613458Y378283D01*
X1613750Y378200D01*
X1614042D01*
X1614333Y378283D01*
X1614583Y378408D01*
X1614792Y378575D01*
G01X1616850Y378200D02*
X1617142Y378242D01*
X1617475Y378367D01*
X1617683Y378575D01*
X1617767Y378867D01*
X1617683Y379158D01*
X1617433Y379408D01*
X1617058Y379533D01*
X1616642D01*
X1616392Y379617D01*
X1616183Y379825D01*
X1616100Y380117D01*
X1616225Y380408D01*
X1616517Y380617D01*
X1616850Y380700D01*
X1617183Y380617D01*
X1617475Y380408D01*
X1617600Y380117D01*
X1617517Y379825D01*
X1617308Y379617D01*
X1617058Y379533D01*
X1616642D01*
X1616267Y379408D01*
X1616017Y379158D01*
X1615933Y378867D01*
X1616017Y378575D01*
X1616225Y378367D01*
X1616558Y378242D01*
X1616850Y378200D01*
G01X1620867Y380492D02*
X1620617Y380617D01*
X1620325Y380700D01*
X1619992D01*
X1619617Y380575D01*
X1619325Y380367D01*
X1619117Y380117D01*
X1618950Y379700D01*
X1618908Y379325D01*
X1618992Y378950D01*
X1619117Y378700D01*
X1619367Y378450D01*
X1619658Y378283D01*
X1619950Y378200D01*
X1620242D01*
X1620533Y378283D01*
X1620783Y378408D01*
X1620992Y378575D01*
G01X1623050Y378200D02*
Y380700D01*
X1622550Y380200D01*
G01Y378200D02*
X1623550D01*
G01X1625358Y380283D02*
X1625608Y380533D01*
X1625900Y380658D01*
X1626233Y380700D01*
X1626650Y380617D01*
X1626942Y380408D01*
X1627025Y380158D01*
X1626983Y379908D01*
X1626817Y379700D01*
X1625983Y379283D01*
X1625608Y378992D01*
X1625358Y378575D01*
X1625275Y378200D01*
X1627025D01*
G01X1614667Y376992D02*
X1614417Y377117D01*
X1614125Y377200D01*
X1613792D01*
X1613417Y377075D01*
X1613125Y376867D01*
X1612917Y376617D01*
X1612750Y376200D01*
X1612708Y375825D01*
X1612792Y375450D01*
X1612917Y375200D01*
X1613167Y374950D01*
X1613458Y374783D01*
X1613750Y374700D01*
X1614042D01*
X1614333Y374783D01*
X1614583Y374908D01*
X1614792Y375075D01*
G01X1616850Y374700D02*
X1617142Y374742D01*
X1617475Y374867D01*
X1617683Y375075D01*
X1617767Y375367D01*
X1617683Y375658D01*
X1617433Y375908D01*
X1617058Y376033D01*
X1616642D01*
X1616392Y376117D01*
X1616183Y376325D01*
X1616100Y376617D01*
X1616225Y376908D01*
X1616517Y377117D01*
X1616850Y377200D01*
X1617183Y377117D01*
X1617475Y376908D01*
X1617600Y376617D01*
X1617517Y376325D01*
X1617308Y376117D01*
X1617058Y376033D01*
X1616642D01*
X1616267Y375908D01*
X1616017Y375658D01*
X1615933Y375367D01*
X1616017Y375075D01*
X1616225Y374867D01*
X1616558Y374742D01*
X1616850Y374700D01*
G01X1620867Y376992D02*
X1620617Y377117D01*
X1620325Y377200D01*
X1619992D01*
X1619617Y377075D01*
X1619325Y376867D01*
X1619117Y376617D01*
X1618950Y376200D01*
X1618908Y375825D01*
X1618992Y375450D01*
X1619117Y375200D01*
X1619367Y374950D01*
X1619658Y374783D01*
X1619950Y374700D01*
X1620242D01*
X1620533Y374783D01*
X1620783Y374908D01*
X1620992Y375075D01*
G01X1623050Y374700D02*
Y377200D01*
X1622550Y376700D01*
G01Y374700D02*
X1623550D01*
G01X1625233Y375200D02*
X1625483Y374908D01*
X1625817Y374742D01*
X1626192Y374700D01*
X1626525Y374742D01*
X1626858Y374950D01*
X1627067Y375200D01*
X1627108Y375450D01*
X1627025Y375742D01*
X1626733Y375950D01*
X1626442Y376033D01*
X1626067D01*
G01X1626442D02*
X1626692Y376158D01*
X1626900Y376367D01*
X1626983Y376617D01*
X1626900Y376867D01*
X1626692Y377075D01*
X1626317Y377200D01*
X1625942Y377158D01*
X1625567Y376992D01*
G01X1639042Y350331D02*
X1639688D01*
Y348704D01*
G01Y343498D02*
Y342798D01*
G01X1625318D02*
Y343498D01*
G01Y348704D02*
Y350331D01*
X1625967D01*
G01X1628900Y429500D02*
Y437200D01*
X1620900D01*
Y438400D01*
G01X1612900Y425100D02*
Y433800D01*
G01Y417700D02*
Y414100D01*
X1622600D01*
Y429500D01*
X1628900D01*
G01X1612900Y437100D02*
Y448400D01*
X1603700D01*
Y449500D01*
G01X1620900Y454000D02*
Y461900D01*
X1612900D01*
G01X1620900Y442000D02*
Y443400D01*
G01X1610300Y461900D02*
X1605900D01*
Y467000D01*
X1603100D01*
G01X1627317Y459200D02*
Y461700D01*
X1628358D01*
X1628692Y461575D01*
X1628900Y461408D01*
X1628983Y461075D01*
X1628900Y460742D01*
X1628650Y460533D01*
X1628358Y460408D01*
X1627317D01*
G01X1628358D02*
X1628983Y459200D01*
G01X1630458Y461283D02*
X1630708Y461533D01*
X1631000Y461658D01*
X1631333Y461700D01*
X1631750Y461617D01*
X1632042Y461408D01*
X1632125Y461158D01*
X1632083Y460908D01*
X1631917Y460700D01*
X1631083Y460283D01*
X1630708Y459992D01*
X1630458Y459575D01*
X1630375Y459200D01*
X1632125D01*
G01X1633517Y461700D02*
Y459200D01*
X1635183D01*
G01X1637950D02*
Y461700D01*
X1636408Y459908D01*
X1638492D01*
G01X1641837Y465160D02*
Y467660D01*
X1642878D01*
X1643212Y467535D01*
X1643420Y467368D01*
X1643503Y467035D01*
X1643420Y466702D01*
X1643170Y466493D01*
X1642878Y466368D01*
X1641837D01*
G01X1642878D02*
X1643503Y465160D01*
G01X1645770D02*
X1646062Y465202D01*
X1646395Y465327D01*
X1646603Y465535D01*
X1646687Y465827D01*
X1646603Y466118D01*
X1646353Y466368D01*
X1645978Y466493D01*
X1645562D01*
X1645312Y466577D01*
X1645103Y466785D01*
X1645020Y467077D01*
X1645145Y467368D01*
X1645437Y467577D01*
X1645770Y467660D01*
X1646103Y467577D01*
X1646395Y467368D01*
X1646520Y467077D01*
X1646437Y466785D01*
X1646228Y466577D01*
X1645978Y466493D01*
X1645562D01*
X1645187Y466368D01*
X1644937Y466118D01*
X1644853Y465827D01*
X1644937Y465535D01*
X1645145Y465327D01*
X1645478Y465202D01*
X1645770Y465160D01*
G01X1649703D02*
X1648037D01*
Y467660D01*
X1649703D01*
G01X1649037Y466452D02*
X1648037D01*
G01X1651970Y465160D02*
Y467660D01*
X1651470Y467160D01*
G01Y465160D02*
X1652470D01*
G01X1655070D02*
Y467660D01*
X1654570Y467160D01*
G01Y465160D02*
X1655570D01*
G01X1643017Y461500D02*
Y464000D01*
X1644058D01*
X1644392Y463875D01*
X1644600Y463708D01*
X1644683Y463375D01*
X1644600Y463042D01*
X1644350Y462833D01*
X1644058Y462708D01*
X1643017D01*
G01X1644058D02*
X1644683Y461500D01*
G01X1646158Y463583D02*
X1646408Y463833D01*
X1646700Y463958D01*
X1647033Y464000D01*
X1647450Y463917D01*
X1647742Y463708D01*
X1647825Y463458D01*
X1647783Y463208D01*
X1647617Y463000D01*
X1646783Y462583D01*
X1646408Y462292D01*
X1646158Y461875D01*
X1646075Y461500D01*
X1647825D01*
G01X1648967D02*
Y464000D01*
X1650050Y461917D01*
X1651133Y464000D01*
Y461500D01*
G01X1652358Y463583D02*
X1652608Y463833D01*
X1652900Y463958D01*
X1653233Y464000D01*
X1653650Y463917D01*
X1653942Y463708D01*
X1654025Y463458D01*
X1653983Y463208D01*
X1653817Y463000D01*
X1652983Y462583D01*
X1652608Y462292D01*
X1652358Y461875D01*
X1652275Y461500D01*
X1654025D01*
G01X1612547Y464590D02*
Y467090D01*
X1613588D01*
X1613922Y466965D01*
X1614130Y466798D01*
X1614213Y466465D01*
X1614130Y466132D01*
X1613880Y465923D01*
X1613588Y465798D01*
X1612547D01*
G01X1613588D02*
X1614213Y464590D01*
G01X1616480D02*
X1616772Y464632D01*
X1617105Y464757D01*
X1617313Y464965D01*
X1617397Y465257D01*
X1617313Y465548D01*
X1617063Y465798D01*
X1616688Y465923D01*
X1616272D01*
X1616022Y466007D01*
X1615813Y466215D01*
X1615730Y466507D01*
X1615855Y466798D01*
X1616147Y467007D01*
X1616480Y467090D01*
X1616813Y467007D01*
X1617105Y466798D01*
X1617230Y466507D01*
X1617147Y466215D01*
X1616938Y466007D01*
X1616688Y465923D01*
X1616272D01*
X1615897Y465798D01*
X1615647Y465548D01*
X1615563Y465257D01*
X1615647Y464965D01*
X1615855Y464757D01*
X1616188Y464632D01*
X1616480Y464590D01*
G01X1619913Y465923D02*
X1620080Y466048D01*
X1620205Y466257D01*
X1620288Y466548D01*
X1620205Y466798D01*
X1620038Y466965D01*
X1619747Y467090D01*
X1618622D01*
Y464590D01*
X1619997D01*
X1620288Y464757D01*
X1620455Y465007D01*
X1620538Y465298D01*
X1620455Y465590D01*
X1620205Y465840D01*
X1619913Y465923D01*
X1618622D01*
G01X1621888Y466673D02*
X1622138Y466923D01*
X1622430Y467048D01*
X1622763Y467090D01*
X1623180Y467007D01*
X1623472Y466798D01*
X1623555Y466548D01*
X1623513Y466298D01*
X1623347Y466090D01*
X1622513Y465673D01*
X1622138Y465382D01*
X1621888Y464965D01*
X1621805Y464590D01*
X1623555D01*
G01X1625780D02*
Y467090D01*
X1625280Y466590D01*
G01Y464590D02*
X1626280D01*
G01X1627317Y455700D02*
Y458200D01*
X1628358D01*
X1628692Y458075D01*
X1628900Y457908D01*
X1628983Y457575D01*
X1628900Y457242D01*
X1628650Y457033D01*
X1628358Y456908D01*
X1627317D01*
G01X1628358D02*
X1628983Y455700D01*
G01X1630458Y457783D02*
X1630708Y458033D01*
X1631000Y458158D01*
X1631333Y458200D01*
X1631750Y458117D01*
X1632042Y457908D01*
X1632125Y457658D01*
X1632083Y457408D01*
X1631917Y457200D01*
X1631083Y456783D01*
X1630708Y456492D01*
X1630458Y456075D01*
X1630375Y455700D01*
X1632125D01*
G01X1634350Y458200D02*
Y455700D01*
G01X1633392Y458200D02*
X1635308D01*
G01X1636658Y457783D02*
X1636908Y458033D01*
X1637200Y458158D01*
X1637533Y458200D01*
X1637950Y458117D01*
X1638242Y457908D01*
X1638325Y457658D01*
X1638283Y457408D01*
X1638117Y457200D01*
X1637283Y456783D01*
X1636908Y456492D01*
X1636658Y456075D01*
X1636575Y455700D01*
X1638325D01*
G01X1639842Y455992D02*
X1640133Y455783D01*
X1640467Y455700D01*
X1640800Y455783D01*
X1641092Y456033D01*
X1641300Y456408D01*
X1641383Y456783D01*
Y457242D01*
X1641300Y457617D01*
X1641092Y457950D01*
X1640842Y458117D01*
X1640550Y458200D01*
X1640217Y458117D01*
X1639967Y457950D01*
X1639800Y457700D01*
X1639717Y457367D01*
X1639800Y457075D01*
X1640008Y456783D01*
X1640258Y456617D01*
X1640550Y456575D01*
X1640883Y456658D01*
X1641133Y456867D01*
X1641383Y457242D01*
G01X1643017Y458000D02*
Y460500D01*
X1644058D01*
X1644392Y460375D01*
X1644600Y460208D01*
X1644683Y459875D01*
X1644600Y459542D01*
X1644350Y459333D01*
X1644058Y459208D01*
X1643017D01*
G01X1644058D02*
X1644683Y458000D01*
G01X1646158Y460083D02*
X1646408Y460333D01*
X1646700Y460458D01*
X1647033Y460500D01*
X1647450Y460417D01*
X1647742Y460208D01*
X1647825Y459958D01*
X1647783Y459708D01*
X1647617Y459500D01*
X1646783Y459083D01*
X1646408Y458792D01*
X1646158Y458375D01*
X1646075Y458000D01*
X1647825D01*
G01X1648967D02*
Y460500D01*
X1650050Y458417D01*
X1651133Y460500D01*
Y458000D01*
G01X1653650D02*
Y460500D01*
X1652108Y458708D01*
X1654192D01*
G01X1647643Y432712D02*
X1645143D01*
Y433753D01*
X1645268Y434087D01*
X1645435Y434295D01*
X1645768Y434378D01*
X1646101Y434295D01*
X1646310Y434045D01*
X1646435Y433753D01*
Y432712D01*
G01Y433753D02*
X1647643Y434378D01*
G01X1645560Y435853D02*
X1645310Y436103D01*
X1645185Y436395D01*
X1645143Y436728D01*
X1645226Y437145D01*
X1645435Y437437D01*
X1645685Y437520D01*
X1645935Y437478D01*
X1646143Y437312D01*
X1646560Y436478D01*
X1646851Y436103D01*
X1647268Y435853D01*
X1647643Y435770D01*
Y437520D01*
G01Y438787D02*
X1645143D01*
X1647643Y440703D01*
X1645143D01*
G01X1647643Y442845D02*
X1645143D01*
X1645643Y442345D01*
G01X1647643D02*
Y443345D01*
G01X1633500Y404627D02*
X1631000D01*
Y405668D01*
X1631125Y406002D01*
X1631292Y406210D01*
X1631625Y406293D01*
X1631958Y406210D01*
X1632167Y405960D01*
X1632292Y405668D01*
Y404627D01*
G01Y405668D02*
X1633500Y406293D01*
G01X1631417Y407768D02*
X1631167Y408018D01*
X1631042Y408310D01*
X1631000Y408643D01*
X1631083Y409060D01*
X1631292Y409352D01*
X1631542Y409435D01*
X1631792Y409393D01*
X1632000Y409227D01*
X1632417Y408393D01*
X1632708Y408018D01*
X1633125Y407768D01*
X1633500Y407685D01*
Y409435D01*
G01Y410702D02*
X1631000D01*
X1633500Y412618D01*
X1631000D01*
G01X1632458Y413968D02*
X1632167Y414260D01*
X1632000Y414510D01*
X1631917Y414843D01*
X1632000Y415135D01*
X1632167Y415343D01*
X1632417Y415510D01*
X1632708Y415552D01*
X1632958Y415510D01*
X1633208Y415343D01*
X1633417Y415093D01*
X1633500Y414802D01*
X1633417Y414468D01*
X1633167Y414177D01*
X1632792Y414010D01*
X1632375Y413968D01*
X1631833Y414052D01*
X1631542Y414177D01*
X1631250Y414385D01*
X1631042Y414677D01*
X1631000Y414968D01*
X1631083Y415260D01*
X1631292Y415468D01*
G01X1594500Y403667D02*
X1592000D01*
Y404708D01*
X1592125Y405042D01*
X1592292Y405250D01*
X1592625Y405333D01*
X1592958Y405250D01*
X1593167Y405000D01*
X1593292Y404708D01*
Y403667D01*
G01Y404708D02*
X1594500Y405333D01*
G01Y407600D02*
X1594458Y407892D01*
X1594333Y408225D01*
X1594125Y408433D01*
X1593833Y408517D01*
X1593542Y408433D01*
X1593292Y408183D01*
X1593167Y407808D01*
Y407392D01*
X1593083Y407142D01*
X1592875Y406933D01*
X1592583Y406850D01*
X1592292Y406975D01*
X1592083Y407267D01*
X1592000Y407600D01*
X1592083Y407933D01*
X1592292Y408225D01*
X1592583Y408350D01*
X1592875Y408267D01*
X1593083Y408058D01*
X1593167Y407808D01*
Y407392D01*
X1593292Y407017D01*
X1593542Y406767D01*
X1593833Y406683D01*
X1594125Y406767D01*
X1594333Y406975D01*
X1594458Y407308D01*
X1594500Y407600D01*
G01X1592208Y411617D02*
X1592083Y411367D01*
X1592000Y411075D01*
Y410742D01*
X1592125Y410367D01*
X1592333Y410075D01*
X1592583Y409867D01*
X1593000Y409700D01*
X1593375Y409658D01*
X1593750Y409742D01*
X1594000Y409867D01*
X1594250Y410117D01*
X1594417Y410408D01*
X1594500Y410700D01*
Y410992D01*
X1594417Y411283D01*
X1594292Y411533D01*
X1594125Y411742D01*
G01X1592417Y413008D02*
X1592167Y413258D01*
X1592042Y413550D01*
X1592000Y413883D01*
X1592083Y414300D01*
X1592292Y414592D01*
X1592542Y414675D01*
X1592792Y414633D01*
X1593000Y414467D01*
X1593417Y413633D01*
X1593708Y413258D01*
X1594125Y413008D01*
X1594500Y412925D01*
Y414675D01*
G01Y416900D02*
X1592000D01*
X1592500Y416400D01*
G01X1594500D02*
Y417400D01*
G01X1592967Y418100D02*
Y420600D01*
X1594008D01*
X1594342Y420475D01*
X1594550Y420308D01*
X1594633Y419975D01*
X1594550Y419642D01*
X1594300Y419433D01*
X1594008Y419308D01*
X1592967D01*
G01X1594008D02*
X1594633Y418100D01*
G01X1596108Y420183D02*
X1596358Y420433D01*
X1596650Y420558D01*
X1596983Y420600D01*
X1597400Y420517D01*
X1597692Y420308D01*
X1597775Y420058D01*
X1597733Y419808D01*
X1597567Y419600D01*
X1596733Y419183D01*
X1596358Y418892D01*
X1596108Y418475D01*
X1596025Y418100D01*
X1597775D01*
G01X1599167D02*
Y420600D01*
X1600167D01*
X1600500Y420475D01*
X1600750Y420183D01*
X1600833Y419850D01*
X1600750Y419517D01*
X1600542Y419267D01*
X1600167Y419142D01*
X1599167D01*
G01X1602308Y420183D02*
X1602558Y420433D01*
X1602850Y420558D01*
X1603183Y420600D01*
X1603600Y420517D01*
X1603892Y420308D01*
X1603975Y420058D01*
X1603933Y419808D01*
X1603767Y419600D01*
X1602933Y419183D01*
X1602558Y418892D01*
X1602308Y418475D01*
X1602225Y418100D01*
X1603975D01*
G01X1605408Y420183D02*
X1605658Y420433D01*
X1605950Y420558D01*
X1606283Y420600D01*
X1606700Y420517D01*
X1606992Y420308D01*
X1607075Y420058D01*
X1607033Y419808D01*
X1606867Y419600D01*
X1606033Y419183D01*
X1605658Y418892D01*
X1605408Y418475D01*
X1605325Y418100D01*
X1607075D01*
G01X1624367Y421500D02*
Y424000D01*
X1625408D01*
X1625742Y423875D01*
X1625950Y423708D01*
X1626033Y423375D01*
X1625950Y423042D01*
X1625700Y422833D01*
X1625408Y422708D01*
X1624367D01*
G01X1625408D02*
X1626033Y421500D01*
G01X1628300D02*
X1628592Y421542D01*
X1628925Y421667D01*
X1629133Y421875D01*
X1629217Y422167D01*
X1629133Y422458D01*
X1628883Y422708D01*
X1628508Y422833D01*
X1628092D01*
X1627842Y422917D01*
X1627633Y423125D01*
X1627550Y423417D01*
X1627675Y423708D01*
X1627967Y423917D01*
X1628300Y424000D01*
X1628633Y423917D01*
X1628925Y423708D01*
X1629050Y423417D01*
X1628967Y423125D01*
X1628758Y422917D01*
X1628508Y422833D01*
X1628092D01*
X1627717Y422708D01*
X1627467Y422458D01*
X1627383Y422167D01*
X1627467Y421875D01*
X1627675Y421667D01*
X1628008Y421542D01*
X1628300Y421500D01*
G01X1632317Y423792D02*
X1632067Y423917D01*
X1631775Y424000D01*
X1631442D01*
X1631067Y423875D01*
X1630775Y423667D01*
X1630567Y423417D01*
X1630400Y423000D01*
X1630358Y422625D01*
X1630442Y422250D01*
X1630567Y422000D01*
X1630817Y421750D01*
X1631108Y421583D01*
X1631400Y421500D01*
X1631692D01*
X1631983Y421583D01*
X1632233Y421708D01*
X1632442Y421875D01*
G01X1634500Y421500D02*
Y424000D01*
X1634000Y423500D01*
G01Y421500D02*
X1635000D01*
G01X1637517D02*
X1637600Y422042D01*
X1637725Y422500D01*
X1637892Y422917D01*
X1638100Y423375D01*
X1638433Y424000D01*
X1636767D01*
G01X1627037Y417200D02*
Y419700D01*
X1628078D01*
X1628412Y419575D01*
X1628620Y419408D01*
X1628703Y419075D01*
X1628620Y418742D01*
X1628370Y418533D01*
X1628078Y418408D01*
X1627037D01*
G01X1628078D02*
X1628703Y417200D01*
G01X1630178Y419283D02*
X1630428Y419533D01*
X1630720Y419658D01*
X1631053Y419700D01*
X1631470Y419617D01*
X1631762Y419408D01*
X1631845Y419158D01*
X1631803Y418908D01*
X1631637Y418700D01*
X1630803Y418283D01*
X1630428Y417992D01*
X1630178Y417575D01*
X1630095Y417200D01*
X1631845D01*
G01X1633112D02*
Y419700D01*
X1635028Y417200D01*
Y419700D01*
G01X1637087Y417200D02*
X1637170Y417742D01*
X1637295Y418200D01*
X1637462Y418617D01*
X1637670Y419075D01*
X1638003Y419700D01*
X1636337D01*
G01X1645108Y410877D02*
X1644983Y410627D01*
X1644900Y410335D01*
Y410002D01*
X1645025Y409627D01*
X1645233Y409335D01*
X1645483Y409127D01*
X1645900Y408960D01*
X1646275Y408918D01*
X1646650Y409002D01*
X1646900Y409127D01*
X1647150Y409377D01*
X1647317Y409668D01*
X1647400Y409960D01*
Y410252D01*
X1647317Y410543D01*
X1647192Y410793D01*
X1647025Y411002D01*
G01X1647108Y412352D02*
X1647317Y412643D01*
X1647400Y412977D01*
X1647317Y413310D01*
X1647067Y413602D01*
X1646692Y413810D01*
X1646317Y413893D01*
X1645858D01*
X1645483Y413810D01*
X1645150Y413602D01*
X1644983Y413352D01*
X1644900Y413060D01*
X1644983Y412727D01*
X1645150Y412477D01*
X1645400Y412310D01*
X1645733Y412227D01*
X1646025Y412310D01*
X1646317Y412518D01*
X1646483Y412768D01*
X1646525Y413060D01*
X1646442Y413393D01*
X1646233Y413643D01*
X1645858Y413893D01*
G01X1644900Y414910D02*
X1647400Y415493D01*
X1644900Y416160D01*
X1647400Y416827D01*
X1644900Y417410D01*
G01X1647400Y419260D02*
X1647358Y419552D01*
X1647233Y419885D01*
X1647025Y420093D01*
X1646733Y420177D01*
X1646442Y420093D01*
X1646192Y419843D01*
X1646067Y419468D01*
Y419052D01*
X1645983Y418802D01*
X1645775Y418593D01*
X1645483Y418510D01*
X1645192Y418635D01*
X1644983Y418927D01*
X1644900Y419260D01*
X1644983Y419593D01*
X1645192Y419885D01*
X1645483Y420010D01*
X1645775Y419927D01*
X1645983Y419718D01*
X1646067Y419468D01*
Y419052D01*
X1646192Y418677D01*
X1646442Y418427D01*
X1646733Y418343D01*
X1647025Y418427D01*
X1647233Y418635D01*
X1647358Y418968D01*
X1647400Y419260D01*
G01X1648300Y431560D02*
X1650300Y429560D01*
X1648300Y427560D01*
G01X1660250Y425410D02*
Y433410D01*
X1648300D01*
Y425410D01*
X1660250D01*
G01X1621747Y472160D02*
Y474660D01*
X1622788D01*
X1623122Y474535D01*
X1623330Y474368D01*
X1623413Y474035D01*
X1623330Y473702D01*
X1623080Y473493D01*
X1622788Y473368D01*
X1621747D01*
G01X1622788D02*
X1623413Y472160D01*
G01X1624888Y474243D02*
X1625138Y474493D01*
X1625430Y474618D01*
X1625763Y474660D01*
X1626180Y474577D01*
X1626472Y474368D01*
X1626555Y474118D01*
X1626513Y473868D01*
X1626347Y473660D01*
X1625513Y473243D01*
X1625138Y472952D01*
X1624888Y472535D01*
X1624805Y472160D01*
X1626555D01*
G01X1627697D02*
Y474660D01*
X1628780Y472577D01*
X1629863Y474660D01*
Y472160D01*
G01X1631880D02*
X1632172Y472202D01*
X1632505Y472327D01*
X1632713Y472535D01*
X1632797Y472827D01*
X1632713Y473118D01*
X1632463Y473368D01*
X1632088Y473493D01*
X1631672D01*
X1631422Y473577D01*
X1631213Y473785D01*
X1631130Y474077D01*
X1631255Y474368D01*
X1631547Y474577D01*
X1631880Y474660D01*
X1632213Y474577D01*
X1632505Y474368D01*
X1632630Y474077D01*
X1632547Y473785D01*
X1632338Y473577D01*
X1632088Y473493D01*
X1631672D01*
X1631297Y473368D01*
X1631047Y473118D01*
X1630963Y472827D01*
X1631047Y472535D01*
X1631255Y472327D01*
X1631588Y472202D01*
X1631880Y472160D01*
G01X1645717Y468700D02*
Y471200D01*
X1646758D01*
X1647092Y471075D01*
X1647300Y470908D01*
X1647383Y470575D01*
X1647300Y470242D01*
X1647050Y470033D01*
X1646758Y469908D01*
X1645717D01*
G01X1646758D02*
X1647383Y468700D01*
G01X1648858Y470783D02*
X1649108Y471033D01*
X1649400Y471158D01*
X1649733Y471200D01*
X1650150Y471117D01*
X1650442Y470908D01*
X1650525Y470658D01*
X1650483Y470408D01*
X1650317Y470200D01*
X1649483Y469783D01*
X1649108Y469492D01*
X1648858Y469075D01*
X1648775Y468700D01*
X1650525D01*
G01X1651667D02*
Y471200D01*
X1652750Y469117D01*
X1653833Y471200D01*
Y468700D01*
G01X1655850D02*
Y471200D01*
X1655350Y470700D01*
G01Y468700D02*
X1656350D01*
G01X1627700Y485667D02*
X1625200D01*
Y486708D01*
X1625325Y487042D01*
X1625492Y487250D01*
X1625825Y487333D01*
X1626158Y487250D01*
X1626367Y487000D01*
X1626492Y486708D01*
Y485667D01*
G01Y486708D02*
X1627700Y487333D01*
G01Y489600D02*
X1627658Y489892D01*
X1627533Y490225D01*
X1627325Y490433D01*
X1627033Y490517D01*
X1626742Y490433D01*
X1626492Y490183D01*
X1626367Y489808D01*
Y489392D01*
X1626283Y489142D01*
X1626075Y488933D01*
X1625783Y488850D01*
X1625492Y488975D01*
X1625283Y489267D01*
X1625200Y489600D01*
X1625283Y489933D01*
X1625492Y490225D01*
X1625783Y490350D01*
X1626075Y490267D01*
X1626283Y490058D01*
X1626367Y489808D01*
Y489392D01*
X1626492Y489017D01*
X1626742Y488767D01*
X1627033Y488683D01*
X1627325Y488767D01*
X1627533Y488975D01*
X1627658Y489308D01*
X1627700Y489600D01*
G01X1626367Y493033D02*
X1626242Y493200D01*
X1626033Y493325D01*
X1625742Y493408D01*
X1625492Y493325D01*
X1625325Y493158D01*
X1625200Y492867D01*
Y491742D01*
X1627700D01*
Y493117D01*
X1627533Y493408D01*
X1627283Y493575D01*
X1626992Y493658D01*
X1626700Y493575D01*
X1626450Y493325D01*
X1626367Y493033D01*
Y491742D01*
G01X1627700Y495800D02*
X1625200D01*
X1625700Y495300D01*
G01X1627700D02*
Y496300D01*
G01X1627325Y497983D02*
X1627533Y498233D01*
X1627658Y498525D01*
X1627700Y498900D01*
X1627617Y499275D01*
X1627450Y499567D01*
X1627158Y499775D01*
X1626825Y499817D01*
X1626492Y499733D01*
X1626283Y499525D01*
X1626117Y499233D01*
X1626075Y498942D01*
X1626117Y498650D01*
X1626283Y498275D01*
X1625200Y498400D01*
Y499525D01*
G01X1610567Y483367D02*
Y485867D01*
X1611608D01*
X1611942Y485742D01*
X1612150Y485575D01*
X1612233Y485242D01*
X1612150Y484909D01*
X1611900Y484700D01*
X1611608Y484575D01*
X1610567D01*
G01X1611608D02*
X1612233Y483367D01*
G01X1614500D02*
X1614792Y483409D01*
X1615125Y483534D01*
X1615333Y483742D01*
X1615417Y484034D01*
X1615333Y484325D01*
X1615083Y484575D01*
X1614708Y484700D01*
X1614292D01*
X1614042Y484784D01*
X1613833Y484992D01*
X1613750Y485284D01*
X1613875Y485575D01*
X1614167Y485784D01*
X1614500Y485867D01*
X1614833Y485784D01*
X1615125Y485575D01*
X1615250Y485284D01*
X1615167Y484992D01*
X1614958Y484784D01*
X1614708Y484700D01*
X1614292D01*
X1613917Y484575D01*
X1613667Y484325D01*
X1613583Y484034D01*
X1613667Y483742D01*
X1613875Y483534D01*
X1614208Y483409D01*
X1614500Y483367D01*
G01X1617933Y484700D02*
X1618100Y484825D01*
X1618225Y485034D01*
X1618308Y485325D01*
X1618225Y485575D01*
X1618058Y485742D01*
X1617767Y485867D01*
X1616642D01*
Y483367D01*
X1618017D01*
X1618308Y483534D01*
X1618475Y483784D01*
X1618558Y484075D01*
X1618475Y484367D01*
X1618225Y484617D01*
X1617933Y484700D01*
X1616642D01*
G01X1620700Y483367D02*
Y485867D01*
X1620200Y485367D01*
G01Y483367D02*
X1621200D01*
G01X1624300D02*
Y485867D01*
X1622758Y484075D01*
X1624842D01*
G01X1610483Y477508D02*
Y480008D01*
X1611524D01*
X1611858Y479883D01*
X1612066Y479716D01*
X1612149Y479383D01*
X1612066Y479050D01*
X1611816Y478841D01*
X1611524Y478716D01*
X1610483D01*
G01X1611524D02*
X1612149Y477508D01*
G01X1614416D02*
X1614708Y477550D01*
X1615041Y477675D01*
X1615249Y477883D01*
X1615333Y478175D01*
X1615249Y478466D01*
X1614999Y478716D01*
X1614624Y478841D01*
X1614208D01*
X1613958Y478925D01*
X1613749Y479133D01*
X1613666Y479425D01*
X1613791Y479716D01*
X1614083Y479925D01*
X1614416Y480008D01*
X1614749Y479925D01*
X1615041Y479716D01*
X1615166Y479425D01*
X1615083Y479133D01*
X1614874Y478925D01*
X1614624Y478841D01*
X1614208D01*
X1613833Y478716D01*
X1613583Y478466D01*
X1613499Y478175D01*
X1613583Y477883D01*
X1613791Y477675D01*
X1614124Y477550D01*
X1614416Y477508D01*
G01X1617849Y478841D02*
X1618016Y478966D01*
X1618141Y479175D01*
X1618224Y479466D01*
X1618141Y479716D01*
X1617974Y479883D01*
X1617683Y480008D01*
X1616558D01*
Y477508D01*
X1617933D01*
X1618224Y477675D01*
X1618391Y477925D01*
X1618474Y478216D01*
X1618391Y478508D01*
X1618141Y478758D01*
X1617849Y478841D01*
X1616558D01*
G01X1620616Y477508D02*
Y480008D01*
X1620116Y479508D01*
G01Y477508D02*
X1621116D01*
G01X1622924Y479591D02*
X1623174Y479841D01*
X1623466Y479966D01*
X1623799Y480008D01*
X1624216Y479925D01*
X1624508Y479716D01*
X1624591Y479466D01*
X1624549Y479216D01*
X1624383Y479008D01*
X1623549Y478591D01*
X1623174Y478300D01*
X1622924Y477883D01*
X1622841Y477508D01*
X1624591D01*
G01X1616156Y524283D02*
X1613656D01*
Y525324D01*
X1613781Y525658D01*
X1613948Y525866D01*
X1614281Y525949D01*
X1614614Y525866D01*
X1614823Y525616D01*
X1614948Y525324D01*
Y524283D01*
G01Y525324D02*
X1616156Y525949D01*
G01Y528216D02*
X1616114Y528508D01*
X1615989Y528841D01*
X1615781Y529049D01*
X1615489Y529133D01*
X1615198Y529049D01*
X1614948Y528799D01*
X1614823Y528424D01*
Y528008D01*
X1614739Y527758D01*
X1614531Y527549D01*
X1614239Y527466D01*
X1613948Y527591D01*
X1613739Y527883D01*
X1613656Y528216D01*
X1613739Y528549D01*
X1613948Y528841D01*
X1614239Y528966D01*
X1614531Y528883D01*
X1614739Y528674D01*
X1614823Y528424D01*
Y528008D01*
X1614948Y527633D01*
X1615198Y527383D01*
X1615489Y527299D01*
X1615781Y527383D01*
X1615989Y527591D01*
X1616114Y527924D01*
X1616156Y528216D01*
G01X1614823Y531649D02*
X1614698Y531816D01*
X1614489Y531941D01*
X1614198Y532024D01*
X1613948Y531941D01*
X1613781Y531774D01*
X1613656Y531483D01*
Y530358D01*
X1616156D01*
Y531733D01*
X1615989Y532024D01*
X1615739Y532191D01*
X1615448Y532274D01*
X1615156Y532191D01*
X1614906Y531941D01*
X1614823Y531649D01*
Y530358D01*
G01X1614073Y533624D02*
X1613823Y533874D01*
X1613698Y534166D01*
X1613656Y534499D01*
X1613739Y534916D01*
X1613948Y535208D01*
X1614198Y535291D01*
X1614448Y535249D01*
X1614656Y535083D01*
X1615073Y534249D01*
X1615364Y533874D01*
X1615781Y533624D01*
X1616156Y533541D01*
Y535291D01*
G01X1614129Y514570D02*
Y517070D01*
X1615170D01*
X1615504Y516945D01*
X1615712Y516778D01*
X1615795Y516445D01*
X1615712Y516112D01*
X1615462Y515903D01*
X1615170Y515778D01*
X1614129D01*
G01X1615170D02*
X1615795Y514570D01*
G01X1618062D02*
X1618354Y514612D01*
X1618687Y514737D01*
X1618895Y514945D01*
X1618979Y515237D01*
X1618895Y515528D01*
X1618645Y515778D01*
X1618270Y515903D01*
X1617854D01*
X1617604Y515987D01*
X1617395Y516195D01*
X1617312Y516487D01*
X1617437Y516778D01*
X1617729Y516987D01*
X1618062Y517070D01*
X1618395Y516987D01*
X1618687Y516778D01*
X1618812Y516487D01*
X1618729Y516195D01*
X1618520Y515987D01*
X1618270Y515903D01*
X1617854D01*
X1617479Y515778D01*
X1617229Y515528D01*
X1617145Y515237D01*
X1617229Y514945D01*
X1617437Y514737D01*
X1617770Y514612D01*
X1618062Y514570D01*
G01X1621495Y515903D02*
X1621662Y516028D01*
X1621787Y516237D01*
X1621870Y516528D01*
X1621787Y516778D01*
X1621620Y516945D01*
X1621329Y517070D01*
X1620204D01*
Y514570D01*
X1621579D01*
X1621870Y514737D01*
X1622037Y514987D01*
X1622120Y515278D01*
X1622037Y515570D01*
X1621787Y515820D01*
X1621495Y515903D01*
X1620204D01*
G01X1623345Y515070D02*
X1623595Y514778D01*
X1623929Y514612D01*
X1624304Y514570D01*
X1624637Y514612D01*
X1624970Y514820D01*
X1625179Y515070D01*
X1625220Y515320D01*
X1625137Y515612D01*
X1624845Y515820D01*
X1624554Y515903D01*
X1624179D01*
G01X1624554D02*
X1624804Y516028D01*
X1625012Y516237D01*
X1625095Y516487D01*
X1625012Y516737D01*
X1624804Y516945D01*
X1624429Y517070D01*
X1624054Y517028D01*
X1623679Y516862D01*
G01X1614165Y511009D02*
Y513509D01*
X1615206D01*
X1615540Y513384D01*
X1615748Y513217D01*
X1615831Y512884D01*
X1615748Y512551D01*
X1615498Y512342D01*
X1615206Y512217D01*
X1614165D01*
G01X1615206D02*
X1615831Y511009D01*
G01X1618098D02*
X1618390Y511051D01*
X1618723Y511176D01*
X1618931Y511384D01*
X1619015Y511676D01*
X1618931Y511967D01*
X1618681Y512217D01*
X1618306Y512342D01*
X1617890D01*
X1617640Y512426D01*
X1617431Y512634D01*
X1617348Y512926D01*
X1617473Y513217D01*
X1617765Y513426D01*
X1618098Y513509D01*
X1618431Y513426D01*
X1618723Y513217D01*
X1618848Y512926D01*
X1618765Y512634D01*
X1618556Y512426D01*
X1618306Y512342D01*
X1617890D01*
X1617515Y512217D01*
X1617265Y511967D01*
X1617181Y511676D01*
X1617265Y511384D01*
X1617473Y511176D01*
X1617806Y511051D01*
X1618098Y511009D01*
G01X1621531Y512342D02*
X1621698Y512467D01*
X1621823Y512676D01*
X1621906Y512967D01*
X1621823Y513217D01*
X1621656Y513384D01*
X1621365Y513509D01*
X1620240D01*
Y511009D01*
X1621615D01*
X1621906Y511176D01*
X1622073Y511426D01*
X1622156Y511717D01*
X1622073Y512009D01*
X1621823Y512259D01*
X1621531Y512342D01*
X1620240D01*
G01X1623381Y511384D02*
X1623631Y511176D01*
X1623923Y511051D01*
X1624298Y511009D01*
X1624673Y511092D01*
X1624965Y511259D01*
X1625173Y511551D01*
X1625215Y511884D01*
X1625131Y512217D01*
X1624923Y512426D01*
X1624631Y512592D01*
X1624340Y512634D01*
X1624048Y512592D01*
X1623673Y512426D01*
X1623798Y513509D01*
X1624923D01*
G01X1619620Y524227D02*
X1617120D01*
Y525268D01*
X1617245Y525602D01*
X1617412Y525810D01*
X1617745Y525893D01*
X1618078Y525810D01*
X1618287Y525560D01*
X1618412Y525268D01*
Y524227D01*
G01Y525268D02*
X1619620Y525893D01*
G01Y528160D02*
X1619578Y528452D01*
X1619453Y528785D01*
X1619245Y528993D01*
X1618953Y529077D01*
X1618662Y528993D01*
X1618412Y528743D01*
X1618287Y528368D01*
Y527952D01*
X1618203Y527702D01*
X1617995Y527493D01*
X1617703Y527410D01*
X1617412Y527535D01*
X1617203Y527827D01*
X1617120Y528160D01*
X1617203Y528493D01*
X1617412Y528785D01*
X1617703Y528910D01*
X1617995Y528827D01*
X1618203Y528618D01*
X1618287Y528368D01*
Y527952D01*
X1618412Y527577D01*
X1618662Y527327D01*
X1618953Y527243D01*
X1619245Y527327D01*
X1619453Y527535D01*
X1619578Y527868D01*
X1619620Y528160D01*
G01X1618287Y531593D02*
X1618162Y531760D01*
X1617953Y531885D01*
X1617662Y531968D01*
X1617412Y531885D01*
X1617245Y531718D01*
X1617120Y531427D01*
Y530302D01*
X1619620D01*
Y531677D01*
X1619453Y531968D01*
X1619203Y532135D01*
X1618912Y532218D01*
X1618620Y532135D01*
X1618370Y531885D01*
X1618287Y531593D01*
Y530302D01*
G01X1619620Y534360D02*
X1617120D01*
X1617620Y533860D01*
G01X1619620D02*
Y534860D01*
G01X1606527Y470440D02*
Y472940D01*
X1607568D01*
X1607902Y472815D01*
X1608110Y472648D01*
X1608193Y472315D01*
X1608110Y471982D01*
X1607860Y471773D01*
X1607568Y471648D01*
X1606527D01*
G01X1607568D02*
X1608193Y470440D01*
G01X1610460D02*
Y472940D01*
X1609960Y472440D01*
G01Y470440D02*
X1610960D01*
G01X1612310Y472940D02*
X1612893Y470440D01*
X1613560Y472940D01*
X1614227Y470440D01*
X1614810Y472940D01*
G01X1616660Y470440D02*
Y472940D01*
X1616160Y472440D01*
G01Y470440D02*
X1617160D01*
G01X1618843Y470815D02*
X1619093Y470607D01*
X1619385Y470482D01*
X1619760Y470440D01*
X1620135Y470523D01*
X1620427Y470690D01*
X1620635Y470982D01*
X1620677Y471315D01*
X1620593Y471648D01*
X1620385Y471857D01*
X1620093Y472023D01*
X1619802Y472065D01*
X1619510Y472023D01*
X1619135Y471857D01*
X1619260Y472940D01*
X1620385D01*
G01X1606567Y473867D02*
Y476367D01*
X1607608D01*
X1607942Y476242D01*
X1608150Y476075D01*
X1608233Y475742D01*
X1608150Y475409D01*
X1607900Y475200D01*
X1607608Y475075D01*
X1606567D01*
G01X1607608D02*
X1608233Y473867D01*
G01X1610500D02*
Y476367D01*
X1610000Y475867D01*
G01Y473867D02*
X1611000D01*
G01X1612350Y476367D02*
X1612933Y473867D01*
X1613600Y476367D01*
X1614267Y473867D01*
X1614850Y476367D01*
G01X1616700Y473867D02*
Y476367D01*
X1616200Y475867D01*
G01Y473867D02*
X1617200D01*
G01X1620300D02*
Y476367D01*
X1618758Y474575D01*
X1620842D01*
G01X1629277Y468620D02*
Y471120D01*
X1630318D01*
X1630652Y470995D01*
X1630860Y470828D01*
X1630943Y470495D01*
X1630860Y470162D01*
X1630610Y469953D01*
X1630318Y469828D01*
X1629277D01*
G01X1630318D02*
X1630943Y468620D01*
G01X1633127D02*
X1633210Y469162D01*
X1633335Y469620D01*
X1633502Y470037D01*
X1633710Y470495D01*
X1634043Y471120D01*
X1632377D01*
G01X1635060D02*
X1635643Y468620D01*
X1636310Y471120D01*
X1636977Y468620D01*
X1637560Y471120D01*
G01X1639410Y468620D02*
Y471120D01*
X1638910Y470620D01*
G01Y468620D02*
X1639910D01*
G01X1642510Y471120D02*
X1642177Y471037D01*
X1641927Y470828D01*
X1641760Y470578D01*
X1641635Y470245D01*
X1641593Y469870D01*
X1641635Y469495D01*
X1641760Y469162D01*
X1641927Y468912D01*
X1642177Y468703D01*
X1642510Y468620D01*
X1642843Y468703D01*
X1643093Y468912D01*
X1643260Y469162D01*
X1643385Y469495D01*
X1643427Y469870D01*
X1643385Y470245D01*
X1643260Y470578D01*
X1643093Y470828D01*
X1642843Y471037D01*
X1642510Y471120D01*
G01X1605282Y501862D02*
X1605157Y501612D01*
X1605074Y501320D01*
Y500987D01*
X1605199Y500612D01*
X1605407Y500320D01*
X1605657Y500112D01*
X1606074Y499945D01*
X1606449Y499903D01*
X1606824Y499987D01*
X1607074Y500112D01*
X1607324Y500362D01*
X1607491Y500653D01*
X1607574Y500945D01*
Y501237D01*
X1607491Y501528D01*
X1607366Y501778D01*
X1607199Y501987D01*
G01X1607574Y504045D02*
X1607532Y504337D01*
X1607407Y504670D01*
X1607199Y504878D01*
X1606907Y504962D01*
X1606616Y504878D01*
X1606366Y504628D01*
X1606241Y504253D01*
Y503837D01*
X1606157Y503587D01*
X1605949Y503378D01*
X1605657Y503295D01*
X1605366Y503420D01*
X1605157Y503712D01*
X1605074Y504045D01*
X1605157Y504378D01*
X1605366Y504670D01*
X1605657Y504795D01*
X1605949Y504712D01*
X1606157Y504503D01*
X1606241Y504253D01*
Y503837D01*
X1606366Y503462D01*
X1606616Y503212D01*
X1606907Y503128D01*
X1607199Y503212D01*
X1607407Y503420D01*
X1607532Y503753D01*
X1607574Y504045D01*
G01X1606241Y507478D02*
X1606116Y507645D01*
X1605907Y507770D01*
X1605616Y507853D01*
X1605366Y507770D01*
X1605199Y507603D01*
X1605074Y507312D01*
Y506187D01*
X1607574D01*
Y507562D01*
X1607407Y507853D01*
X1607157Y508020D01*
X1606866Y508103D01*
X1606574Y508020D01*
X1606324Y507770D01*
X1606241Y507478D01*
Y506187D01*
G01X1607282Y509537D02*
X1607491Y509828D01*
X1607574Y510162D01*
X1607491Y510495D01*
X1607241Y510787D01*
X1606866Y510995D01*
X1606491Y511078D01*
X1606032D01*
X1605657Y510995D01*
X1605324Y510787D01*
X1605157Y510537D01*
X1605074Y510245D01*
X1605157Y509912D01*
X1605324Y509662D01*
X1605574Y509495D01*
X1605907Y509412D01*
X1606199Y509495D01*
X1606491Y509703D01*
X1606657Y509953D01*
X1606699Y510245D01*
X1606616Y510578D01*
X1606407Y510828D01*
X1606032Y511078D01*
G01X1608935Y501871D02*
X1608810Y501621D01*
X1608727Y501329D01*
Y500996D01*
X1608852Y500621D01*
X1609060Y500329D01*
X1609310Y500121D01*
X1609727Y499954D01*
X1610102Y499912D01*
X1610477Y499996D01*
X1610727Y500121D01*
X1610977Y500371D01*
X1611144Y500662D01*
X1611227Y500954D01*
Y501246D01*
X1611144Y501537D01*
X1611019Y501787D01*
X1610852Y501996D01*
G01X1611227Y504054D02*
X1611185Y504346D01*
X1611060Y504679D01*
X1610852Y504887D01*
X1610560Y504971D01*
X1610269Y504887D01*
X1610019Y504637D01*
X1609894Y504262D01*
Y503846D01*
X1609810Y503596D01*
X1609602Y503387D01*
X1609310Y503304D01*
X1609019Y503429D01*
X1608810Y503721D01*
X1608727Y504054D01*
X1608810Y504387D01*
X1609019Y504679D01*
X1609310Y504804D01*
X1609602Y504721D01*
X1609810Y504512D01*
X1609894Y504262D01*
Y503846D01*
X1610019Y503471D01*
X1610269Y503221D01*
X1610560Y503137D01*
X1610852Y503221D01*
X1611060Y503429D01*
X1611185Y503762D01*
X1611227Y504054D01*
G01X1609894Y507487D02*
X1609769Y507654D01*
X1609560Y507779D01*
X1609269Y507862D01*
X1609019Y507779D01*
X1608852Y507612D01*
X1608727Y507321D01*
Y506196D01*
X1611227D01*
Y507571D01*
X1611060Y507862D01*
X1610810Y508029D01*
X1610519Y508112D01*
X1610227Y508029D01*
X1609977Y507779D01*
X1609894Y507487D01*
Y506196D01*
G01X1611227Y510254D02*
X1608727D01*
X1609227Y509754D01*
G01X1611227D02*
Y510754D01*
G01X1608727Y513354D02*
X1608810Y513021D01*
X1609019Y512771D01*
X1609269Y512604D01*
X1609602Y512479D01*
X1609977Y512437D01*
X1610352Y512479D01*
X1610685Y512604D01*
X1610935Y512771D01*
X1611144Y513021D01*
X1611227Y513354D01*
X1611144Y513687D01*
X1610935Y513937D01*
X1610685Y514104D01*
X1610352Y514229D01*
X1609977Y514271D01*
X1609602Y514229D01*
X1609269Y514104D01*
X1609019Y513937D01*
X1608810Y513687D01*
X1608727Y513354D01*
G01X1615879Y507532D02*
X1615629Y507657D01*
X1615337Y507740D01*
X1615004D01*
X1614629Y507615D01*
X1614337Y507407D01*
X1614129Y507157D01*
X1613962Y506740D01*
X1613920Y506365D01*
X1614004Y505990D01*
X1614129Y505740D01*
X1614379Y505490D01*
X1614670Y505323D01*
X1614962Y505240D01*
X1615254D01*
X1615545Y505323D01*
X1615795Y505448D01*
X1616004Y505615D01*
G01X1618062Y505240D02*
X1618354Y505282D01*
X1618687Y505407D01*
X1618895Y505615D01*
X1618979Y505907D01*
X1618895Y506198D01*
X1618645Y506448D01*
X1618270Y506573D01*
X1617854D01*
X1617604Y506657D01*
X1617395Y506865D01*
X1617312Y507157D01*
X1617437Y507448D01*
X1617729Y507657D01*
X1618062Y507740D01*
X1618395Y507657D01*
X1618687Y507448D01*
X1618812Y507157D01*
X1618729Y506865D01*
X1618520Y506657D01*
X1618270Y506573D01*
X1617854D01*
X1617479Y506448D01*
X1617229Y506198D01*
X1617145Y505907D01*
X1617229Y505615D01*
X1617437Y505407D01*
X1617770Y505282D01*
X1618062Y505240D01*
G01X1621495Y506573D02*
X1621662Y506698D01*
X1621787Y506907D01*
X1621870Y507198D01*
X1621787Y507448D01*
X1621620Y507615D01*
X1621329Y507740D01*
X1620204D01*
Y505240D01*
X1621579D01*
X1621870Y505407D01*
X1622037Y505657D01*
X1622120Y505948D01*
X1622037Y506240D01*
X1621787Y506490D01*
X1621495Y506573D01*
X1620204D01*
G01X1624262Y505240D02*
Y507740D01*
X1623762Y507240D01*
G01Y505240D02*
X1624762D01*
G01X1627362D02*
Y507740D01*
X1626862Y507240D01*
G01Y505240D02*
X1627862D01*
G01X1593248Y510726D02*
X1592998Y510851D01*
X1592706Y510934D01*
X1592373D01*
X1591998Y510809D01*
X1591706Y510601D01*
X1591498Y510351D01*
X1591331Y509934D01*
X1591289Y509559D01*
X1591373Y509184D01*
X1591498Y508934D01*
X1591748Y508684D01*
X1592039Y508517D01*
X1592331Y508434D01*
X1592623D01*
X1592914Y508517D01*
X1593164Y508642D01*
X1593373Y508809D01*
G01X1595431Y508434D02*
X1595723Y508476D01*
X1596056Y508601D01*
X1596264Y508809D01*
X1596348Y509101D01*
X1596264Y509392D01*
X1596014Y509642D01*
X1595639Y509767D01*
X1595223D01*
X1594973Y509851D01*
X1594764Y510059D01*
X1594681Y510351D01*
X1594806Y510642D01*
X1595098Y510851D01*
X1595431Y510934D01*
X1595764Y510851D01*
X1596056Y510642D01*
X1596181Y510351D01*
X1596098Y510059D01*
X1595889Y509851D01*
X1595639Y509767D01*
X1595223D01*
X1594848Y509642D01*
X1594598Y509392D01*
X1594514Y509101D01*
X1594598Y508809D01*
X1594806Y508601D01*
X1595139Y508476D01*
X1595431Y508434D01*
G01X1598864Y509767D02*
X1599031Y509892D01*
X1599156Y510101D01*
X1599239Y510392D01*
X1599156Y510642D01*
X1598989Y510809D01*
X1598698Y510934D01*
X1597573D01*
Y508434D01*
X1598948D01*
X1599239Y508601D01*
X1599406Y508851D01*
X1599489Y509142D01*
X1599406Y509434D01*
X1599156Y509684D01*
X1598864Y509767D01*
X1597573D01*
G01X1601631Y508434D02*
Y510934D01*
X1601131Y510434D01*
G01Y508434D02*
X1602131D01*
G01X1625903Y478232D02*
X1626133Y478542D01*
X1626401Y478697D01*
X1626708Y478749D01*
X1627091Y478646D01*
X1627359Y478387D01*
X1627436Y478077D01*
X1627398Y477767D01*
X1627244Y477509D01*
X1626478Y476992D01*
X1626133Y476631D01*
X1625903Y476114D01*
X1625826Y475649D01*
X1627436D01*
G01X1628888Y476269D02*
X1629118Y475907D01*
X1629424Y475701D01*
X1629769Y475649D01*
X1630076Y475701D01*
X1630383Y475959D01*
X1630574Y476269D01*
X1630613Y476579D01*
X1630536Y476941D01*
X1630268Y477199D01*
X1629999Y477302D01*
X1629654D01*
G01X1629999D02*
X1630229Y477457D01*
X1630421Y477716D01*
X1630498Y478026D01*
X1630421Y478336D01*
X1630229Y478594D01*
X1629884Y478749D01*
X1629539Y478697D01*
X1629194Y478491D01*
G01X1633898Y525541D02*
Y529588D01*
X1641902D01*
G01Y472305D02*
X1633898D01*
Y476362D01*
G01X1608651Y543668D02*
X1608958Y543410D01*
X1609303Y543255D01*
X1609609D01*
X1609916Y543410D01*
X1610146Y543668D01*
X1610261Y544030D01*
X1610184Y544392D01*
X1609993Y544702D01*
X1609648Y544908D01*
X1609188Y545012D01*
X1608919Y545218D01*
X1608804Y545580D01*
X1608881Y545942D01*
X1609073Y546200D01*
X1609341Y546355D01*
X1609609D01*
X1609878Y546252D01*
X1610108Y545993D01*
G01X1611598Y543255D02*
X1612556Y546355D01*
X1613514Y543255D01*
G01X1613169Y544340D02*
X1611943D01*
G01X1615656Y546355D02*
Y543255D01*
G01X1614774Y546355D02*
X1616538D01*
G01X1617798Y543255D02*
X1618756Y546355D01*
X1619714Y543255D01*
G01X1619369Y544340D02*
X1618143D01*
G01X1621664Y542222D02*
X1621281Y542738D01*
X1621089Y543255D01*
Y545322D01*
X1621281Y545838D01*
X1621664Y546355D01*
G01X1624879Y543255D02*
X1624956Y543927D01*
X1625071Y544495D01*
X1625224Y545012D01*
X1625416Y545580D01*
X1625723Y546355D01*
X1624189D01*
G01X1628056Y543152D02*
X1627979Y543203D01*
Y543307D01*
X1628056Y543358D01*
X1628133Y543307D01*
Y543203D01*
X1628056Y543152D01*
G01Y544547D02*
X1627979Y544598D01*
Y544702D01*
X1628056Y544753D01*
X1628133Y544702D01*
Y544598D01*
X1628056Y544547D01*
G01X1631156Y546355D02*
X1630849Y546252D01*
X1630619Y545993D01*
X1630466Y545683D01*
X1630351Y545270D01*
X1630313Y544805D01*
X1630351Y544340D01*
X1630466Y543927D01*
X1630619Y543617D01*
X1630849Y543358D01*
X1631156Y543255D01*
X1631463Y543358D01*
X1631693Y543617D01*
X1631846Y543927D01*
X1631961Y544340D01*
X1631999Y544805D01*
X1631961Y545270D01*
X1631846Y545683D01*
X1631693Y545993D01*
X1631463Y546252D01*
X1631156Y546355D01*
G01X1634448Y542222D02*
X1634831Y542738D01*
X1635023Y543255D01*
Y545322D01*
X1634831Y545838D01*
X1634448Y546355D01*
G01X1589000Y579800D02*
X1592200D01*
Y578200D01*
X1601300D01*
Y586900D01*
G01X1602708Y542517D02*
X1602583Y542267D01*
X1602500Y541975D01*
Y541642D01*
X1602625Y541267D01*
X1602833Y540975D01*
X1603083Y540767D01*
X1603500Y540600D01*
X1603875Y540558D01*
X1604250Y540642D01*
X1604500Y540767D01*
X1604750Y541017D01*
X1604917Y541308D01*
X1605000Y541600D01*
Y541892D01*
X1604917Y542183D01*
X1604792Y542433D01*
X1604625Y542642D01*
G01X1605000Y544700D02*
X1604958Y544992D01*
X1604833Y545325D01*
X1604625Y545533D01*
X1604333Y545617D01*
X1604042Y545533D01*
X1603792Y545283D01*
X1603667Y544908D01*
Y544492D01*
X1603583Y544242D01*
X1603375Y544033D01*
X1603083Y543950D01*
X1602792Y544075D01*
X1602583Y544367D01*
X1602500Y544700D01*
X1602583Y545033D01*
X1602792Y545325D01*
X1603083Y545450D01*
X1603375Y545367D01*
X1603583Y545158D01*
X1603667Y544908D01*
Y544492D01*
X1603792Y544117D01*
X1604042Y543867D01*
X1604333Y543783D01*
X1604625Y543867D01*
X1604833Y544075D01*
X1604958Y544408D01*
X1605000Y544700D01*
G01Y546758D02*
X1602500Y547800D01*
X1605000Y548842D01*
G01X1604125Y548467D02*
Y547133D01*
G01X1605000Y550900D02*
X1602500D01*
X1603000Y550400D01*
G01X1605000D02*
Y551400D01*
G01Y554500D02*
X1602500D01*
X1604292Y552958D01*
Y555042D01*
G01X1599308Y547917D02*
X1599183Y547667D01*
X1599100Y547375D01*
Y547042D01*
X1599225Y546667D01*
X1599433Y546375D01*
X1599683Y546167D01*
X1600100Y546000D01*
X1600475Y545958D01*
X1600850Y546042D01*
X1601100Y546167D01*
X1601350Y546417D01*
X1601517Y546708D01*
X1601600Y547000D01*
Y547292D01*
X1601517Y547583D01*
X1601392Y547833D01*
X1601225Y548042D01*
G01X1601600Y550100D02*
X1601558Y550392D01*
X1601433Y550725D01*
X1601225Y550933D01*
X1600933Y551017D01*
X1600642Y550933D01*
X1600392Y550683D01*
X1600267Y550308D01*
Y549892D01*
X1600183Y549642D01*
X1599975Y549433D01*
X1599683Y549350D01*
X1599392Y549475D01*
X1599183Y549767D01*
X1599100Y550100D01*
X1599183Y550433D01*
X1599392Y550725D01*
X1599683Y550850D01*
X1599975Y550767D01*
X1600183Y550558D01*
X1600267Y550308D01*
Y549892D01*
X1600392Y549517D01*
X1600642Y549267D01*
X1600933Y549183D01*
X1601225Y549267D01*
X1601433Y549475D01*
X1601558Y549808D01*
X1601600Y550100D01*
G01Y552158D02*
X1599100Y553200D01*
X1601600Y554242D01*
G01X1600725Y553867D02*
Y552533D01*
G01X1601600Y556300D02*
X1599100D01*
X1599600Y555800D01*
G01X1601600D02*
Y556800D01*
G01X1599517Y558608D02*
X1599267Y558858D01*
X1599142Y559150D01*
X1599100Y559483D01*
X1599183Y559900D01*
X1599392Y560192D01*
X1599642Y560275D01*
X1599892Y560233D01*
X1600100Y560067D01*
X1600517Y559233D01*
X1600808Y558858D01*
X1601225Y558608D01*
X1601600Y558525D01*
Y560275D01*
G01X1634310Y534968D02*
Y537468D01*
X1635351D01*
X1635685Y537343D01*
X1635893Y537176D01*
X1635976Y536843D01*
X1635893Y536510D01*
X1635643Y536301D01*
X1635351Y536176D01*
X1634310D01*
G01X1635351D02*
X1635976Y534968D01*
G01X1638243D02*
X1638535Y535010D01*
X1638868Y535135D01*
X1639076Y535343D01*
X1639160Y535635D01*
X1639076Y535926D01*
X1638826Y536176D01*
X1638451Y536301D01*
X1638035D01*
X1637785Y536385D01*
X1637576Y536593D01*
X1637493Y536885D01*
X1637618Y537176D01*
X1637910Y537385D01*
X1638243Y537468D01*
X1638576Y537385D01*
X1638868Y537176D01*
X1638993Y536885D01*
X1638910Y536593D01*
X1638701Y536385D01*
X1638451Y536301D01*
X1638035D01*
X1637660Y536176D01*
X1637410Y535926D01*
X1637326Y535635D01*
X1637410Y535343D01*
X1637618Y535135D01*
X1637951Y535010D01*
X1638243Y534968D01*
G01X1640301D02*
X1641343Y537468D01*
X1642385Y534968D01*
G01X1642010Y535843D02*
X1640676D01*
G01X1644443Y534968D02*
Y537468D01*
X1643943Y536968D01*
G01Y534968D02*
X1644943D01*
G01X1648043D02*
Y537468D01*
X1646501Y535676D01*
X1648585D01*
G01X1625207Y538620D02*
Y541120D01*
X1626248D01*
X1626582Y540995D01*
X1626790Y540828D01*
X1626873Y540495D01*
X1626790Y540162D01*
X1626540Y539953D01*
X1626248Y539828D01*
X1625207D01*
G01X1626248D02*
X1626873Y538620D01*
G01X1629140D02*
X1629432Y538662D01*
X1629765Y538787D01*
X1629973Y538995D01*
X1630057Y539287D01*
X1629973Y539578D01*
X1629723Y539828D01*
X1629348Y539953D01*
X1628932D01*
X1628682Y540037D01*
X1628473Y540245D01*
X1628390Y540537D01*
X1628515Y540828D01*
X1628807Y541037D01*
X1629140Y541120D01*
X1629473Y541037D01*
X1629765Y540828D01*
X1629890Y540537D01*
X1629807Y540245D01*
X1629598Y540037D01*
X1629348Y539953D01*
X1628932D01*
X1628557Y539828D01*
X1628307Y539578D01*
X1628223Y539287D01*
X1628307Y538995D01*
X1628515Y538787D01*
X1628848Y538662D01*
X1629140Y538620D01*
G01X1631198D02*
X1632240Y541120D01*
X1633282Y538620D01*
G01X1632907Y539495D02*
X1631573D01*
G01X1635340Y538620D02*
Y541120D01*
X1634840Y540620D01*
G01Y538620D02*
X1635840D01*
G01X1637523Y539120D02*
X1637773Y538828D01*
X1638107Y538662D01*
X1638482Y538620D01*
X1638815Y538662D01*
X1639148Y538870D01*
X1639357Y539120D01*
X1639398Y539370D01*
X1639315Y539662D01*
X1639023Y539870D01*
X1638732Y539953D01*
X1638357D01*
G01X1638732D02*
X1638982Y540078D01*
X1639190Y540287D01*
X1639273Y540537D01*
X1639190Y540787D01*
X1638982Y540995D01*
X1638607Y541120D01*
X1638232Y541078D01*
X1637857Y540912D01*
G01X1597600Y546167D02*
X1595100D01*
Y547208D01*
X1595225Y547542D01*
X1595392Y547750D01*
X1595725Y547833D01*
X1596058Y547750D01*
X1596267Y547500D01*
X1596392Y547208D01*
Y546167D01*
G01Y547208D02*
X1597600Y547833D01*
G01Y550100D02*
X1597558Y550392D01*
X1597433Y550725D01*
X1597225Y550933D01*
X1596933Y551017D01*
X1596642Y550933D01*
X1596392Y550683D01*
X1596267Y550308D01*
Y549892D01*
X1596183Y549642D01*
X1595975Y549433D01*
X1595683Y549350D01*
X1595392Y549475D01*
X1595183Y549767D01*
X1595100Y550100D01*
X1595183Y550433D01*
X1595392Y550725D01*
X1595683Y550850D01*
X1595975Y550767D01*
X1596183Y550558D01*
X1596267Y550308D01*
Y549892D01*
X1596392Y549517D01*
X1596642Y549267D01*
X1596933Y549183D01*
X1597225Y549267D01*
X1597433Y549475D01*
X1597558Y549808D01*
X1597600Y550100D01*
G01Y552158D02*
X1595100Y553200D01*
X1597600Y554242D01*
G01X1596725Y553867D02*
Y552533D01*
G01X1597600Y556300D02*
X1595100D01*
X1595600Y555800D01*
G01X1597600D02*
Y556800D01*
G01X1595517Y558608D02*
X1595267Y558858D01*
X1595142Y559150D01*
X1595100Y559483D01*
X1595183Y559900D01*
X1595392Y560192D01*
X1595642Y560275D01*
X1595892Y560233D01*
X1596100Y560067D01*
X1596517Y559233D01*
X1596808Y558858D01*
X1597225Y558608D01*
X1597600Y558525D01*
Y560275D01*
G01X1618070Y552845D02*
X1618300Y553155D01*
X1618568Y553310D01*
X1618875Y553362D01*
X1619258Y553259D01*
X1619526Y553000D01*
X1619603Y552690D01*
X1619565Y552380D01*
X1619411Y552122D01*
X1618645Y551605D01*
X1618300Y551244D01*
X1618070Y550727D01*
X1617993Y550262D01*
X1619603D01*
G01X1621055D02*
Y553362D01*
X1621821D01*
X1622128Y553207D01*
X1622358Y553000D01*
X1622550Y552690D01*
X1622703Y552329D01*
X1622741Y551812D01*
X1622703Y551295D01*
X1622550Y550934D01*
X1622358Y550624D01*
X1622128Y550417D01*
X1621821Y550262D01*
X1621055D01*
G01X1624346Y550624D02*
X1624615Y550365D01*
X1624921Y550262D01*
X1625228Y550365D01*
X1625496Y550675D01*
X1625688Y551140D01*
X1625765Y551605D01*
Y552174D01*
X1625688Y552639D01*
X1625496Y553052D01*
X1625266Y553259D01*
X1624998Y553362D01*
X1624691Y553259D01*
X1624461Y553052D01*
X1624308Y552742D01*
X1624231Y552329D01*
X1624308Y551967D01*
X1624500Y551605D01*
X1624730Y551399D01*
X1624998Y551347D01*
X1625305Y551450D01*
X1625535Y551709D01*
X1625765Y552174D01*
G01X1643987Y552320D02*
X1644195Y552070D01*
X1644445Y551903D01*
X1644737Y551820D01*
X1645070Y551903D01*
X1645320Y552070D01*
X1645570Y552320D01*
X1645653Y552653D01*
Y554320D01*
G01X1647920Y551820D02*
X1648212Y551862D01*
X1648545Y551987D01*
X1648753Y552195D01*
X1648837Y552487D01*
X1648753Y552778D01*
X1648503Y553028D01*
X1648128Y553153D01*
X1647712D01*
X1647462Y553237D01*
X1647253Y553445D01*
X1647170Y553737D01*
X1647295Y554028D01*
X1647587Y554237D01*
X1647920Y554320D01*
X1648253Y554237D01*
X1648545Y554028D01*
X1648670Y553737D01*
X1648587Y553445D01*
X1648378Y553237D01*
X1648128Y553153D01*
X1647712D01*
X1647337Y553028D01*
X1647087Y552778D01*
X1647003Y552487D01*
X1647087Y552195D01*
X1647295Y551987D01*
X1647628Y551862D01*
X1647920Y551820D01*
G01X1649978D02*
X1651020Y554320D01*
X1652062Y551820D01*
G01X1651687Y552695D02*
X1650353D01*
G01X1654120Y551820D02*
Y554320D01*
X1653620Y553820D01*
G01Y551820D02*
X1654620D01*
G01X1712287Y622067D02*
Y555807D01*
X1604846D01*
Y622067D01*
X1712287D01*
G01X1640814Y542568D02*
X1641022Y542318D01*
X1641272Y542151D01*
X1641564Y542068D01*
X1641897Y542151D01*
X1642147Y542318D01*
X1642397Y542568D01*
X1642480Y542901D01*
Y544568D01*
G01X1643955Y544151D02*
X1644205Y544401D01*
X1644497Y544526D01*
X1644830Y544568D01*
X1645247Y544485D01*
X1645539Y544276D01*
X1645622Y544026D01*
X1645580Y543776D01*
X1645414Y543568D01*
X1644580Y543151D01*
X1644205Y542860D01*
X1643955Y542443D01*
X1643872Y542068D01*
X1645622D01*
G01X1646597Y544568D02*
X1647180Y542068D01*
X1647847Y544568D01*
X1648514Y542068D01*
X1649097Y544568D01*
G01X1650155Y544151D02*
X1650405Y544401D01*
X1650697Y544526D01*
X1651030Y544568D01*
X1651447Y544485D01*
X1651739Y544276D01*
X1651822Y544026D01*
X1651780Y543776D01*
X1651614Y543568D01*
X1650780Y543151D01*
X1650405Y542860D01*
X1650155Y542443D01*
X1650072Y542068D01*
X1651822D01*
G01X1601300Y592300D02*
Y596200D01*
X1591700D01*
G01X1591442Y605967D02*
X1591317Y605717D01*
X1591234Y605425D01*
Y605092D01*
X1591359Y604717D01*
X1591567Y604425D01*
X1591817Y604217D01*
X1592234Y604050D01*
X1592609Y604008D01*
X1592984Y604092D01*
X1593234Y604217D01*
X1593484Y604467D01*
X1593651Y604758D01*
X1593734Y605050D01*
Y605342D01*
X1593651Y605633D01*
X1593526Y605883D01*
X1593359Y606092D01*
G01X1593734Y608150D02*
X1593692Y608442D01*
X1593567Y608775D01*
X1593359Y608983D01*
X1593067Y609067D01*
X1592776Y608983D01*
X1592526Y608733D01*
X1592401Y608358D01*
Y607942D01*
X1592317Y607692D01*
X1592109Y607483D01*
X1591817Y607400D01*
X1591526Y607525D01*
X1591317Y607817D01*
X1591234Y608150D01*
X1591317Y608483D01*
X1591526Y608775D01*
X1591817Y608900D01*
X1592109Y608817D01*
X1592317Y608608D01*
X1592401Y608358D01*
Y607942D01*
X1592526Y607567D01*
X1592776Y607317D01*
X1593067Y607233D01*
X1593359Y607317D01*
X1593567Y607525D01*
X1593692Y607858D01*
X1593734Y608150D01*
G01Y610208D02*
X1591234Y611250D01*
X1593734Y612292D01*
G01X1592859Y611917D02*
Y610583D01*
G01X1592692Y613558D02*
X1592401Y613850D01*
X1592234Y614100D01*
X1592151Y614433D01*
X1592234Y614725D01*
X1592401Y614933D01*
X1592651Y615100D01*
X1592942Y615142D01*
X1593192Y615100D01*
X1593442Y614933D01*
X1593651Y614683D01*
X1593734Y614392D01*
X1593651Y614058D01*
X1593401Y613767D01*
X1593026Y613600D01*
X1592609Y613558D01*
X1592067Y613642D01*
X1591776Y613767D01*
X1591484Y613975D01*
X1591276Y614267D01*
X1591234Y614558D01*
X1591317Y614850D01*
X1591526Y615058D01*
G01X1598542Y601467D02*
X1598417Y601217D01*
X1598334Y600925D01*
Y600592D01*
X1598459Y600217D01*
X1598667Y599925D01*
X1598917Y599717D01*
X1599334Y599550D01*
X1599709Y599508D01*
X1600084Y599592D01*
X1600334Y599717D01*
X1600584Y599967D01*
X1600751Y600258D01*
X1600834Y600550D01*
Y600842D01*
X1600751Y601133D01*
X1600626Y601383D01*
X1600459Y601592D01*
G01X1600834Y603650D02*
X1600792Y603942D01*
X1600667Y604275D01*
X1600459Y604483D01*
X1600167Y604567D01*
X1599876Y604483D01*
X1599626Y604233D01*
X1599501Y603858D01*
Y603442D01*
X1599417Y603192D01*
X1599209Y602983D01*
X1598917Y602900D01*
X1598626Y603025D01*
X1598417Y603317D01*
X1598334Y603650D01*
X1598417Y603983D01*
X1598626Y604275D01*
X1598917Y604400D01*
X1599209Y604317D01*
X1599417Y604108D01*
X1599501Y603858D01*
Y603442D01*
X1599626Y603067D01*
X1599876Y602817D01*
X1600167Y602733D01*
X1600459Y602817D01*
X1600667Y603025D01*
X1600792Y603358D01*
X1600834Y603650D01*
G01Y605708D02*
X1598334Y606750D01*
X1600834Y607792D01*
G01X1599959Y607417D02*
Y606083D01*
G01X1600834Y610350D02*
X1598334D01*
X1600126Y608808D01*
Y610892D01*
G01X1596352Y624343D02*
X1596582Y624653D01*
X1596850Y624808D01*
X1597157Y624860D01*
X1597540Y624757D01*
X1597808Y624498D01*
X1597885Y624188D01*
X1597847Y623878D01*
X1597693Y623620D01*
X1596927Y623103D01*
X1596582Y622742D01*
X1596352Y622225D01*
X1596275Y621760D01*
X1597885D01*
G01X1599222D02*
X1600180Y624860D01*
X1601138Y621760D01*
G01X1600793Y622845D02*
X1599567D01*
G01X1602628Y622122D02*
X1602897Y621863D01*
X1603203Y621760D01*
X1603510Y621863D01*
X1603778Y622173D01*
X1603970Y622638D01*
X1604047Y623103D01*
Y623672D01*
X1603970Y624137D01*
X1603778Y624550D01*
X1603548Y624757D01*
X1603280Y624860D01*
X1602973Y624757D01*
X1602743Y624550D01*
X1602590Y624240D01*
X1602513Y623827D01*
X1602590Y623465D01*
X1602782Y623103D01*
X1603012Y622897D01*
X1603280Y622845D01*
X1603587Y622948D01*
X1603817Y623207D01*
X1604047Y623672D01*
G01X1675357Y7153D02*
X1675510Y7308D01*
X1675625Y7567D01*
X1675702Y7928D01*
X1675625Y8238D01*
X1675472Y8445D01*
X1675203Y8600D01*
X1674168D01*
Y5500D01*
X1675433D01*
X1675702Y5707D01*
X1675855Y6017D01*
X1675932Y6378D01*
X1675855Y6740D01*
X1675625Y7050D01*
X1675357Y7153D01*
X1674168D01*
G01X1677192Y5500D02*
X1678150Y8600D01*
X1679108Y5500D01*
G01X1678763Y6585D02*
X1677537D01*
G01X1681250Y8600D02*
Y5500D01*
G01X1680368Y8600D02*
X1682132D01*
G01X1711367Y5330D02*
Y7830D01*
X1712408D01*
X1712742Y7705D01*
X1712950Y7538D01*
X1713033Y7205D01*
X1712950Y6872D01*
X1712700Y6663D01*
X1712408Y6538D01*
X1711367D01*
G01X1712408D02*
X1713033Y5330D01*
G01X1715300D02*
X1715592Y5372D01*
X1715925Y5497D01*
X1716133Y5705D01*
X1716217Y5997D01*
X1716133Y6288D01*
X1715883Y6538D01*
X1715508Y6663D01*
X1715092D01*
X1714842Y6747D01*
X1714633Y6955D01*
X1714550Y7247D01*
X1714675Y7538D01*
X1714967Y7747D01*
X1715300Y7830D01*
X1715633Y7747D01*
X1715925Y7538D01*
X1716050Y7247D01*
X1715967Y6955D01*
X1715758Y6747D01*
X1715508Y6663D01*
X1715092D01*
X1714717Y6538D01*
X1714467Y6288D01*
X1714383Y5997D01*
X1714467Y5705D01*
X1714675Y5497D01*
X1715008Y5372D01*
X1715300Y5330D01*
G01X1717483D02*
Y7830D01*
X1718317D01*
X1718650Y7705D01*
X1718900Y7538D01*
X1719108Y7288D01*
X1719275Y6997D01*
X1719317Y6580D01*
X1719275Y6163D01*
X1719108Y5872D01*
X1718900Y5622D01*
X1718650Y5455D01*
X1718317Y5330D01*
X1717483D01*
G01X1720708Y7413D02*
X1720958Y7663D01*
X1721250Y7788D01*
X1721583Y7830D01*
X1722000Y7747D01*
X1722292Y7538D01*
X1722375Y7288D01*
X1722333Y7038D01*
X1722167Y6830D01*
X1721333Y6413D01*
X1720958Y6122D01*
X1720708Y5705D01*
X1720625Y5330D01*
X1722375D01*
G01X1724600D02*
Y7830D01*
X1724100Y7330D01*
G01Y5330D02*
X1725100D01*
G01X1697677Y-11547D02*
X1695177Y-9797D01*
G01Y-11547D02*
X1697677Y-9797D01*
G01X1696344Y-7239D02*
X1696219Y-7072D01*
X1696010Y-6947D01*
X1695719Y-6864D01*
X1695469Y-6947D01*
X1695302Y-7114D01*
X1695177Y-7405D01*
Y-8530D01*
X1697677D01*
Y-7155D01*
X1697510Y-6864D01*
X1697260Y-6697D01*
X1696969Y-6614D01*
X1696677Y-6697D01*
X1696427Y-6947D01*
X1696344Y-7239D01*
Y-8530D01*
G01X1695177Y-4472D02*
X1697677D01*
G01X1695177Y-5430D02*
Y-3514D01*
G01X1697677Y-1372D02*
X1697635Y-1080D01*
X1697510Y-747D01*
X1697302Y-539D01*
X1697010Y-455D01*
X1696719Y-539D01*
X1696469Y-789D01*
X1696344Y-1164D01*
Y-1580D01*
X1696260Y-1830D01*
X1696052Y-2039D01*
X1695760Y-2122D01*
X1695469Y-1997D01*
X1695260Y-1705D01*
X1695177Y-1372D01*
X1695260Y-1039D01*
X1695469Y-747D01*
X1695760Y-622D01*
X1696052Y-705D01*
X1696260Y-914D01*
X1696344Y-1164D01*
Y-1580D01*
X1696469Y-1955D01*
X1696719Y-2205D01*
X1697010Y-2289D01*
X1697302Y-2205D01*
X1697510Y-1997D01*
X1697635Y-1664D01*
X1697677Y-1372D01*
G01X1696427Y1978D02*
Y2811D01*
X1697177D01*
X1697427Y2561D01*
X1697594Y2270D01*
X1697677Y1853D01*
X1697594Y1436D01*
X1697427Y1145D01*
X1697177Y895D01*
X1696885Y728D01*
X1696552Y645D01*
X1696260D01*
X1696010Y728D01*
X1695719Y895D01*
X1695469Y1145D01*
X1695302Y1395D01*
X1695177Y1728D01*
Y2020D01*
X1695260Y2353D01*
X1695427Y2603D01*
G01X1697677Y4828D02*
X1695177D01*
X1695677Y4328D01*
G01X1697677D02*
Y5328D01*
G01X1678212Y-24788D02*
X1673212D01*
G01X1675712Y-27288D02*
Y-22288D01*
G01X1701992Y3790D02*
X1702222Y4100D01*
X1702490Y4255D01*
X1702797Y4307D01*
X1703180Y4204D01*
X1703448Y3945D01*
X1703525Y3635D01*
X1703487Y3325D01*
X1703333Y3067D01*
X1702567Y2550D01*
X1702222Y2189D01*
X1701992Y1672D01*
X1701915Y1207D01*
X1703525D01*
G01X1758503Y50D02*
Y-20050D01*
X1698503D01*
Y50D01*
X1758503D01*
G01X1704900Y54000D02*
X1711000D01*
Y40600D01*
X1711400D01*
G01X1713600Y71100D02*
X1710600D01*
Y75000D01*
X1703300D01*
Y74100D01*
G01X1672000Y62037D02*
X1669500D01*
Y63078D01*
X1669625Y63412D01*
X1669792Y63620D01*
X1670125Y63703D01*
X1670458Y63620D01*
X1670667Y63370D01*
X1670792Y63078D01*
Y62037D01*
G01Y63078D02*
X1672000Y63703D01*
G01Y65970D02*
X1669500D01*
X1670000Y65470D01*
G01X1672000D02*
Y66470D01*
G01X1669500Y68153D02*
X1671292D01*
X1671667Y68320D01*
X1671917Y68653D01*
X1672000Y69070D01*
X1671917Y69487D01*
X1671667Y69820D01*
X1671292Y69987D01*
X1669500D01*
G01X1672000Y72170D02*
X1669500D01*
X1670000Y71670D01*
G01X1672000D02*
Y72670D01*
G01Y75770D02*
X1669500D01*
X1671292Y74228D01*
Y76312D01*
G01X1668500Y62037D02*
X1666000D01*
Y63078D01*
X1666125Y63412D01*
X1666292Y63620D01*
X1666625Y63703D01*
X1666958Y63620D01*
X1667167Y63370D01*
X1667292Y63078D01*
Y62037D01*
G01Y63078D02*
X1668500Y63703D01*
G01X1666417Y65178D02*
X1666167Y65428D01*
X1666042Y65720D01*
X1666000Y66053D01*
X1666083Y66470D01*
X1666292Y66762D01*
X1666542Y66845D01*
X1666792Y66803D01*
X1667000Y66637D01*
X1667417Y65803D01*
X1667708Y65428D01*
X1668125Y65178D01*
X1668500Y65095D01*
Y66845D01*
G01X1666000Y69070D02*
X1668500D01*
G01X1666000Y68112D02*
Y70028D01*
G01X1668500Y72670D02*
X1666000D01*
X1667792Y71128D01*
Y73212D01*
G01X1668208Y74562D02*
X1668417Y74853D01*
X1668500Y75187D01*
X1668417Y75520D01*
X1668167Y75812D01*
X1667792Y76020D01*
X1667417Y76103D01*
X1666958D01*
X1666583Y76020D01*
X1666250Y75812D01*
X1666083Y75562D01*
X1666000Y75270D01*
X1666083Y74937D01*
X1666250Y74687D01*
X1666500Y74520D01*
X1666833Y74437D01*
X1667125Y74520D01*
X1667417Y74728D01*
X1667583Y74978D01*
X1667625Y75270D01*
X1667542Y75603D01*
X1667333Y75853D01*
X1666958Y76103D01*
G01X1665000Y62037D02*
X1662500D01*
Y63078D01*
X1662625Y63412D01*
X1662792Y63620D01*
X1663125Y63703D01*
X1663458Y63620D01*
X1663667Y63370D01*
X1663792Y63078D01*
Y62037D01*
G01Y63078D02*
X1665000Y63703D01*
G01X1662917Y65178D02*
X1662667Y65428D01*
X1662542Y65720D01*
X1662500Y66053D01*
X1662583Y66470D01*
X1662792Y66762D01*
X1663042Y66845D01*
X1663292Y66803D01*
X1663500Y66637D01*
X1663917Y65803D01*
X1664208Y65428D01*
X1664625Y65178D01*
X1665000Y65095D01*
Y66845D01*
G01X1662500Y68153D02*
X1664292D01*
X1664667Y68320D01*
X1664917Y68653D01*
X1665000Y69070D01*
X1664917Y69487D01*
X1664667Y69820D01*
X1664292Y69987D01*
X1662500D01*
G01X1665000Y72170D02*
X1662500D01*
X1663000Y71670D01*
G01X1665000D02*
Y72670D01*
G01X1661500Y62037D02*
X1659000D01*
Y63078D01*
X1659125Y63412D01*
X1659292Y63620D01*
X1659625Y63703D01*
X1659958Y63620D01*
X1660167Y63370D01*
X1660292Y63078D01*
Y62037D01*
G01Y63078D02*
X1661500Y63703D01*
G01Y65970D02*
X1659000D01*
X1659500Y65470D01*
G01X1661500D02*
Y66470D01*
G01X1659000Y68153D02*
X1660792D01*
X1661167Y68320D01*
X1661417Y68653D01*
X1661500Y69070D01*
X1661417Y69487D01*
X1661167Y69820D01*
X1660792Y69987D01*
X1659000D01*
G01X1661500Y72170D02*
X1659000D01*
X1659500Y71670D01*
G01X1661500D02*
Y72670D01*
G01X1661000Y74353D02*
X1661292Y74603D01*
X1661458Y74937D01*
X1661500Y75312D01*
X1661458Y75645D01*
X1661250Y75978D01*
X1661000Y76187D01*
X1660750Y76228D01*
X1660458Y76145D01*
X1660250Y75853D01*
X1660167Y75562D01*
Y75187D01*
G01Y75562D02*
X1660042Y75812D01*
X1659833Y76020D01*
X1659583Y76103D01*
X1659333Y76020D01*
X1659125Y75812D01*
X1659000Y75437D01*
X1659042Y75062D01*
X1659208Y74687D01*
G01X1675500Y62037D02*
X1673000D01*
Y63078D01*
X1673125Y63412D01*
X1673292Y63620D01*
X1673625Y63703D01*
X1673958Y63620D01*
X1674167Y63370D01*
X1674292Y63078D01*
Y62037D01*
G01Y63078D02*
X1675500Y63703D01*
G01Y65970D02*
X1675458Y66262D01*
X1675333Y66595D01*
X1675125Y66803D01*
X1674833Y66887D01*
X1674542Y66803D01*
X1674292Y66553D01*
X1674167Y66178D01*
Y65762D01*
X1674083Y65512D01*
X1673875Y65303D01*
X1673583Y65220D01*
X1673292Y65345D01*
X1673083Y65637D01*
X1673000Y65970D01*
X1673083Y66303D01*
X1673292Y66595D01*
X1673583Y66720D01*
X1673875Y66637D01*
X1674083Y66428D01*
X1674167Y66178D01*
Y65762D01*
X1674292Y65387D01*
X1674542Y65137D01*
X1674833Y65053D01*
X1675125Y65137D01*
X1675333Y65345D01*
X1675458Y65678D01*
X1675500Y65970D01*
G01Y69903D02*
Y68237D01*
X1673000D01*
Y69903D01*
G01X1674208Y69237D02*
Y68237D01*
G01X1675500Y72170D02*
X1673000D01*
X1673500Y71670D01*
G01X1675500D02*
Y72670D01*
G01X1675208Y74562D02*
X1675417Y74853D01*
X1675500Y75187D01*
X1675417Y75520D01*
X1675167Y75812D01*
X1674792Y76020D01*
X1674417Y76103D01*
X1673958D01*
X1673583Y76020D01*
X1673250Y75812D01*
X1673083Y75562D01*
X1673000Y75270D01*
X1673083Y74937D01*
X1673250Y74687D01*
X1673500Y74520D01*
X1673833Y74437D01*
X1674125Y74520D01*
X1674417Y74728D01*
X1674583Y74978D01*
X1674625Y75270D01*
X1674542Y75603D01*
X1674333Y75853D01*
X1673958Y76103D01*
G01X1672137Y84180D02*
Y86680D01*
X1673178D01*
X1673512Y86555D01*
X1673720Y86388D01*
X1673803Y86055D01*
X1673720Y85722D01*
X1673470Y85513D01*
X1673178Y85388D01*
X1672137D01*
G01X1673178D02*
X1673803Y84180D01*
G01X1676070D02*
Y86680D01*
X1675570Y86180D01*
G01Y84180D02*
X1676570D01*
G01X1679170Y86680D02*
X1678837Y86597D01*
X1678587Y86388D01*
X1678420Y86138D01*
X1678295Y85805D01*
X1678253Y85430D01*
X1678295Y85055D01*
X1678420Y84722D01*
X1678587Y84472D01*
X1678837Y84263D01*
X1679170Y84180D01*
X1679503Y84263D01*
X1679753Y84472D01*
X1679920Y84722D01*
X1680045Y85055D01*
X1680087Y85430D01*
X1680045Y85805D01*
X1679920Y86138D01*
X1679753Y86388D01*
X1679503Y86597D01*
X1679170Y86680D01*
G01X1681020D02*
X1681603Y84180D01*
X1682270Y86680D01*
X1682937Y84180D01*
X1683520Y86680D01*
G01X1684453Y84680D02*
X1684703Y84388D01*
X1685037Y84222D01*
X1685412Y84180D01*
X1685745Y84222D01*
X1686078Y84430D01*
X1686287Y84680D01*
X1686328Y84930D01*
X1686245Y85222D01*
X1685953Y85430D01*
X1685662Y85513D01*
X1685287D01*
G01X1685662D02*
X1685912Y85638D01*
X1686120Y85847D01*
X1686203Y86097D01*
X1686120Y86347D01*
X1685912Y86555D01*
X1685537Y86680D01*
X1685162Y86638D01*
X1684787Y86472D01*
G01X1690037Y91600D02*
Y94100D01*
X1691078D01*
X1691412Y93975D01*
X1691620Y93808D01*
X1691703Y93475D01*
X1691620Y93142D01*
X1691370Y92933D01*
X1691078Y92808D01*
X1690037D01*
G01X1691078D02*
X1691703Y91600D01*
G01X1693970D02*
Y94100D01*
X1693470Y93600D01*
G01Y91600D02*
X1694470D01*
G01X1697070Y94100D02*
X1696737Y94017D01*
X1696487Y93808D01*
X1696320Y93558D01*
X1696195Y93225D01*
X1696153Y92850D01*
X1696195Y92475D01*
X1696320Y92142D01*
X1696487Y91892D01*
X1696737Y91683D01*
X1697070Y91600D01*
X1697403Y91683D01*
X1697653Y91892D01*
X1697820Y92142D01*
X1697945Y92475D01*
X1697987Y92850D01*
X1697945Y93225D01*
X1697820Y93558D01*
X1697653Y93808D01*
X1697403Y94017D01*
X1697070Y94100D01*
G01X1698920D02*
X1699503Y91600D01*
X1700170Y94100D01*
X1700837Y91600D01*
X1701420Y94100D01*
G01X1703770Y91600D02*
Y94100D01*
X1702228Y92308D01*
X1704312D01*
G01X1665700Y46597D02*
X1663200D01*
Y47638D01*
X1663325Y47972D01*
X1663492Y48180D01*
X1663825Y48263D01*
X1664158Y48180D01*
X1664367Y47930D01*
X1664492Y47638D01*
Y46597D01*
G01Y47638D02*
X1665700Y48263D01*
G01X1664658Y49738D02*
X1664367Y50030D01*
X1664200Y50280D01*
X1664117Y50613D01*
X1664200Y50905D01*
X1664367Y51113D01*
X1664617Y51280D01*
X1664908Y51322D01*
X1665158Y51280D01*
X1665408Y51113D01*
X1665617Y50863D01*
X1665700Y50572D01*
X1665617Y50238D01*
X1665367Y49947D01*
X1664992Y49780D01*
X1664575Y49738D01*
X1664033Y49822D01*
X1663742Y49947D01*
X1663450Y50155D01*
X1663242Y50447D01*
X1663200Y50738D01*
X1663283Y51030D01*
X1663492Y51238D01*
G01X1663200Y52380D02*
X1665700Y52963D01*
X1663200Y53630D01*
X1665700Y54297D01*
X1663200Y54880D01*
G01X1665700Y57230D02*
X1663200D01*
X1664992Y55688D01*
Y57772D01*
G01X1665700Y59830D02*
X1663200D01*
X1663700Y59330D01*
G01X1665700D02*
Y60330D01*
G01X1657290Y49807D02*
X1654790D01*
Y50848D01*
X1654915Y51182D01*
X1655082Y51390D01*
X1655415Y51473D01*
X1655748Y51390D01*
X1655957Y51140D01*
X1656082Y50848D01*
Y49807D01*
G01Y50848D02*
X1657290Y51473D01*
G01X1656998Y53032D02*
X1657207Y53323D01*
X1657290Y53657D01*
X1657207Y53990D01*
X1656957Y54282D01*
X1656582Y54490D01*
X1656207Y54573D01*
X1655748D01*
X1655373Y54490D01*
X1655040Y54282D01*
X1654873Y54032D01*
X1654790Y53740D01*
X1654873Y53407D01*
X1655040Y53157D01*
X1655290Y52990D01*
X1655623Y52907D01*
X1655915Y52990D01*
X1656207Y53198D01*
X1656373Y53448D01*
X1656415Y53740D01*
X1656332Y54073D01*
X1656123Y54323D01*
X1655748Y54573D01*
G01X1656040Y57090D02*
Y57923D01*
X1656790D01*
X1657040Y57673D01*
X1657207Y57382D01*
X1657290Y56965D01*
X1657207Y56548D01*
X1657040Y56257D01*
X1656790Y56007D01*
X1656498Y55840D01*
X1656165Y55757D01*
X1655873D01*
X1655623Y55840D01*
X1655332Y56007D01*
X1655082Y56257D01*
X1654915Y56507D01*
X1654790Y56840D01*
Y57132D01*
X1654873Y57465D01*
X1655040Y57715D01*
G01X1657290Y59940D02*
X1654790D01*
X1655290Y59440D01*
G01X1657290D02*
Y60440D01*
G01X1656915Y62123D02*
X1657123Y62373D01*
X1657248Y62665D01*
X1657290Y63040D01*
X1657207Y63415D01*
X1657040Y63707D01*
X1656748Y63915D01*
X1656415Y63957D01*
X1656082Y63873D01*
X1655873Y63665D01*
X1655707Y63373D01*
X1655665Y63082D01*
X1655707Y62790D01*
X1655873Y62415D01*
X1654790Y62540D01*
Y63665D01*
G01X1653890Y49807D02*
X1651390D01*
Y50848D01*
X1651515Y51182D01*
X1651682Y51390D01*
X1652015Y51473D01*
X1652348Y51390D01*
X1652557Y51140D01*
X1652682Y50848D01*
Y49807D01*
G01Y50848D02*
X1653890Y51473D01*
G01X1653598Y53032D02*
X1653807Y53323D01*
X1653890Y53657D01*
X1653807Y53990D01*
X1653557Y54282D01*
X1653182Y54490D01*
X1652807Y54573D01*
X1652348D01*
X1651973Y54490D01*
X1651640Y54282D01*
X1651473Y54032D01*
X1651390Y53740D01*
X1651473Y53407D01*
X1651640Y53157D01*
X1651890Y52990D01*
X1652223Y52907D01*
X1652515Y52990D01*
X1652807Y53198D01*
X1652973Y53448D01*
X1653015Y53740D01*
X1652932Y54073D01*
X1652723Y54323D01*
X1652348Y54573D01*
G01X1652640Y57090D02*
Y57923D01*
X1653390D01*
X1653640Y57673D01*
X1653807Y57382D01*
X1653890Y56965D01*
X1653807Y56548D01*
X1653640Y56257D01*
X1653390Y56007D01*
X1653098Y55840D01*
X1652765Y55757D01*
X1652473D01*
X1652223Y55840D01*
X1651932Y56007D01*
X1651682Y56257D01*
X1651515Y56507D01*
X1651390Y56840D01*
Y57132D01*
X1651473Y57465D01*
X1651640Y57715D01*
G01X1653890Y59940D02*
X1651390D01*
X1651890Y59440D01*
G01X1653890D02*
Y60440D01*
G01Y63540D02*
X1651390D01*
X1653182Y61998D01*
Y64082D01*
G01X1696533Y90750D02*
Y88958D01*
X1696700Y88583D01*
X1697033Y88333D01*
X1697450Y88250D01*
X1697867Y88333D01*
X1698200Y88583D01*
X1698367Y88958D01*
Y90750D01*
G01X1700550Y88250D02*
Y90750D01*
X1700050Y90250D01*
G01Y88250D02*
X1701050D01*
G01X1703650Y90750D02*
X1703317Y90667D01*
X1703067Y90458D01*
X1702900Y90208D01*
X1702775Y89875D01*
X1702733Y89500D01*
X1702775Y89125D01*
X1702900Y88792D01*
X1703067Y88542D01*
X1703317Y88333D01*
X1703650Y88250D01*
X1703983Y88333D01*
X1704233Y88542D01*
X1704400Y88792D01*
X1704525Y89125D01*
X1704567Y89500D01*
X1704525Y89875D01*
X1704400Y90208D01*
X1704233Y90458D01*
X1703983Y90667D01*
X1703650Y90750D01*
G01X1705500D02*
X1706083Y88250D01*
X1706750Y90750D01*
X1707417Y88250D01*
X1708000Y90750D01*
G01X1709850Y88250D02*
Y90750D01*
X1709350Y90250D01*
G01Y88250D02*
X1710350D01*
G01X1707228Y40567D02*
X1707103Y40317D01*
X1707020Y40025D01*
Y39692D01*
X1707145Y39317D01*
X1707353Y39025D01*
X1707603Y38817D01*
X1708020Y38650D01*
X1708395Y38608D01*
X1708770Y38692D01*
X1709020Y38817D01*
X1709270Y39067D01*
X1709437Y39358D01*
X1709520Y39650D01*
Y39942D01*
X1709437Y40233D01*
X1709312Y40483D01*
X1709145Y40692D01*
G01X1708478Y41958D02*
X1708187Y42250D01*
X1708020Y42500D01*
X1707937Y42833D01*
X1708020Y43125D01*
X1708187Y43333D01*
X1708437Y43500D01*
X1708728Y43542D01*
X1708978Y43500D01*
X1709228Y43333D01*
X1709437Y43083D01*
X1709520Y42792D01*
X1709437Y42458D01*
X1709187Y42167D01*
X1708812Y42000D01*
X1708395Y41958D01*
X1707853Y42042D01*
X1707562Y42167D01*
X1707270Y42375D01*
X1707062Y42667D01*
X1707020Y42958D01*
X1707103Y43250D01*
X1707312Y43458D01*
G01X1707020Y44600D02*
X1709520Y45183D01*
X1707020Y45850D01*
X1709520Y46517D01*
X1707020Y47100D01*
G01X1709520Y48950D02*
X1707020D01*
X1707520Y48450D01*
G01X1709520D02*
Y49450D01*
G01Y52550D02*
X1707020D01*
X1708812Y51008D01*
Y53092D01*
G01X1680017Y77322D02*
X1679767Y77447D01*
X1679475Y77530D01*
X1679142D01*
X1678767Y77405D01*
X1678475Y77197D01*
X1678267Y76947D01*
X1678100Y76530D01*
X1678058Y76155D01*
X1678142Y75780D01*
X1678267Y75530D01*
X1678517Y75280D01*
X1678808Y75113D01*
X1679100Y75030D01*
X1679392D01*
X1679683Y75113D01*
X1679933Y75238D01*
X1680142Y75405D01*
G01X1681367Y75030D02*
Y77530D01*
X1682408D01*
X1682742Y77405D01*
X1682950Y77238D01*
X1683033Y76905D01*
X1682950Y76572D01*
X1682700Y76363D01*
X1682408Y76238D01*
X1681367D01*
G01X1682408D02*
X1683033Y75030D01*
G01X1685300D02*
Y77530D01*
X1684800Y77030D01*
G01Y75030D02*
X1685800D01*
G01X1688400Y77530D02*
X1688067Y77447D01*
X1687817Y77238D01*
X1687650Y76988D01*
X1687525Y76655D01*
X1687483Y76280D01*
X1687525Y75905D01*
X1687650Y75572D01*
X1687817Y75322D01*
X1688067Y75113D01*
X1688400Y75030D01*
X1688733Y75113D01*
X1688983Y75322D01*
X1689150Y75572D01*
X1689275Y75905D01*
X1689317Y76280D01*
X1689275Y76655D01*
X1689150Y76988D01*
X1688983Y77238D01*
X1688733Y77447D01*
X1688400Y77530D01*
G01X1690250D02*
X1690833Y75030D01*
X1691500Y77530D01*
X1692167Y75030D01*
X1692750Y77530D01*
G01X1693808Y77113D02*
X1694058Y77363D01*
X1694350Y77488D01*
X1694683Y77530D01*
X1695100Y77447D01*
X1695392Y77238D01*
X1695475Y76988D01*
X1695433Y76738D01*
X1695267Y76530D01*
X1694433Y76113D01*
X1694058Y75822D01*
X1693808Y75405D01*
X1693725Y75030D01*
X1695475D01*
G01X1687651Y86843D02*
X1692074D01*
G01Y88736D02*
Y84950D01*
G01X1698942Y86843D02*
X1695353D01*
Y84950D01*
X1692074Y86843D01*
X1695353Y88736D01*
Y86843D01*
G01X1675540Y46193D02*
X1677332D01*
X1677707Y46360D01*
X1677957Y46693D01*
X1678040Y47110D01*
X1677957Y47527D01*
X1677707Y47860D01*
X1677332Y48027D01*
X1675540D01*
G01X1676998Y49418D02*
X1676707Y49710D01*
X1676540Y49960D01*
X1676457Y50293D01*
X1676540Y50585D01*
X1676707Y50793D01*
X1676957Y50960D01*
X1677248Y51002D01*
X1677498Y50960D01*
X1677748Y50793D01*
X1677957Y50543D01*
X1678040Y50252D01*
X1677957Y49918D01*
X1677707Y49627D01*
X1677332Y49460D01*
X1676915Y49418D01*
X1676373Y49502D01*
X1676082Y49627D01*
X1675790Y49835D01*
X1675582Y50127D01*
X1675540Y50418D01*
X1675623Y50710D01*
X1675832Y50918D01*
G01X1675540Y52060D02*
X1678040Y52643D01*
X1675540Y53310D01*
X1678040Y53977D01*
X1675540Y54560D01*
G01X1678040Y56410D02*
X1675540D01*
X1676040Y55910D01*
G01X1678040D02*
Y56910D01*
G01Y59510D02*
X1675540D01*
X1676040Y59010D01*
G01X1678040D02*
Y60010D01*
G01X1701120Y57500D02*
X1703320Y59700D01*
G01X1701120Y57500D02*
X1703320Y55300D01*
G01Y50500D02*
Y64500D01*
G01X1681820D02*
X1702620D01*
G01X1681820Y50500D02*
Y64500D01*
G01X1703320Y50500D02*
X1681820D01*
G01X1678947Y136000D02*
Y138500D01*
X1679988D01*
X1680322Y138375D01*
X1680530Y138208D01*
X1680613Y137875D01*
X1680530Y137542D01*
X1680280Y137333D01*
X1679988Y137208D01*
X1678947D01*
G01X1679988D02*
X1680613Y136000D01*
G01X1682880D02*
Y138500D01*
X1682380Y138000D01*
G01Y136000D02*
X1683380D01*
G01X1685980Y138500D02*
Y136000D01*
G01X1685022Y138500D02*
X1686938D01*
G01X1688288Y138083D02*
X1688538Y138333D01*
X1688830Y138458D01*
X1689163Y138500D01*
X1689580Y138417D01*
X1689872Y138208D01*
X1689955Y137958D01*
X1689913Y137708D01*
X1689747Y137500D01*
X1688913Y137083D01*
X1688538Y136792D01*
X1688288Y136375D01*
X1688205Y136000D01*
X1689955D01*
G01X1692097D02*
X1692180Y136542D01*
X1692305Y137000D01*
X1692472Y137417D01*
X1692680Y137875D01*
X1693013Y138500D01*
X1691347D01*
G01X1707790Y96647D02*
X1705290D01*
Y97688D01*
X1705415Y98022D01*
X1705582Y98230D01*
X1705915Y98313D01*
X1706248Y98230D01*
X1706457Y97980D01*
X1706582Y97688D01*
Y96647D01*
G01Y97688D02*
X1707790Y98313D01*
G01X1705707Y99788D02*
X1705457Y100038D01*
X1705332Y100330D01*
X1705290Y100663D01*
X1705373Y101080D01*
X1705582Y101372D01*
X1705832Y101455D01*
X1706082Y101413D01*
X1706290Y101247D01*
X1706707Y100413D01*
X1706998Y100038D01*
X1707415Y99788D01*
X1707790Y99705D01*
Y101455D01*
G01X1707415Y102763D02*
X1707623Y103013D01*
X1707748Y103305D01*
X1707790Y103680D01*
X1707707Y104055D01*
X1707540Y104347D01*
X1707248Y104555D01*
X1706915Y104597D01*
X1706582Y104513D01*
X1706373Y104305D01*
X1706207Y104013D01*
X1706165Y103722D01*
X1706207Y103430D01*
X1706373Y103055D01*
X1705290Y103180D01*
Y104305D01*
G01Y105530D02*
X1707790Y106113D01*
X1705290Y106780D01*
X1707790Y107447D01*
X1705290Y108030D01*
G01X1707790Y109880D02*
X1705290D01*
X1705790Y109380D01*
G01X1707790D02*
Y110380D01*
G01X1707415Y112063D02*
X1707623Y112313D01*
X1707748Y112605D01*
X1707790Y112980D01*
X1707707Y113355D01*
X1707540Y113647D01*
X1707248Y113855D01*
X1706915Y113897D01*
X1706582Y113813D01*
X1706373Y113605D01*
X1706207Y113313D01*
X1706165Y113022D01*
X1706207Y112730D01*
X1706373Y112355D01*
X1705290Y112480D01*
Y113605D01*
G01X1707790Y115997D02*
X1707248Y116080D01*
X1706790Y116205D01*
X1706373Y116372D01*
X1705915Y116580D01*
X1705290Y116913D01*
Y115247D01*
G01X1704290Y96647D02*
X1701790D01*
Y97688D01*
X1701915Y98022D01*
X1702082Y98230D01*
X1702415Y98313D01*
X1702748Y98230D01*
X1702957Y97980D01*
X1703082Y97688D01*
Y96647D01*
G01Y97688D02*
X1704290Y98313D01*
G01Y100580D02*
X1701790D01*
X1702290Y100080D01*
G01X1704290D02*
Y101080D01*
G01X1701790Y103680D02*
X1704290D01*
G01X1701790Y102722D02*
Y104638D01*
G01X1702207Y105988D02*
X1701957Y106238D01*
X1701832Y106530D01*
X1701790Y106863D01*
X1701873Y107280D01*
X1702082Y107572D01*
X1702332Y107655D01*
X1702582Y107613D01*
X1702790Y107447D01*
X1703207Y106613D01*
X1703498Y106238D01*
X1703915Y105988D01*
X1704290Y105905D01*
Y107655D01*
G01Y110380D02*
X1701790D01*
X1703582Y108838D01*
Y110922D01*
G01X1703790Y118107D02*
X1701290D01*
Y119148D01*
X1701415Y119482D01*
X1701582Y119690D01*
X1701915Y119773D01*
X1702248Y119690D01*
X1702457Y119440D01*
X1702582Y119148D01*
Y118107D01*
G01Y119148D02*
X1703790Y119773D01*
G01X1701707Y121248D02*
X1701457Y121498D01*
X1701332Y121790D01*
X1701290Y122123D01*
X1701373Y122540D01*
X1701582Y122832D01*
X1701832Y122915D01*
X1702082Y122873D01*
X1702290Y122707D01*
X1702707Y121873D01*
X1702998Y121498D01*
X1703415Y121248D01*
X1703790Y121165D01*
Y122915D01*
G01X1703415Y124223D02*
X1703623Y124473D01*
X1703748Y124765D01*
X1703790Y125140D01*
X1703707Y125515D01*
X1703540Y125807D01*
X1703248Y126015D01*
X1702915Y126057D01*
X1702582Y125973D01*
X1702373Y125765D01*
X1702207Y125473D01*
X1702165Y125182D01*
X1702207Y124890D01*
X1702373Y124515D01*
X1701290Y124640D01*
Y125765D01*
G01Y126990D02*
X1703790Y127573D01*
X1701290Y128240D01*
X1703790Y128907D01*
X1701290Y129490D01*
G01X1703790Y131340D02*
X1701290D01*
X1701790Y130840D01*
G01X1703790D02*
Y131840D01*
G01Y134440D02*
X1701290D01*
X1701790Y133940D01*
G01X1703790D02*
Y134940D01*
G01Y137457D02*
X1703248Y137540D01*
X1702790Y137665D01*
X1702373Y137832D01*
X1701915Y138040D01*
X1701290Y138373D01*
Y136707D01*
G01X1698400Y153817D02*
X1695900D01*
Y154858D01*
X1696025Y155192D01*
X1696192Y155400D01*
X1696525Y155483D01*
X1696858Y155400D01*
X1697067Y155150D01*
X1697192Y154858D01*
Y153817D01*
G01Y154858D02*
X1698400Y155483D01*
G01X1698108Y157042D02*
X1698317Y157333D01*
X1698400Y157667D01*
X1698317Y158000D01*
X1698067Y158292D01*
X1697692Y158500D01*
X1697317Y158583D01*
X1696858D01*
X1696483Y158500D01*
X1696150Y158292D01*
X1695983Y158042D01*
X1695900Y157750D01*
X1695983Y157417D01*
X1696150Y157167D01*
X1696400Y157000D01*
X1696733Y156917D01*
X1697025Y157000D01*
X1697317Y157208D01*
X1697483Y157458D01*
X1697525Y157750D01*
X1697442Y158083D01*
X1697233Y158333D01*
X1696858Y158583D01*
G01X1698400Y160058D02*
X1695900D01*
Y161642D01*
G01X1697108Y161058D02*
Y160058D01*
G01X1697358Y163158D02*
X1697067Y163450D01*
X1696900Y163700D01*
X1696817Y164033D01*
X1696900Y164325D01*
X1697067Y164533D01*
X1697317Y164700D01*
X1697608Y164742D01*
X1697858Y164700D01*
X1698108Y164533D01*
X1698317Y164283D01*
X1698400Y163992D01*
X1698317Y163658D01*
X1698067Y163367D01*
X1697692Y163200D01*
X1697275Y163158D01*
X1696733Y163242D01*
X1696442Y163367D01*
X1696150Y163575D01*
X1695942Y163867D01*
X1695900Y164158D01*
X1695983Y164450D01*
X1696192Y164658D01*
G01X1696317Y166258D02*
X1696067Y166508D01*
X1695942Y166800D01*
X1695900Y167133D01*
X1695983Y167550D01*
X1696192Y167842D01*
X1696442Y167925D01*
X1696692Y167883D01*
X1696900Y167717D01*
X1697317Y166883D01*
X1697608Y166508D01*
X1698025Y166258D01*
X1698400Y166175D01*
Y167925D01*
G01X1706850Y149067D02*
X1704350D01*
Y150108D01*
X1704475Y150442D01*
X1704642Y150650D01*
X1704975Y150733D01*
X1705308Y150650D01*
X1705517Y150400D01*
X1705642Y150108D01*
Y149067D01*
G01Y150108D02*
X1706850Y150733D01*
G01X1706558Y152292D02*
X1706767Y152583D01*
X1706850Y152917D01*
X1706767Y153250D01*
X1706517Y153542D01*
X1706142Y153750D01*
X1705767Y153833D01*
X1705308D01*
X1704933Y153750D01*
X1704600Y153542D01*
X1704433Y153292D01*
X1704350Y153000D01*
X1704433Y152667D01*
X1704600Y152417D01*
X1704850Y152250D01*
X1705183Y152167D01*
X1705475Y152250D01*
X1705767Y152458D01*
X1705933Y152708D01*
X1705975Y153000D01*
X1705892Y153333D01*
X1705683Y153583D01*
X1705308Y153833D01*
G01X1706850Y155308D02*
X1704350D01*
Y156892D01*
G01X1705558Y156308D02*
Y155308D01*
G01X1706350Y158283D02*
X1706642Y158533D01*
X1706808Y158867D01*
X1706850Y159242D01*
X1706808Y159575D01*
X1706600Y159908D01*
X1706350Y160117D01*
X1706100Y160158D01*
X1705808Y160075D01*
X1705600Y159783D01*
X1705517Y159492D01*
Y159117D01*
G01Y159492D02*
X1705392Y159742D01*
X1705183Y159950D01*
X1704933Y160033D01*
X1704683Y159950D01*
X1704475Y159742D01*
X1704350Y159367D01*
X1704392Y158992D01*
X1704558Y158617D01*
G01X1706350Y161383D02*
X1706642Y161633D01*
X1706808Y161967D01*
X1706850Y162342D01*
X1706808Y162675D01*
X1706600Y163008D01*
X1706350Y163217D01*
X1706100Y163258D01*
X1705808Y163175D01*
X1705600Y162883D01*
X1705517Y162592D01*
Y162217D01*
G01Y162592D02*
X1705392Y162842D01*
X1705183Y163050D01*
X1704933Y163133D01*
X1704683Y163050D01*
X1704475Y162842D01*
X1704350Y162467D01*
X1704392Y162092D01*
X1704558Y161717D01*
G01X1702650Y154867D02*
X1700150D01*
Y155908D01*
X1700275Y156242D01*
X1700442Y156450D01*
X1700775Y156533D01*
X1701108Y156450D01*
X1701317Y156200D01*
X1701442Y155908D01*
Y154867D01*
G01Y155908D02*
X1702650Y156533D01*
G01X1700567Y158008D02*
X1700317Y158258D01*
X1700192Y158550D01*
X1700150Y158883D01*
X1700233Y159300D01*
X1700442Y159592D01*
X1700692Y159675D01*
X1700942Y159633D01*
X1701150Y159467D01*
X1701567Y158633D01*
X1701858Y158258D01*
X1702275Y158008D01*
X1702650Y157925D01*
Y159675D01*
G01X1702275Y160983D02*
X1702483Y161233D01*
X1702608Y161525D01*
X1702650Y161900D01*
X1702567Y162275D01*
X1702400Y162567D01*
X1702108Y162775D01*
X1701775Y162817D01*
X1701442Y162733D01*
X1701233Y162525D01*
X1701067Y162233D01*
X1701025Y161942D01*
X1701067Y161650D01*
X1701233Y161275D01*
X1700150Y161400D01*
Y162525D01*
G01Y163750D02*
X1702650Y164333D01*
X1700150Y165000D01*
X1702650Y165667D01*
X1700150Y166250D01*
G01X1702358Y167392D02*
X1702567Y167683D01*
X1702650Y168017D01*
X1702567Y168350D01*
X1702317Y168642D01*
X1701942Y168850D01*
X1701567Y168933D01*
X1701108D01*
X1700733Y168850D01*
X1700400Y168642D01*
X1700233Y168392D01*
X1700150Y168100D01*
X1700233Y167767D01*
X1700400Y167517D01*
X1700650Y167350D01*
X1700983Y167267D01*
X1701275Y167350D01*
X1701567Y167558D01*
X1701733Y167808D01*
X1701775Y168100D01*
X1701692Y168433D01*
X1701483Y168683D01*
X1701108Y168933D01*
G01X1702275Y170283D02*
X1702483Y170533D01*
X1702608Y170825D01*
X1702650Y171200D01*
X1702567Y171575D01*
X1702400Y171867D01*
X1702108Y172075D01*
X1701775Y172117D01*
X1701442Y172033D01*
X1701233Y171825D01*
X1701067Y171533D01*
X1701025Y171242D01*
X1701067Y170950D01*
X1701233Y170575D01*
X1700150Y170700D01*
Y171825D01*
G01X1710350Y149067D02*
X1707850D01*
Y150108D01*
X1707975Y150442D01*
X1708142Y150650D01*
X1708475Y150733D01*
X1708808Y150650D01*
X1709017Y150400D01*
X1709142Y150108D01*
Y149067D01*
G01Y150108D02*
X1710350Y150733D01*
G01X1710058Y152292D02*
X1710267Y152583D01*
X1710350Y152917D01*
X1710267Y153250D01*
X1710017Y153542D01*
X1709642Y153750D01*
X1709267Y153833D01*
X1708808D01*
X1708433Y153750D01*
X1708100Y153542D01*
X1707933Y153292D01*
X1707850Y153000D01*
X1707933Y152667D01*
X1708100Y152417D01*
X1708350Y152250D01*
X1708683Y152167D01*
X1708975Y152250D01*
X1709267Y152458D01*
X1709433Y152708D01*
X1709475Y153000D01*
X1709392Y153333D01*
X1709183Y153583D01*
X1708808Y153833D01*
G01X1710350Y155308D02*
X1707850D01*
Y156892D01*
G01X1709058Y156308D02*
Y155308D01*
G01X1708267Y158408D02*
X1708017Y158658D01*
X1707892Y158950D01*
X1707850Y159283D01*
X1707933Y159700D01*
X1708142Y159992D01*
X1708392Y160075D01*
X1708642Y160033D01*
X1708850Y159867D01*
X1709267Y159033D01*
X1709558Y158658D01*
X1709975Y158408D01*
X1710350Y158325D01*
Y160075D01*
G01X1707850Y162300D02*
X1707933Y161967D01*
X1708142Y161717D01*
X1708392Y161550D01*
X1708725Y161425D01*
X1709100Y161383D01*
X1709475Y161425D01*
X1709808Y161550D01*
X1710058Y161717D01*
X1710267Y161967D01*
X1710350Y162300D01*
X1710267Y162633D01*
X1710058Y162883D01*
X1709808Y163050D01*
X1709475Y163175D01*
X1709100Y163217D01*
X1708725Y163175D01*
X1708392Y163050D01*
X1708142Y162883D01*
X1707933Y162633D01*
X1707850Y162300D01*
G01X1657000Y194900D02*
X1651400D01*
G01X1665600D02*
X1679700D01*
G01X1663100D02*
X1659400D01*
G01X1711600Y180800D02*
X1720700D01*
G01X1711600D02*
Y171450D01*
G01Y164350D02*
Y157000D01*
X1750600D01*
Y120100D01*
X1769500D01*
Y108100D01*
X1786500D01*
G01X1668417Y211367D02*
Y213867D01*
X1669458D01*
X1669792Y213742D01*
X1670000Y213575D01*
X1670083Y213242D01*
X1670000Y212909D01*
X1669750Y212700D01*
X1669458Y212575D01*
X1668417D01*
G01X1669458D02*
X1670083Y211367D01*
G01X1672350D02*
Y213867D01*
X1671850Y213367D01*
G01Y211367D02*
X1672850D01*
G01X1674200Y213867D02*
X1674783Y211367D01*
X1675450Y213867D01*
X1676117Y211367D01*
X1676700Y213867D01*
G01X1678467Y211367D02*
X1678550Y211909D01*
X1678675Y212367D01*
X1678842Y212784D01*
X1679050Y213242D01*
X1679383Y213867D01*
X1677717D01*
G01X1694820Y158037D02*
X1692320D01*
Y159078D01*
X1692445Y159412D01*
X1692612Y159620D01*
X1692945Y159703D01*
X1693278Y159620D01*
X1693487Y159370D01*
X1693612Y159078D01*
Y158037D01*
G01Y159078D02*
X1694820Y159703D01*
G01X1694528Y161262D02*
X1694737Y161553D01*
X1694820Y161887D01*
X1694737Y162220D01*
X1694487Y162512D01*
X1694112Y162720D01*
X1693737Y162803D01*
X1693278D01*
X1692903Y162720D01*
X1692570Y162512D01*
X1692403Y162262D01*
X1692320Y161970D01*
X1692403Y161637D01*
X1692570Y161387D01*
X1692820Y161220D01*
X1693153Y161137D01*
X1693445Y161220D01*
X1693737Y161428D01*
X1693903Y161678D01*
X1693945Y161970D01*
X1693862Y162303D01*
X1693653Y162553D01*
X1693278Y162803D01*
G01X1694820Y164278D02*
X1692320D01*
Y165862D01*
G01X1693528Y165278D02*
Y164278D01*
G01X1693778Y167378D02*
X1693487Y167670D01*
X1693320Y167920D01*
X1693237Y168253D01*
X1693320Y168545D01*
X1693487Y168753D01*
X1693737Y168920D01*
X1694028Y168962D01*
X1694278Y168920D01*
X1694528Y168753D01*
X1694737Y168503D01*
X1694820Y168212D01*
X1694737Y167878D01*
X1694487Y167587D01*
X1694112Y167420D01*
X1693695Y167378D01*
X1693153Y167462D01*
X1692862Y167587D01*
X1692570Y167795D01*
X1692362Y168087D01*
X1692320Y168378D01*
X1692403Y168670D01*
X1692612Y168878D01*
G01X1692320Y171270D02*
X1692403Y170937D01*
X1692612Y170687D01*
X1692862Y170520D01*
X1693195Y170395D01*
X1693570Y170353D01*
X1693945Y170395D01*
X1694278Y170520D01*
X1694528Y170687D01*
X1694737Y170937D01*
X1694820Y171270D01*
X1694737Y171603D01*
X1694528Y171853D01*
X1694278Y172020D01*
X1693945Y172145D01*
X1693570Y172187D01*
X1693195Y172145D01*
X1692862Y172020D01*
X1692612Y171853D01*
X1692403Y171603D01*
X1692320Y171270D01*
G01X1690050Y158267D02*
X1687550D01*
Y159308D01*
X1687675Y159642D01*
X1687842Y159850D01*
X1688175Y159933D01*
X1688508Y159850D01*
X1688717Y159600D01*
X1688842Y159308D01*
Y158267D01*
G01Y159308D02*
X1690050Y159933D01*
G01X1687967Y161408D02*
X1687717Y161658D01*
X1687592Y161950D01*
X1687550Y162283D01*
X1687633Y162700D01*
X1687842Y162992D01*
X1688092Y163075D01*
X1688342Y163033D01*
X1688550Y162867D01*
X1688967Y162033D01*
X1689258Y161658D01*
X1689675Y161408D01*
X1690050Y161325D01*
Y163075D01*
G01X1689675Y164383D02*
X1689883Y164633D01*
X1690008Y164925D01*
X1690050Y165300D01*
X1689967Y165675D01*
X1689800Y165967D01*
X1689508Y166175D01*
X1689175Y166217D01*
X1688842Y166133D01*
X1688633Y165925D01*
X1688467Y165633D01*
X1688425Y165342D01*
X1688467Y165050D01*
X1688633Y164675D01*
X1687550Y164800D01*
Y165925D01*
G01Y167150D02*
X1690050Y167733D01*
X1687550Y168400D01*
X1690050Y169067D01*
X1687550Y169650D01*
G01X1690050Y171500D02*
X1690008Y171792D01*
X1689883Y172125D01*
X1689675Y172333D01*
X1689383Y172417D01*
X1689092Y172333D01*
X1688842Y172083D01*
X1688717Y171708D01*
Y171292D01*
X1688633Y171042D01*
X1688425Y170833D01*
X1688133Y170750D01*
X1687842Y170875D01*
X1687633Y171167D01*
X1687550Y171500D01*
X1687633Y171833D01*
X1687842Y172125D01*
X1688133Y172250D01*
X1688425Y172167D01*
X1688633Y171958D01*
X1688717Y171708D01*
Y171292D01*
X1688842Y170917D01*
X1689092Y170667D01*
X1689383Y170583D01*
X1689675Y170667D01*
X1689883Y170875D01*
X1690008Y171208D01*
X1690050Y171500D01*
G01Y174600D02*
X1687550D01*
X1688050Y174100D01*
G01X1690050D02*
Y175100D01*
G01X1685590Y158297D02*
X1683090D01*
Y159338D01*
X1683215Y159672D01*
X1683382Y159880D01*
X1683715Y159963D01*
X1684048Y159880D01*
X1684257Y159630D01*
X1684382Y159338D01*
Y158297D01*
G01Y159338D02*
X1685590Y159963D01*
G01X1683507Y161438D02*
X1683257Y161688D01*
X1683132Y161980D01*
X1683090Y162313D01*
X1683173Y162730D01*
X1683382Y163022D01*
X1683632Y163105D01*
X1683882Y163063D01*
X1684090Y162897D01*
X1684507Y162063D01*
X1684798Y161688D01*
X1685215Y161438D01*
X1685590Y161355D01*
Y163105D01*
G01X1685215Y164413D02*
X1685423Y164663D01*
X1685548Y164955D01*
X1685590Y165330D01*
X1685507Y165705D01*
X1685340Y165997D01*
X1685048Y166205D01*
X1684715Y166247D01*
X1684382Y166163D01*
X1684173Y165955D01*
X1684007Y165663D01*
X1683965Y165372D01*
X1684007Y165080D01*
X1684173Y164705D01*
X1683090Y164830D01*
Y165955D01*
G01Y167180D02*
X1685590Y167763D01*
X1683090Y168430D01*
X1685590Y169097D01*
X1683090Y169680D01*
G01X1685590Y171447D02*
X1685048Y171530D01*
X1684590Y171655D01*
X1684173Y171822D01*
X1683715Y172030D01*
X1683090Y172363D01*
Y170697D01*
G01X1685590Y174630D02*
X1685548Y174922D01*
X1685423Y175255D01*
X1685215Y175463D01*
X1684923Y175547D01*
X1684632Y175463D01*
X1684382Y175213D01*
X1684257Y174838D01*
Y174422D01*
X1684173Y174172D01*
X1683965Y173963D01*
X1683673Y173880D01*
X1683382Y174005D01*
X1683173Y174297D01*
X1683090Y174630D01*
X1683173Y174963D01*
X1683382Y175255D01*
X1683673Y175380D01*
X1683965Y175297D01*
X1684173Y175088D01*
X1684257Y174838D01*
Y174422D01*
X1684382Y174047D01*
X1684632Y173797D01*
X1684923Y173713D01*
X1685215Y173797D01*
X1685423Y174005D01*
X1685548Y174338D01*
X1685590Y174630D01*
G01X1696639Y201536D02*
X1694139D01*
Y202577D01*
X1694264Y202911D01*
X1694431Y203119D01*
X1694764Y203202D01*
X1695097Y203119D01*
X1695306Y202869D01*
X1695431Y202577D01*
Y201536D01*
G01Y202577D02*
X1696639Y203202D01*
G01X1696347Y204761D02*
X1696556Y205052D01*
X1696639Y205386D01*
X1696556Y205719D01*
X1696306Y206011D01*
X1695931Y206219D01*
X1695556Y206302D01*
X1695097D01*
X1694722Y206219D01*
X1694389Y206011D01*
X1694222Y205761D01*
X1694139Y205469D01*
X1694222Y205136D01*
X1694389Y204886D01*
X1694639Y204719D01*
X1694972Y204636D01*
X1695264Y204719D01*
X1695556Y204927D01*
X1695722Y205177D01*
X1695764Y205469D01*
X1695681Y205802D01*
X1695472Y206052D01*
X1695097Y206302D01*
G01X1696639Y207777D02*
X1694139D01*
Y209361D01*
G01X1695347Y208777D02*
Y207777D01*
G01X1695597Y210877D02*
X1695306Y211169D01*
X1695139Y211419D01*
X1695056Y211752D01*
X1695139Y212044D01*
X1695306Y212252D01*
X1695556Y212419D01*
X1695847Y212461D01*
X1696097Y212419D01*
X1696347Y212252D01*
X1696556Y212002D01*
X1696639Y211711D01*
X1696556Y211377D01*
X1696306Y211086D01*
X1695931Y210919D01*
X1695514Y210877D01*
X1694972Y210961D01*
X1694681Y211086D01*
X1694389Y211294D01*
X1694181Y211586D01*
X1694139Y211877D01*
X1694222Y212169D01*
X1694431Y212377D01*
G01X1696639Y214769D02*
X1694139D01*
X1694639Y214269D01*
G01X1696639D02*
Y215269D01*
G01X1663174Y216145D02*
X1664966D01*
X1665341Y216312D01*
X1665591Y216645D01*
X1665674Y217062D01*
X1665591Y217479D01*
X1665341Y217812D01*
X1664966Y217979D01*
X1663174D01*
G01X1665674Y220162D02*
X1665632Y220454D01*
X1665507Y220787D01*
X1665299Y220995D01*
X1665007Y221079D01*
X1664716Y220995D01*
X1664466Y220745D01*
X1664341Y220370D01*
Y219954D01*
X1664257Y219704D01*
X1664049Y219495D01*
X1663757Y219412D01*
X1663466Y219537D01*
X1663257Y219829D01*
X1663174Y220162D01*
X1663257Y220495D01*
X1663466Y220787D01*
X1663757Y220912D01*
X1664049Y220829D01*
X1664257Y220620D01*
X1664341Y220370D01*
Y219954D01*
X1664466Y219579D01*
X1664716Y219329D01*
X1665007Y219245D01*
X1665299Y219329D01*
X1665507Y219537D01*
X1665632Y219870D01*
X1665674Y220162D01*
G01Y224095D02*
Y222429D01*
X1663174D01*
Y224095D01*
G01X1664382Y223429D02*
Y222429D01*
G01X1665174Y225445D02*
X1665466Y225695D01*
X1665632Y226029D01*
X1665674Y226404D01*
X1665632Y226737D01*
X1665424Y227070D01*
X1665174Y227279D01*
X1664924Y227320D01*
X1664632Y227237D01*
X1664424Y226945D01*
X1664341Y226654D01*
Y226279D01*
G01Y226654D02*
X1664216Y226904D01*
X1664007Y227112D01*
X1663757Y227195D01*
X1663507Y227112D01*
X1663299Y226904D01*
X1663174Y226529D01*
X1663216Y226154D01*
X1663382Y225779D01*
G01X1667494Y217791D02*
X1667369Y217541D01*
X1667286Y217249D01*
Y216916D01*
X1667411Y216541D01*
X1667619Y216249D01*
X1667869Y216041D01*
X1668286Y215874D01*
X1668661Y215832D01*
X1669036Y215916D01*
X1669286Y216041D01*
X1669536Y216291D01*
X1669703Y216582D01*
X1669786Y216874D01*
Y217166D01*
X1669703Y217457D01*
X1669578Y217707D01*
X1669411Y217916D01*
G01X1669786Y219974D02*
X1669744Y220266D01*
X1669619Y220599D01*
X1669411Y220807D01*
X1669119Y220891D01*
X1668828Y220807D01*
X1668578Y220557D01*
X1668453Y220182D01*
Y219766D01*
X1668369Y219516D01*
X1668161Y219307D01*
X1667869Y219224D01*
X1667578Y219349D01*
X1667369Y219641D01*
X1667286Y219974D01*
X1667369Y220307D01*
X1667578Y220599D01*
X1667869Y220724D01*
X1668161Y220641D01*
X1668369Y220432D01*
X1668453Y220182D01*
Y219766D01*
X1668578Y219391D01*
X1668828Y219141D01*
X1669119Y219057D01*
X1669411Y219141D01*
X1669619Y219349D01*
X1669744Y219682D01*
X1669786Y219974D01*
G01Y223907D02*
Y222241D01*
X1667286D01*
Y223907D01*
G01X1668494Y223241D02*
Y222241D01*
G01X1669786Y226174D02*
X1669744Y226466D01*
X1669619Y226799D01*
X1669411Y227007D01*
X1669119Y227091D01*
X1668828Y227007D01*
X1668578Y226757D01*
X1668453Y226382D01*
Y225966D01*
X1668369Y225716D01*
X1668161Y225507D01*
X1667869Y225424D01*
X1667578Y225549D01*
X1667369Y225841D01*
X1667286Y226174D01*
X1667369Y226507D01*
X1667578Y226799D01*
X1667869Y226924D01*
X1668161Y226841D01*
X1668369Y226632D01*
X1668453Y226382D01*
Y225966D01*
X1668578Y225591D01*
X1668828Y225341D01*
X1669119Y225257D01*
X1669411Y225341D01*
X1669619Y225549D01*
X1669744Y225882D01*
X1669786Y226174D01*
G01X1700034Y203286D02*
X1699909Y203036D01*
X1699826Y202744D01*
Y202411D01*
X1699951Y202036D01*
X1700159Y201744D01*
X1700409Y201536D01*
X1700826Y201369D01*
X1701201Y201327D01*
X1701576Y201411D01*
X1701826Y201536D01*
X1702076Y201786D01*
X1702243Y202077D01*
X1702326Y202369D01*
Y202661D01*
X1702243Y202952D01*
X1702118Y203202D01*
X1701951Y203411D01*
G01X1702034Y204761D02*
X1702243Y205052D01*
X1702326Y205386D01*
X1702243Y205719D01*
X1701993Y206011D01*
X1701618Y206219D01*
X1701243Y206302D01*
X1700784D01*
X1700409Y206219D01*
X1700076Y206011D01*
X1699909Y205761D01*
X1699826Y205469D01*
X1699909Y205136D01*
X1700076Y204886D01*
X1700326Y204719D01*
X1700659Y204636D01*
X1700951Y204719D01*
X1701243Y204927D01*
X1701409Y205177D01*
X1701451Y205469D01*
X1701368Y205802D01*
X1701159Y206052D01*
X1700784Y206302D01*
G01X1702326Y207777D02*
X1699826D01*
Y209361D01*
G01X1701034Y208777D02*
Y207777D01*
G01X1700243Y210877D02*
X1699993Y211127D01*
X1699868Y211419D01*
X1699826Y211752D01*
X1699909Y212169D01*
X1700118Y212461D01*
X1700368Y212544D01*
X1700618Y212502D01*
X1700826Y212336D01*
X1701243Y211502D01*
X1701534Y211127D01*
X1701951Y210877D01*
X1702326Y210794D01*
Y212544D01*
G01X1701826Y213852D02*
X1702118Y214102D01*
X1702284Y214436D01*
X1702326Y214811D01*
X1702284Y215144D01*
X1702076Y215477D01*
X1701826Y215686D01*
X1701576Y215727D01*
X1701284Y215644D01*
X1701076Y215352D01*
X1700993Y215061D01*
Y214686D01*
G01Y215061D02*
X1700868Y215311D01*
X1700659Y215519D01*
X1700409Y215602D01*
X1700159Y215519D01*
X1699951Y215311D01*
X1699826Y214936D01*
X1699868Y214561D01*
X1700034Y214186D01*
G01X1706450Y209486D02*
X1706658Y209236D01*
X1706908Y209069D01*
X1707200Y208986D01*
X1707533Y209069D01*
X1707783Y209236D01*
X1708033Y209486D01*
X1708116Y209819D01*
Y211486D01*
G01X1710383Y208986D02*
X1710675Y209028D01*
X1711008Y209153D01*
X1711216Y209361D01*
X1711300Y209653D01*
X1711216Y209944D01*
X1710966Y210194D01*
X1710591Y210319D01*
X1710175D01*
X1709925Y210403D01*
X1709716Y210611D01*
X1709633Y210903D01*
X1709758Y211194D01*
X1710050Y211403D01*
X1710383Y211486D01*
X1710716Y211403D01*
X1711008Y211194D01*
X1711133Y210903D01*
X1711050Y210611D01*
X1710841Y210403D01*
X1710591Y210319D01*
X1710175D01*
X1709800Y210194D01*
X1709550Y209944D01*
X1709466Y209653D01*
X1709550Y209361D01*
X1709758Y209153D01*
X1710091Y209028D01*
X1710383Y208986D01*
G01X1714316D02*
X1712650D01*
Y211486D01*
X1714316D01*
G01X1713650Y210278D02*
X1712650D01*
G01X1715666Y209486D02*
X1715916Y209194D01*
X1716250Y209028D01*
X1716625Y208986D01*
X1716958Y209028D01*
X1717291Y209236D01*
X1717500Y209486D01*
X1717541Y209736D01*
X1717458Y210028D01*
X1717166Y210236D01*
X1716875Y210319D01*
X1716500D01*
G01X1716875D02*
X1717125Y210444D01*
X1717333Y210653D01*
X1717416Y210903D01*
X1717333Y211153D01*
X1717125Y211361D01*
X1716750Y211486D01*
X1716375Y211444D01*
X1716000Y211278D01*
G01X1705900Y184150D02*
X1704775D01*
X1703400Y183317D01*
G01Y184983D02*
X1704775Y184150D01*
G01X1705608Y186542D02*
X1705817Y186833D01*
X1705900Y187167D01*
X1705817Y187500D01*
X1705567Y187792D01*
X1705192Y188000D01*
X1704817Y188083D01*
X1704358D01*
X1703983Y188000D01*
X1703650Y187792D01*
X1703483Y187542D01*
X1703400Y187250D01*
X1703483Y186917D01*
X1703650Y186667D01*
X1703900Y186500D01*
X1704233Y186417D01*
X1704525Y186500D01*
X1704817Y186708D01*
X1704983Y186958D01*
X1705025Y187250D01*
X1704942Y187583D01*
X1704733Y187833D01*
X1704358Y188083D01*
G01X1705900Y189558D02*
X1703400D01*
Y191142D01*
G01X1704608Y190558D02*
Y189558D01*
G01X1703817Y192658D02*
X1703567Y192908D01*
X1703442Y193200D01*
X1703400Y193533D01*
X1703483Y193950D01*
X1703692Y194242D01*
X1703942Y194325D01*
X1704192Y194283D01*
X1704400Y194117D01*
X1704817Y193283D01*
X1705108Y192908D01*
X1705525Y192658D01*
X1705900Y192575D01*
Y194325D01*
G01X1666118Y204230D02*
X1665785Y204272D01*
X1665493Y204438D01*
X1665243Y204688D01*
X1665076Y204980D01*
X1664993Y205313D01*
Y205647D01*
X1665076Y205980D01*
X1665243Y206272D01*
X1665493Y206522D01*
X1665785Y206688D01*
X1666118Y206730D01*
X1666451Y206688D01*
X1666743Y206522D01*
X1666993Y206272D01*
X1667160Y205980D01*
X1667243Y205647D01*
Y205313D01*
X1667160Y204980D01*
X1666993Y204688D01*
X1666743Y204438D01*
X1666451Y204272D01*
X1666118Y204230D01*
G01X1666451Y204897D02*
X1666951Y204230D01*
G01X1669218D02*
X1669510Y204272D01*
X1669843Y204397D01*
X1670051Y204605D01*
X1670135Y204897D01*
X1670051Y205188D01*
X1669801Y205438D01*
X1669426Y205563D01*
X1669010D01*
X1668760Y205647D01*
X1668551Y205855D01*
X1668468Y206147D01*
X1668593Y206438D01*
X1668885Y206647D01*
X1669218Y206730D01*
X1669551Y206647D01*
X1669843Y206438D01*
X1669968Y206147D01*
X1669885Y205855D01*
X1669676Y205647D01*
X1669426Y205563D01*
X1669010D01*
X1668635Y205438D01*
X1668385Y205188D01*
X1668301Y204897D01*
X1668385Y204605D01*
X1668593Y204397D01*
X1668926Y204272D01*
X1669218Y204230D01*
G01X1673151D02*
X1671485D01*
Y206730D01*
X1673151D01*
G01X1672485Y205522D02*
X1671485D01*
G01X1674626Y206313D02*
X1674876Y206563D01*
X1675168Y206688D01*
X1675501Y206730D01*
X1675918Y206647D01*
X1676210Y206438D01*
X1676293Y206188D01*
X1676251Y205938D01*
X1676085Y205730D01*
X1675251Y205313D01*
X1674876Y205022D01*
X1674626Y204605D01*
X1674543Y204230D01*
X1676293D01*
G01X1662235Y204108D02*
Y200858D01*
X1658735D01*
G01X1657485Y206358D02*
X1654985D01*
G01X1673718Y217223D02*
X1673676Y216890D01*
X1673510Y216598D01*
X1673260Y216348D01*
X1672968Y216181D01*
X1672635Y216098D01*
X1672301D01*
X1671968Y216181D01*
X1671676Y216348D01*
X1671426Y216598D01*
X1671260Y216890D01*
X1671218Y217223D01*
X1671260Y217556D01*
X1671426Y217848D01*
X1671676Y218098D01*
X1671968Y218265D01*
X1672301Y218348D01*
X1672635D01*
X1672968Y218265D01*
X1673260Y218098D01*
X1673510Y217848D01*
X1673676Y217556D01*
X1673718Y217223D01*
G01X1673051Y217556D02*
X1673718Y218056D01*
G01Y220323D02*
X1673676Y220615D01*
X1673551Y220948D01*
X1673343Y221156D01*
X1673051Y221240D01*
X1672760Y221156D01*
X1672510Y220906D01*
X1672385Y220531D01*
Y220115D01*
X1672301Y219865D01*
X1672093Y219656D01*
X1671801Y219573D01*
X1671510Y219698D01*
X1671301Y219990D01*
X1671218Y220323D01*
X1671301Y220656D01*
X1671510Y220948D01*
X1671801Y221073D01*
X1672093Y220990D01*
X1672301Y220781D01*
X1672385Y220531D01*
Y220115D01*
X1672510Y219740D01*
X1672760Y219490D01*
X1673051Y219406D01*
X1673343Y219490D01*
X1673551Y219698D01*
X1673676Y220031D01*
X1673718Y220323D01*
G01Y224256D02*
Y222590D01*
X1671218D01*
Y224256D01*
G01X1672426Y223590D02*
Y222590D01*
G01X1673718Y226523D02*
X1671218D01*
X1671718Y226023D01*
G01X1673718D02*
Y227023D01*
G01X1654000Y215400D02*
X1657250D01*
Y218900D01*
G01X1712189Y160331D02*
X1716189D01*
Y167731D01*
G01X1667900Y230367D02*
X1665400D01*
Y231408D01*
X1665525Y231742D01*
X1665692Y231950D01*
X1666025Y232033D01*
X1666358Y231950D01*
X1666567Y231700D01*
X1666692Y231408D01*
Y230367D01*
G01Y231408D02*
X1667900Y232033D01*
G01Y234300D02*
X1667858Y234592D01*
X1667733Y234925D01*
X1667525Y235133D01*
X1667233Y235217D01*
X1666942Y235133D01*
X1666692Y234883D01*
X1666567Y234508D01*
Y234092D01*
X1666483Y233842D01*
X1666275Y233633D01*
X1665983Y233550D01*
X1665692Y233675D01*
X1665483Y233967D01*
X1665400Y234300D01*
X1665483Y234633D01*
X1665692Y234925D01*
X1665983Y235050D01*
X1666275Y234967D01*
X1666483Y234758D01*
X1666567Y234508D01*
Y234092D01*
X1666692Y233717D01*
X1666942Y233467D01*
X1667233Y233383D01*
X1667525Y233467D01*
X1667733Y233675D01*
X1667858Y234008D01*
X1667900Y234300D01*
G01Y238233D02*
Y236567D01*
X1665400D01*
Y238233D01*
G01X1666608Y237567D02*
Y236567D01*
G01X1667900Y240500D02*
X1665400D01*
X1665900Y240000D01*
G01X1667900D02*
Y241000D01*
G01Y244100D02*
X1665400D01*
X1667192Y242558D01*
Y244642D01*
G01X1654000Y227400D02*
X1657250D01*
Y223900D01*
G01X1651750Y222650D02*
Y220150D01*
G01X1672572Y327684D02*
X1670072D01*
Y328725D01*
X1670197Y329059D01*
X1670364Y329267D01*
X1670697Y329350D01*
X1671030Y329267D01*
X1671239Y329017D01*
X1671364Y328725D01*
Y327684D01*
G01Y328725D02*
X1672572Y329350D01*
G01Y331617D02*
X1672530Y331909D01*
X1672405Y332242D01*
X1672197Y332450D01*
X1671905Y332534D01*
X1671614Y332450D01*
X1671364Y332200D01*
X1671239Y331825D01*
Y331409D01*
X1671155Y331159D01*
X1670947Y330950D01*
X1670655Y330867D01*
X1670364Y330992D01*
X1670155Y331284D01*
X1670072Y331617D01*
X1670155Y331950D01*
X1670364Y332242D01*
X1670655Y332367D01*
X1670947Y332284D01*
X1671155Y332075D01*
X1671239Y331825D01*
Y331409D01*
X1671364Y331034D01*
X1671614Y330784D01*
X1671905Y330700D01*
X1672197Y330784D01*
X1672405Y330992D01*
X1672530Y331325D01*
X1672572Y331617D01*
G01Y333800D02*
X1670072D01*
Y334634D01*
X1670197Y334967D01*
X1670364Y335217D01*
X1670614Y335425D01*
X1670905Y335592D01*
X1671322Y335634D01*
X1671739Y335592D01*
X1672030Y335425D01*
X1672280Y335217D01*
X1672447Y334967D01*
X1672572Y334634D01*
Y333800D01*
G01X1670489Y337025D02*
X1670239Y337275D01*
X1670114Y337567D01*
X1670072Y337900D01*
X1670155Y338317D01*
X1670364Y338609D01*
X1670614Y338692D01*
X1670864Y338650D01*
X1671072Y338484D01*
X1671489Y337650D01*
X1671780Y337275D01*
X1672197Y337025D01*
X1672572Y336942D01*
Y338692D01*
G01X1671530Y340125D02*
X1671239Y340417D01*
X1671072Y340667D01*
X1670989Y341000D01*
X1671072Y341292D01*
X1671239Y341500D01*
X1671489Y341667D01*
X1671780Y341709D01*
X1672030Y341667D01*
X1672280Y341500D01*
X1672489Y341250D01*
X1672572Y340959D01*
X1672489Y340625D01*
X1672239Y340334D01*
X1671864Y340167D01*
X1671447Y340125D01*
X1670905Y340209D01*
X1670614Y340334D01*
X1670322Y340542D01*
X1670114Y340834D01*
X1670072Y341125D01*
X1670155Y341417D01*
X1670364Y341625D01*
G01X1659555Y325684D02*
Y323892D01*
X1659722Y323517D01*
X1660055Y323267D01*
X1660472Y323184D01*
X1660889Y323267D01*
X1661222Y323517D01*
X1661389Y323892D01*
Y325684D01*
G01X1663572Y323184D02*
X1663864Y323226D01*
X1664197Y323351D01*
X1664405Y323559D01*
X1664489Y323851D01*
X1664405Y324142D01*
X1664155Y324392D01*
X1663780Y324517D01*
X1663364D01*
X1663114Y324601D01*
X1662905Y324809D01*
X1662822Y325101D01*
X1662947Y325392D01*
X1663239Y325601D01*
X1663572Y325684D01*
X1663905Y325601D01*
X1664197Y325392D01*
X1664322Y325101D01*
X1664239Y324809D01*
X1664030Y324601D01*
X1663780Y324517D01*
X1663364D01*
X1662989Y324392D01*
X1662739Y324142D01*
X1662655Y323851D01*
X1662739Y323559D01*
X1662947Y323351D01*
X1663280Y323226D01*
X1663572Y323184D01*
G01X1665755D02*
Y325684D01*
X1666589D01*
X1666922Y325559D01*
X1667172Y325392D01*
X1667380Y325142D01*
X1667547Y324851D01*
X1667589Y324434D01*
X1667547Y324017D01*
X1667380Y323726D01*
X1667172Y323476D01*
X1666922Y323309D01*
X1666589Y323184D01*
X1665755D01*
G01X1668855Y323559D02*
X1669105Y323351D01*
X1669397Y323226D01*
X1669772Y323184D01*
X1670147Y323267D01*
X1670439Y323434D01*
X1670647Y323726D01*
X1670689Y324059D01*
X1670605Y324392D01*
X1670397Y324601D01*
X1670105Y324767D01*
X1669814Y324809D01*
X1669522Y324767D01*
X1669147Y324601D01*
X1669272Y325684D01*
X1670397D01*
G01X1659495Y317087D02*
Y315295D01*
X1659662Y314920D01*
X1659995Y314670D01*
X1660412Y314587D01*
X1660829Y314670D01*
X1661162Y314920D01*
X1661329Y315295D01*
Y317087D01*
G01X1663512Y314587D02*
X1663804Y314629D01*
X1664137Y314754D01*
X1664345Y314962D01*
X1664429Y315254D01*
X1664345Y315545D01*
X1664095Y315795D01*
X1663720Y315920D01*
X1663304D01*
X1663054Y316004D01*
X1662845Y316212D01*
X1662762Y316504D01*
X1662887Y316795D01*
X1663179Y317004D01*
X1663512Y317087D01*
X1663845Y317004D01*
X1664137Y316795D01*
X1664262Y316504D01*
X1664179Y316212D01*
X1663970Y316004D01*
X1663720Y315920D01*
X1663304D01*
X1662929Y315795D01*
X1662679Y315545D01*
X1662595Y315254D01*
X1662679Y314962D01*
X1662887Y314754D01*
X1663220Y314629D01*
X1663512Y314587D01*
G01X1665695D02*
Y317087D01*
X1666529D01*
X1666862Y316962D01*
X1667112Y316795D01*
X1667320Y316545D01*
X1667487Y316254D01*
X1667529Y315837D01*
X1667487Y315420D01*
X1667320Y315129D01*
X1667112Y314879D01*
X1666862Y314712D01*
X1666529Y314587D01*
X1665695D01*
G01X1668795Y315087D02*
X1669045Y314795D01*
X1669379Y314629D01*
X1669754Y314587D01*
X1670087Y314629D01*
X1670420Y314837D01*
X1670629Y315087D01*
X1670670Y315337D01*
X1670587Y315629D01*
X1670295Y315837D01*
X1670004Y315920D01*
X1669629D01*
G01X1670004D02*
X1670254Y316045D01*
X1670462Y316254D01*
X1670545Y316504D01*
X1670462Y316754D01*
X1670254Y316962D01*
X1669879Y317087D01*
X1669504Y317045D01*
X1669129Y316879D01*
G01X1666311Y339723D02*
X1666186Y339473D01*
X1666103Y339181D01*
Y338848D01*
X1666228Y338473D01*
X1666436Y338181D01*
X1666686Y337973D01*
X1667103Y337806D01*
X1667478Y337764D01*
X1667853Y337848D01*
X1668103Y337973D01*
X1668353Y338223D01*
X1668520Y338514D01*
X1668603Y338806D01*
Y339098D01*
X1668520Y339389D01*
X1668395Y339639D01*
X1668228Y339848D01*
G01X1668603Y341906D02*
X1668561Y342198D01*
X1668436Y342531D01*
X1668228Y342739D01*
X1667936Y342823D01*
X1667645Y342739D01*
X1667395Y342489D01*
X1667270Y342114D01*
Y341698D01*
X1667186Y341448D01*
X1666978Y341239D01*
X1666686Y341156D01*
X1666395Y341281D01*
X1666186Y341573D01*
X1666103Y341906D01*
X1666186Y342239D01*
X1666395Y342531D01*
X1666686Y342656D01*
X1666978Y342573D01*
X1667186Y342364D01*
X1667270Y342114D01*
Y341698D01*
X1667395Y341323D01*
X1667645Y341073D01*
X1667936Y340989D01*
X1668228Y341073D01*
X1668436Y341281D01*
X1668561Y341614D01*
X1668603Y341906D01*
G01Y344089D02*
X1666103D01*
Y344923D01*
X1666228Y345256D01*
X1666395Y345506D01*
X1666645Y345714D01*
X1666936Y345881D01*
X1667353Y345923D01*
X1667770Y345881D01*
X1668061Y345714D01*
X1668311Y345506D01*
X1668478Y345256D01*
X1668603Y344923D01*
Y344089D01*
G01X1666520Y347314D02*
X1666270Y347564D01*
X1666145Y347856D01*
X1666103Y348189D01*
X1666186Y348606D01*
X1666395Y348898D01*
X1666645Y348981D01*
X1666895Y348939D01*
X1667103Y348773D01*
X1667520Y347939D01*
X1667811Y347564D01*
X1668228Y347314D01*
X1668603Y347231D01*
Y348981D01*
G01X1662574Y339850D02*
X1662449Y339600D01*
X1662366Y339308D01*
Y338975D01*
X1662491Y338600D01*
X1662699Y338308D01*
X1662949Y338100D01*
X1663366Y337933D01*
X1663741Y337891D01*
X1664116Y337975D01*
X1664366Y338100D01*
X1664616Y338350D01*
X1664783Y338641D01*
X1664866Y338933D01*
Y339225D01*
X1664783Y339516D01*
X1664658Y339766D01*
X1664491Y339975D01*
G01X1664866Y342033D02*
X1664824Y342325D01*
X1664699Y342658D01*
X1664491Y342866D01*
X1664199Y342950D01*
X1663908Y342866D01*
X1663658Y342616D01*
X1663533Y342241D01*
Y341825D01*
X1663449Y341575D01*
X1663241Y341366D01*
X1662949Y341283D01*
X1662658Y341408D01*
X1662449Y341700D01*
X1662366Y342033D01*
X1662449Y342366D01*
X1662658Y342658D01*
X1662949Y342783D01*
X1663241Y342700D01*
X1663449Y342491D01*
X1663533Y342241D01*
Y341825D01*
X1663658Y341450D01*
X1663908Y341200D01*
X1664199Y341116D01*
X1664491Y341200D01*
X1664699Y341408D01*
X1664824Y341741D01*
X1664866Y342033D01*
G01Y345966D02*
Y344300D01*
X1662366D01*
Y345966D01*
G01X1663574Y345300D02*
Y344300D01*
G01X1662783Y347441D02*
X1662533Y347691D01*
X1662408Y347983D01*
X1662366Y348316D01*
X1662449Y348733D01*
X1662658Y349025D01*
X1662908Y349108D01*
X1663158Y349066D01*
X1663366Y348900D01*
X1663783Y348066D01*
X1664074Y347691D01*
X1664491Y347441D01*
X1664866Y347358D01*
Y349108D01*
G01X1658908Y339950D02*
X1658783Y339700D01*
X1658700Y339408D01*
Y339075D01*
X1658825Y338700D01*
X1659033Y338408D01*
X1659283Y338200D01*
X1659700Y338033D01*
X1660075Y337991D01*
X1660450Y338075D01*
X1660700Y338200D01*
X1660950Y338450D01*
X1661117Y338741D01*
X1661200Y339033D01*
Y339325D01*
X1661117Y339616D01*
X1660992Y339866D01*
X1660825Y340075D01*
G01X1661200Y342133D02*
X1661158Y342425D01*
X1661033Y342758D01*
X1660825Y342966D01*
X1660533Y343050D01*
X1660242Y342966D01*
X1659992Y342716D01*
X1659867Y342341D01*
Y341925D01*
X1659783Y341675D01*
X1659575Y341466D01*
X1659283Y341383D01*
X1658992Y341508D01*
X1658783Y341800D01*
X1658700Y342133D01*
X1658783Y342466D01*
X1658992Y342758D01*
X1659283Y342883D01*
X1659575Y342800D01*
X1659783Y342591D01*
X1659867Y342341D01*
Y341925D01*
X1659992Y341550D01*
X1660242Y341300D01*
X1660533Y341216D01*
X1660825Y341300D01*
X1661033Y341508D01*
X1661158Y341841D01*
X1661200Y342133D01*
G01Y346066D02*
Y344400D01*
X1658700D01*
Y346066D01*
G01X1659908Y345400D02*
Y344400D01*
G01X1661200Y348333D02*
X1658700D01*
X1659200Y347833D01*
G01X1661200D02*
Y348833D01*
G01X1664319Y355661D02*
X1661819D01*
Y356702D01*
X1661944Y357036D01*
X1662111Y357244D01*
X1662444Y357327D01*
X1662777Y357244D01*
X1662986Y356994D01*
X1663111Y356702D01*
Y355661D01*
G01Y356702D02*
X1664319Y357327D01*
G01X1662236Y358802D02*
X1661986Y359052D01*
X1661861Y359344D01*
X1661819Y359677D01*
X1661902Y360094D01*
X1662111Y360386D01*
X1662361Y360469D01*
X1662611Y360427D01*
X1662819Y360261D01*
X1663236Y359427D01*
X1663527Y359052D01*
X1663944Y358802D01*
X1664319Y358719D01*
Y360469D01*
G01Y361861D02*
X1661819D01*
Y362861D01*
X1661944Y363194D01*
X1662236Y363444D01*
X1662569Y363527D01*
X1662902Y363444D01*
X1663152Y363236D01*
X1663277Y362861D01*
Y361861D01*
G01X1664319Y366294D02*
X1661819D01*
X1663611Y364752D01*
Y366836D01*
G01X1668256Y355536D02*
X1665756D01*
Y356577D01*
X1665881Y356911D01*
X1666048Y357119D01*
X1666381Y357202D01*
X1666714Y357119D01*
X1666923Y356869D01*
X1667048Y356577D01*
Y355536D01*
G01Y356577D02*
X1668256Y357202D01*
G01X1666173Y358677D02*
X1665923Y358927D01*
X1665798Y359219D01*
X1665756Y359552D01*
X1665839Y359969D01*
X1666048Y360261D01*
X1666298Y360344D01*
X1666548Y360302D01*
X1666756Y360136D01*
X1667173Y359302D01*
X1667464Y358927D01*
X1667881Y358677D01*
X1668256Y358594D01*
Y360344D01*
G01Y361736D02*
X1665756D01*
Y362736D01*
X1665881Y363069D01*
X1666173Y363319D01*
X1666506Y363402D01*
X1666839Y363319D01*
X1667089Y363111D01*
X1667214Y362736D01*
Y361736D01*
G01X1667756Y364752D02*
X1668048Y365002D01*
X1668214Y365336D01*
X1668256Y365711D01*
X1668214Y366044D01*
X1668006Y366377D01*
X1667756Y366586D01*
X1667506Y366627D01*
X1667214Y366544D01*
X1667006Y366252D01*
X1666923Y365961D01*
Y365586D01*
G01Y365961D02*
X1666798Y366211D01*
X1666589Y366419D01*
X1666339Y366502D01*
X1666089Y366419D01*
X1665881Y366211D01*
X1665756Y365836D01*
X1665798Y365461D01*
X1665964Y365086D01*
G01X1665442Y408269D02*
Y410769D01*
X1666483D01*
X1666817Y410644D01*
X1667025Y410477D01*
X1667108Y410144D01*
X1667025Y409811D01*
X1666775Y409602D01*
X1666483Y409477D01*
X1665442D01*
G01X1666483D02*
X1667108Y408269D01*
G01X1668583Y409311D02*
X1668875Y409602D01*
X1669125Y409769D01*
X1669458Y409852D01*
X1669750Y409769D01*
X1669958Y409602D01*
X1670125Y409352D01*
X1670167Y409061D01*
X1670125Y408811D01*
X1669958Y408561D01*
X1669708Y408352D01*
X1669417Y408269D01*
X1669083Y408352D01*
X1668792Y408602D01*
X1668625Y408977D01*
X1668583Y409394D01*
X1668667Y409936D01*
X1668792Y410227D01*
X1669000Y410519D01*
X1669292Y410727D01*
X1669583Y410769D01*
X1669875Y410686D01*
X1670083Y410477D01*
G01X1671225Y410769D02*
X1671808Y408269D01*
X1672475Y410769D01*
X1673142Y408269D01*
X1673725Y410769D01*
G01X1674783Y410352D02*
X1675033Y410602D01*
X1675325Y410727D01*
X1675658Y410769D01*
X1676075Y410686D01*
X1676367Y410477D01*
X1676450Y410227D01*
X1676408Y409977D01*
X1676242Y409769D01*
X1675408Y409352D01*
X1675033Y409061D01*
X1674783Y408644D01*
X1674700Y408269D01*
X1676450D01*
G01X1678592D02*
X1678675Y408811D01*
X1678800Y409269D01*
X1678967Y409686D01*
X1679175Y410144D01*
X1679508Y410769D01*
X1677842D01*
G01X1665513Y411766D02*
Y414266D01*
X1666554D01*
X1666888Y414141D01*
X1667096Y413974D01*
X1667179Y413641D01*
X1667096Y413308D01*
X1666846Y413099D01*
X1666554Y412974D01*
X1665513D01*
G01X1666554D02*
X1667179Y411766D01*
G01X1668738Y412058D02*
X1669029Y411849D01*
X1669363Y411766D01*
X1669696Y411849D01*
X1669988Y412099D01*
X1670196Y412474D01*
X1670279Y412849D01*
Y413308D01*
X1670196Y413683D01*
X1669988Y414016D01*
X1669738Y414183D01*
X1669446Y414266D01*
X1669113Y414183D01*
X1668863Y414016D01*
X1668696Y413766D01*
X1668613Y413433D01*
X1668696Y413141D01*
X1668904Y412849D01*
X1669154Y412683D01*
X1669446Y412641D01*
X1669779Y412724D01*
X1670029Y412933D01*
X1670279Y413308D01*
G01X1671296Y414266D02*
X1671879Y411766D01*
X1672546Y414266D01*
X1673213Y411766D01*
X1673796Y414266D01*
G01X1675646Y411766D02*
Y414266D01*
X1675146Y413766D01*
G01Y411766D02*
X1676146D01*
G01X1678746D02*
X1679038Y411808D01*
X1679371Y411933D01*
X1679579Y412141D01*
X1679663Y412433D01*
X1679579Y412724D01*
X1679329Y412974D01*
X1678954Y413099D01*
X1678538D01*
X1678288Y413183D01*
X1678079Y413391D01*
X1677996Y413683D01*
X1678121Y413974D01*
X1678413Y414183D01*
X1678746Y414266D01*
X1679079Y414183D01*
X1679371Y413974D01*
X1679496Y413683D01*
X1679413Y413391D01*
X1679204Y413183D01*
X1678954Y413099D01*
X1678538D01*
X1678163Y412974D01*
X1677913Y412724D01*
X1677829Y412433D01*
X1677913Y412141D01*
X1678121Y411933D01*
X1678454Y411808D01*
X1678746Y411766D01*
G01X1666106Y457620D02*
X1663606D01*
Y458661D01*
X1663731Y458995D01*
X1663898Y459203D01*
X1664231Y459286D01*
X1664564Y459203D01*
X1664773Y458953D01*
X1664898Y458661D01*
Y457620D01*
G01Y458661D02*
X1666106Y459286D01*
G01Y461553D02*
X1666064Y461845D01*
X1665939Y462178D01*
X1665731Y462386D01*
X1665439Y462470D01*
X1665148Y462386D01*
X1664898Y462136D01*
X1664773Y461761D01*
Y461345D01*
X1664689Y461095D01*
X1664481Y460886D01*
X1664189Y460803D01*
X1663898Y460928D01*
X1663689Y461220D01*
X1663606Y461553D01*
X1663689Y461886D01*
X1663898Y462178D01*
X1664189Y462303D01*
X1664481Y462220D01*
X1664689Y462011D01*
X1664773Y461761D01*
Y461345D01*
X1664898Y460970D01*
X1665148Y460720D01*
X1665439Y460636D01*
X1665731Y460720D01*
X1665939Y460928D01*
X1666064Y461261D01*
X1666106Y461553D01*
G01X1664773Y464986D02*
X1664648Y465153D01*
X1664439Y465278D01*
X1664148Y465361D01*
X1663898Y465278D01*
X1663731Y465111D01*
X1663606Y464820D01*
Y463695D01*
X1666106D01*
Y465070D01*
X1665939Y465361D01*
X1665689Y465528D01*
X1665398Y465611D01*
X1665106Y465528D01*
X1664856Y465278D01*
X1664773Y464986D01*
Y463695D01*
G01X1666106Y467753D02*
X1663606D01*
X1664106Y467253D01*
G01X1666106D02*
Y468253D01*
G01Y470853D02*
X1666064Y471145D01*
X1665939Y471478D01*
X1665731Y471686D01*
X1665439Y471770D01*
X1665148Y471686D01*
X1664898Y471436D01*
X1664773Y471061D01*
Y470645D01*
X1664689Y470395D01*
X1664481Y470186D01*
X1664189Y470103D01*
X1663898Y470228D01*
X1663689Y470520D01*
X1663606Y470853D01*
X1663689Y471186D01*
X1663898Y471478D01*
X1664189Y471603D01*
X1664481Y471520D01*
X1664689Y471311D01*
X1664773Y471061D01*
Y470645D01*
X1664898Y470270D01*
X1665148Y470020D01*
X1665439Y469936D01*
X1665731Y470020D01*
X1665939Y470228D01*
X1666064Y470561D01*
X1666106Y470853D01*
G01X1670330Y457537D02*
X1667830D01*
Y458578D01*
X1667955Y458912D01*
X1668122Y459120D01*
X1668455Y459203D01*
X1668788Y459120D01*
X1668997Y458870D01*
X1669122Y458578D01*
Y457537D01*
G01Y458578D02*
X1670330Y459203D01*
G01Y461470D02*
X1670288Y461762D01*
X1670163Y462095D01*
X1669955Y462303D01*
X1669663Y462387D01*
X1669372Y462303D01*
X1669122Y462053D01*
X1668997Y461678D01*
Y461262D01*
X1668913Y461012D01*
X1668705Y460803D01*
X1668413Y460720D01*
X1668122Y460845D01*
X1667913Y461137D01*
X1667830Y461470D01*
X1667913Y461803D01*
X1668122Y462095D01*
X1668413Y462220D01*
X1668705Y462137D01*
X1668913Y461928D01*
X1668997Y461678D01*
Y461262D01*
X1669122Y460887D01*
X1669372Y460637D01*
X1669663Y460553D01*
X1669955Y460637D01*
X1670163Y460845D01*
X1670288Y461178D01*
X1670330Y461470D01*
G01X1668997Y464903D02*
X1668872Y465070D01*
X1668663Y465195D01*
X1668372Y465278D01*
X1668122Y465195D01*
X1667955Y465028D01*
X1667830Y464737D01*
Y463612D01*
X1670330D01*
Y464987D01*
X1670163Y465278D01*
X1669913Y465445D01*
X1669622Y465528D01*
X1669330Y465445D01*
X1669080Y465195D01*
X1668997Y464903D01*
Y463612D01*
G01X1670330Y467670D02*
X1667830D01*
X1668330Y467170D01*
G01X1670330D02*
Y468170D01*
G01X1670038Y470062D02*
X1670247Y470353D01*
X1670330Y470687D01*
X1670247Y471020D01*
X1669997Y471312D01*
X1669622Y471520D01*
X1669247Y471603D01*
X1668788D01*
X1668413Y471520D01*
X1668080Y471312D01*
X1667913Y471062D01*
X1667830Y470770D01*
X1667913Y470437D01*
X1668080Y470187D01*
X1668330Y470020D01*
X1668663Y469937D01*
X1668955Y470020D01*
X1669247Y470228D01*
X1669413Y470478D01*
X1669455Y470770D01*
X1669372Y471103D01*
X1669163Y471353D01*
X1668788Y471603D01*
G01X1680080Y444107D02*
X1677580D01*
Y445148D01*
X1677705Y445482D01*
X1677872Y445690D01*
X1678205Y445773D01*
X1678538Y445690D01*
X1678747Y445440D01*
X1678872Y445148D01*
Y444107D01*
G01Y445148D02*
X1680080Y445773D01*
G01X1679788Y447332D02*
X1679997Y447623D01*
X1680080Y447957D01*
X1679997Y448290D01*
X1679747Y448582D01*
X1679372Y448790D01*
X1678997Y448873D01*
X1678538D01*
X1678163Y448790D01*
X1677830Y448582D01*
X1677663Y448332D01*
X1677580Y448040D01*
X1677663Y447707D01*
X1677830Y447457D01*
X1678080Y447290D01*
X1678413Y447207D01*
X1678705Y447290D01*
X1678997Y447498D01*
X1679163Y447748D01*
X1679205Y448040D01*
X1679122Y448373D01*
X1678913Y448623D01*
X1678538Y448873D01*
G01X1677580Y449890D02*
X1680080Y450473D01*
X1677580Y451140D01*
X1680080Y451807D01*
X1677580Y452390D01*
G01X1680080Y454240D02*
X1677580D01*
X1678080Y453740D01*
G01X1680080D02*
Y454740D01*
G01Y457840D02*
X1677580D01*
X1679372Y456298D01*
Y458382D01*
G01X1666767Y438866D02*
Y441366D01*
X1667808D01*
X1668142Y441241D01*
X1668350Y441074D01*
X1668433Y440741D01*
X1668350Y440408D01*
X1668100Y440199D01*
X1667808Y440074D01*
X1666767D01*
G01X1667808D02*
X1668433Y438866D01*
G01X1669992Y439158D02*
X1670283Y438949D01*
X1670617Y438866D01*
X1670950Y438949D01*
X1671242Y439199D01*
X1671450Y439574D01*
X1671533Y439949D01*
Y440408D01*
X1671450Y440783D01*
X1671242Y441116D01*
X1670992Y441283D01*
X1670700Y441366D01*
X1670367Y441283D01*
X1670117Y441116D01*
X1669950Y440866D01*
X1669867Y440533D01*
X1669950Y440241D01*
X1670158Y439949D01*
X1670408Y439783D01*
X1670700Y439741D01*
X1671033Y439824D01*
X1671283Y440033D01*
X1671533Y440408D01*
G01X1672550Y441366D02*
X1673133Y438866D01*
X1673800Y441366D01*
X1674467Y438866D01*
X1675050Y441366D01*
G01X1676900Y438866D02*
Y441366D01*
X1676400Y440866D01*
G01Y438866D02*
X1677400D01*
G01X1679917D02*
X1680000Y439408D01*
X1680125Y439866D01*
X1680292Y440283D01*
X1680500Y440741D01*
X1680833Y441366D01*
X1679167D01*
G01X1683167Y438966D02*
Y441466D01*
X1684208D01*
X1684542Y441341D01*
X1684750Y441174D01*
X1684833Y440841D01*
X1684750Y440508D01*
X1684500Y440299D01*
X1684208Y440174D01*
X1683167D01*
G01X1684208D02*
X1684833Y438966D01*
G01X1686392Y439258D02*
X1686683Y439049D01*
X1687017Y438966D01*
X1687350Y439049D01*
X1687642Y439299D01*
X1687850Y439674D01*
X1687933Y440049D01*
Y440508D01*
X1687850Y440883D01*
X1687642Y441216D01*
X1687392Y441383D01*
X1687100Y441466D01*
X1686767Y441383D01*
X1686517Y441216D01*
X1686350Y440966D01*
X1686267Y440633D01*
X1686350Y440341D01*
X1686558Y440049D01*
X1686808Y439883D01*
X1687100Y439841D01*
X1687433Y439924D01*
X1687683Y440133D01*
X1687933Y440508D01*
G01X1688950Y441466D02*
X1689533Y438966D01*
X1690200Y441466D01*
X1690867Y438966D01*
X1691450Y441466D01*
G01X1693300Y438966D02*
Y441466D01*
X1692800Y440966D01*
G01Y438966D02*
X1693800D01*
G01X1695608Y440008D02*
X1695900Y440299D01*
X1696150Y440466D01*
X1696483Y440549D01*
X1696775Y440466D01*
X1696983Y440299D01*
X1697150Y440049D01*
X1697192Y439758D01*
X1697150Y439508D01*
X1696983Y439258D01*
X1696733Y439049D01*
X1696442Y438966D01*
X1696108Y439049D01*
X1695817Y439299D01*
X1695650Y439674D01*
X1695608Y440091D01*
X1695692Y440633D01*
X1695817Y440924D01*
X1696025Y441216D01*
X1696317Y441424D01*
X1696608Y441466D01*
X1696900Y441383D01*
X1697108Y441174D01*
G01X1685030Y444397D02*
X1682530D01*
Y445438D01*
X1682655Y445772D01*
X1682822Y445980D01*
X1683155Y446063D01*
X1683488Y445980D01*
X1683697Y445730D01*
X1683822Y445438D01*
Y444397D01*
G01Y445438D02*
X1685030Y446063D01*
G01X1684738Y447622D02*
X1684947Y447913D01*
X1685030Y448247D01*
X1684947Y448580D01*
X1684697Y448872D01*
X1684322Y449080D01*
X1683947Y449163D01*
X1683488D01*
X1683113Y449080D01*
X1682780Y448872D01*
X1682613Y448622D01*
X1682530Y448330D01*
X1682613Y447997D01*
X1682780Y447747D01*
X1683030Y447580D01*
X1683363Y447497D01*
X1683655Y447580D01*
X1683947Y447788D01*
X1684113Y448038D01*
X1684155Y448330D01*
X1684072Y448663D01*
X1683863Y448913D01*
X1683488Y449163D01*
G01X1682530Y450180D02*
X1685030Y450763D01*
X1682530Y451430D01*
X1685030Y452097D01*
X1682530Y452680D01*
G01X1685030Y454530D02*
X1682530D01*
X1683030Y454030D01*
G01X1685030D02*
Y455030D01*
G01X1684530Y456713D02*
X1684822Y456963D01*
X1684988Y457297D01*
X1685030Y457672D01*
X1684988Y458005D01*
X1684780Y458338D01*
X1684530Y458547D01*
X1684280Y458588D01*
X1683988Y458505D01*
X1683780Y458213D01*
X1683697Y457922D01*
Y457547D01*
G01Y457922D02*
X1683572Y458172D01*
X1683363Y458380D01*
X1683113Y458463D01*
X1682863Y458380D01*
X1682655Y458172D01*
X1682530Y457797D01*
X1682572Y457422D01*
X1682738Y457047D01*
G01X1676540Y444607D02*
X1674040D01*
Y445648D01*
X1674165Y445982D01*
X1674332Y446190D01*
X1674665Y446273D01*
X1674998Y446190D01*
X1675207Y445940D01*
X1675332Y445648D01*
Y444607D01*
G01Y445648D02*
X1676540Y446273D01*
G01X1674457Y447748D02*
X1674207Y447998D01*
X1674082Y448290D01*
X1674040Y448623D01*
X1674123Y449040D01*
X1674332Y449332D01*
X1674582Y449415D01*
X1674832Y449373D01*
X1675040Y449207D01*
X1675457Y448373D01*
X1675748Y447998D01*
X1676165Y447748D01*
X1676540Y447665D01*
Y449415D01*
G01Y450557D02*
X1674040D01*
X1676123Y451640D01*
X1674040Y452723D01*
X1676540D01*
G01X1676165Y453823D02*
X1676373Y454073D01*
X1676498Y454365D01*
X1676540Y454740D01*
X1676457Y455115D01*
X1676290Y455407D01*
X1675998Y455615D01*
X1675665Y455657D01*
X1675332Y455573D01*
X1675123Y455365D01*
X1674957Y455073D01*
X1674915Y454782D01*
X1674957Y454490D01*
X1675123Y454115D01*
X1674040Y454240D01*
Y455365D01*
G01X1669207Y423030D02*
Y425530D01*
X1670248D01*
X1670582Y425405D01*
X1670790Y425238D01*
X1670873Y424905D01*
X1670790Y424572D01*
X1670540Y424363D01*
X1670248Y424238D01*
X1669207D01*
G01X1670248D02*
X1670873Y423030D01*
G01X1672348Y425113D02*
X1672598Y425363D01*
X1672890Y425488D01*
X1673223Y425530D01*
X1673640Y425447D01*
X1673932Y425238D01*
X1674015Y424988D01*
X1673973Y424738D01*
X1673807Y424530D01*
X1672973Y424113D01*
X1672598Y423822D01*
X1672348Y423405D01*
X1672265Y423030D01*
X1674015D01*
G01X1675157D02*
Y425530D01*
X1676240Y423447D01*
X1677323Y425530D01*
Y423030D01*
G01X1678423Y423530D02*
X1678673Y423238D01*
X1679007Y423072D01*
X1679382Y423030D01*
X1679715Y423072D01*
X1680048Y423280D01*
X1680257Y423530D01*
X1680298Y423780D01*
X1680215Y424072D01*
X1679923Y424280D01*
X1679632Y424363D01*
X1679257D01*
G01X1679632D02*
X1679882Y424488D01*
X1680090Y424697D01*
X1680173Y424947D01*
X1680090Y425197D01*
X1679882Y425405D01*
X1679507Y425530D01*
X1679132Y425488D01*
X1678757Y425322D01*
G01X1666157Y419050D02*
Y421550D01*
X1667198D01*
X1667532Y421425D01*
X1667740Y421258D01*
X1667823Y420925D01*
X1667740Y420592D01*
X1667490Y420383D01*
X1667198Y420258D01*
X1666157D01*
G01X1667198D02*
X1667823Y419050D01*
G01X1670090D02*
X1670382Y419092D01*
X1670715Y419217D01*
X1670923Y419425D01*
X1671007Y419717D01*
X1670923Y420008D01*
X1670673Y420258D01*
X1670298Y420383D01*
X1669882D01*
X1669632Y420467D01*
X1669423Y420675D01*
X1669340Y420967D01*
X1669465Y421258D01*
X1669757Y421467D01*
X1670090Y421550D01*
X1670423Y421467D01*
X1670715Y421258D01*
X1670840Y420967D01*
X1670757Y420675D01*
X1670548Y420467D01*
X1670298Y420383D01*
X1669882D01*
X1669507Y420258D01*
X1669257Y420008D01*
X1669173Y419717D01*
X1669257Y419425D01*
X1669465Y419217D01*
X1669798Y419092D01*
X1670090Y419050D01*
G01X1674023D02*
X1672357D01*
Y421550D01*
X1674023D01*
G01X1673357Y420342D02*
X1672357D01*
G01X1675498Y421133D02*
X1675748Y421383D01*
X1676040Y421508D01*
X1676373Y421550D01*
X1676790Y421467D01*
X1677082Y421258D01*
X1677165Y421008D01*
X1677123Y420758D01*
X1676957Y420550D01*
X1676123Y420133D01*
X1675748Y419842D01*
X1675498Y419425D01*
X1675415Y419050D01*
X1677165D01*
G01X1679890D02*
Y421550D01*
X1678348Y419758D01*
X1680432D01*
G01X1669033Y432370D02*
Y430578D01*
X1669200Y430203D01*
X1669533Y429953D01*
X1669950Y429870D01*
X1670367Y429953D01*
X1670700Y430203D01*
X1670867Y430578D01*
Y432370D01*
G01X1673050Y429870D02*
Y432370D01*
X1672550Y431870D01*
G01Y429870D02*
X1673550D01*
G01X1674900Y432370D02*
X1675483Y429870D01*
X1676150Y432370D01*
X1676817Y429870D01*
X1677400Y432370D01*
G01X1678458Y431953D02*
X1678708Y432203D01*
X1679000Y432328D01*
X1679333Y432370D01*
X1679750Y432287D01*
X1680042Y432078D01*
X1680125Y431828D01*
X1680083Y431578D01*
X1679917Y431370D01*
X1679083Y430953D01*
X1678708Y430662D01*
X1678458Y430245D01*
X1678375Y429870D01*
X1680125D01*
G01X1664971Y483999D02*
X1661871D01*
G01Y485609D02*
X1664971D01*
G01X1663421D02*
Y483999D01*
G01X1664971Y487176D02*
X1661871D01*
Y488632D01*
G01X1663369Y488096D02*
Y487176D01*
G01X1661871Y490544D02*
Y491464D01*
G01Y491004D02*
X1664971D01*
G01Y490544D02*
Y491464D01*
G01X1663938Y493606D02*
Y494602D01*
G01X1661871Y496744D02*
Y497664D01*
G01Y497204D02*
X1664971D01*
G01Y496744D02*
Y497664D01*
G01Y500304D02*
X1664919Y499997D01*
X1664713Y499729D01*
X1664403Y499499D01*
X1664041Y499346D01*
X1663628Y499269D01*
X1663214D01*
X1662801Y499346D01*
X1662439Y499499D01*
X1662129Y499729D01*
X1661923Y499997D01*
X1661871Y500304D01*
X1661923Y500611D01*
X1662129Y500879D01*
X1662439Y501109D01*
X1662801Y501262D01*
X1663214Y501339D01*
X1663628D01*
X1664041Y501262D01*
X1664403Y501109D01*
X1664713Y500879D01*
X1664919Y500611D01*
X1664971Y500304D01*
G01X1692075Y491850D02*
X1691825Y491975D01*
X1691533Y492058D01*
X1691200D01*
X1690825Y491933D01*
X1690533Y491725D01*
X1690325Y491475D01*
X1690158Y491058D01*
X1690116Y490683D01*
X1690200Y490308D01*
X1690325Y490058D01*
X1690575Y489808D01*
X1690866Y489641D01*
X1691158Y489558D01*
X1691450D01*
X1691741Y489641D01*
X1691991Y489766D01*
X1692200Y489933D01*
G01X1694258Y489558D02*
X1694550Y489600D01*
X1694883Y489725D01*
X1695091Y489933D01*
X1695175Y490225D01*
X1695091Y490516D01*
X1694841Y490766D01*
X1694466Y490891D01*
X1694050D01*
X1693800Y490975D01*
X1693591Y491183D01*
X1693508Y491475D01*
X1693633Y491766D01*
X1693925Y491975D01*
X1694258Y492058D01*
X1694591Y491975D01*
X1694883Y491766D01*
X1695008Y491475D01*
X1694925Y491183D01*
X1694716Y490975D01*
X1694466Y490891D01*
X1694050D01*
X1693675Y490766D01*
X1693425Y490516D01*
X1693341Y490225D01*
X1693425Y489933D01*
X1693633Y489725D01*
X1693966Y489600D01*
X1694258Y489558D01*
G01X1697691Y490891D02*
X1697858Y491016D01*
X1697983Y491225D01*
X1698066Y491516D01*
X1697983Y491766D01*
X1697816Y491933D01*
X1697525Y492058D01*
X1696400D01*
Y489558D01*
X1697775D01*
X1698066Y489725D01*
X1698233Y489975D01*
X1698316Y490266D01*
X1698233Y490558D01*
X1697983Y490808D01*
X1697691Y490891D01*
X1696400D01*
G01X1700458Y489558D02*
Y492058D01*
X1699958Y491558D01*
G01Y489558D02*
X1700958D01*
G01X1702766Y491641D02*
X1703016Y491891D01*
X1703308Y492016D01*
X1703641Y492058D01*
X1704058Y491975D01*
X1704350Y491766D01*
X1704433Y491516D01*
X1704391Y491266D01*
X1704225Y491058D01*
X1703391Y490641D01*
X1703016Y490350D01*
X1702766Y489933D01*
X1702683Y489558D01*
X1704433D01*
G01X1673764Y472666D02*
Y475166D01*
X1674805D01*
X1675139Y475041D01*
X1675347Y474874D01*
X1675430Y474541D01*
X1675347Y474208D01*
X1675097Y473999D01*
X1674805Y473874D01*
X1673764D01*
G01X1674805D02*
X1675430Y472666D01*
G01X1677697D02*
X1677989Y472708D01*
X1678322Y472833D01*
X1678530Y473041D01*
X1678614Y473333D01*
X1678530Y473624D01*
X1678280Y473874D01*
X1677905Y473999D01*
X1677489D01*
X1677239Y474083D01*
X1677030Y474291D01*
X1676947Y474583D01*
X1677072Y474874D01*
X1677364Y475083D01*
X1677697Y475166D01*
X1678030Y475083D01*
X1678322Y474874D01*
X1678447Y474583D01*
X1678364Y474291D01*
X1678155Y474083D01*
X1677905Y473999D01*
X1677489D01*
X1677114Y473874D01*
X1676864Y473624D01*
X1676780Y473333D01*
X1676864Y473041D01*
X1677072Y472833D01*
X1677405Y472708D01*
X1677697Y472666D01*
G01X1681130Y473999D02*
X1681297Y474124D01*
X1681422Y474333D01*
X1681505Y474624D01*
X1681422Y474874D01*
X1681255Y475041D01*
X1680964Y475166D01*
X1679839D01*
Y472666D01*
X1681214D01*
X1681505Y472833D01*
X1681672Y473083D01*
X1681755Y473374D01*
X1681672Y473666D01*
X1681422Y473916D01*
X1681130Y473999D01*
X1679839D01*
G01X1683897Y472666D02*
Y475166D01*
X1683397Y474666D01*
G01Y472666D02*
X1684397D01*
G01X1686080Y473166D02*
X1686330Y472874D01*
X1686664Y472708D01*
X1687039Y472666D01*
X1687372Y472708D01*
X1687705Y472916D01*
X1687914Y473166D01*
X1687955Y473416D01*
X1687872Y473708D01*
X1687580Y473916D01*
X1687289Y473999D01*
X1686914D01*
G01X1687289D02*
X1687539Y474124D01*
X1687747Y474333D01*
X1687830Y474583D01*
X1687747Y474833D01*
X1687539Y475041D01*
X1687164Y475166D01*
X1686789Y475124D01*
X1686414Y474958D01*
G01X1673764Y469366D02*
Y471866D01*
X1674805D01*
X1675139Y471741D01*
X1675347Y471574D01*
X1675430Y471241D01*
X1675347Y470908D01*
X1675097Y470699D01*
X1674805Y470574D01*
X1673764D01*
G01X1674805D02*
X1675430Y469366D01*
G01X1677697D02*
X1677989Y469408D01*
X1678322Y469533D01*
X1678530Y469741D01*
X1678614Y470033D01*
X1678530Y470324D01*
X1678280Y470574D01*
X1677905Y470699D01*
X1677489D01*
X1677239Y470783D01*
X1677030Y470991D01*
X1676947Y471283D01*
X1677072Y471574D01*
X1677364Y471783D01*
X1677697Y471866D01*
X1678030Y471783D01*
X1678322Y471574D01*
X1678447Y471283D01*
X1678364Y470991D01*
X1678155Y470783D01*
X1677905Y470699D01*
X1677489D01*
X1677114Y470574D01*
X1676864Y470324D01*
X1676780Y470033D01*
X1676864Y469741D01*
X1677072Y469533D01*
X1677405Y469408D01*
X1677697Y469366D01*
G01X1681130Y470699D02*
X1681297Y470824D01*
X1681422Y471033D01*
X1681505Y471324D01*
X1681422Y471574D01*
X1681255Y471741D01*
X1680964Y471866D01*
X1679839D01*
Y469366D01*
X1681214D01*
X1681505Y469533D01*
X1681672Y469783D01*
X1681755Y470074D01*
X1681672Y470366D01*
X1681422Y470616D01*
X1681130Y470699D01*
X1679839D01*
G01X1683897Y469366D02*
Y471866D01*
X1683397Y471366D01*
G01Y469366D02*
X1684397D01*
G01X1686205Y470408D02*
X1686497Y470699D01*
X1686747Y470866D01*
X1687080Y470949D01*
X1687372Y470866D01*
X1687580Y470699D01*
X1687747Y470449D01*
X1687789Y470158D01*
X1687747Y469908D01*
X1687580Y469658D01*
X1687330Y469449D01*
X1687039Y469366D01*
X1686705Y469449D01*
X1686414Y469699D01*
X1686247Y470074D01*
X1686205Y470491D01*
X1686289Y471033D01*
X1686414Y471324D01*
X1686622Y471616D01*
X1686914Y471824D01*
X1687205Y471866D01*
X1687497Y471783D01*
X1687705Y471574D01*
G01X1673764Y466066D02*
Y468566D01*
X1674805D01*
X1675139Y468441D01*
X1675347Y468274D01*
X1675430Y467941D01*
X1675347Y467608D01*
X1675097Y467399D01*
X1674805Y467274D01*
X1673764D01*
G01X1674805D02*
X1675430Y466066D01*
G01X1677697D02*
X1677989Y466108D01*
X1678322Y466233D01*
X1678530Y466441D01*
X1678614Y466733D01*
X1678530Y467024D01*
X1678280Y467274D01*
X1677905Y467399D01*
X1677489D01*
X1677239Y467483D01*
X1677030Y467691D01*
X1676947Y467983D01*
X1677072Y468274D01*
X1677364Y468483D01*
X1677697Y468566D01*
X1678030Y468483D01*
X1678322Y468274D01*
X1678447Y467983D01*
X1678364Y467691D01*
X1678155Y467483D01*
X1677905Y467399D01*
X1677489D01*
X1677114Y467274D01*
X1676864Y467024D01*
X1676780Y466733D01*
X1676864Y466441D01*
X1677072Y466233D01*
X1677405Y466108D01*
X1677697Y466066D01*
G01X1681130Y467399D02*
X1681297Y467524D01*
X1681422Y467733D01*
X1681505Y468024D01*
X1681422Y468274D01*
X1681255Y468441D01*
X1680964Y468566D01*
X1679839D01*
Y466066D01*
X1681214D01*
X1681505Y466233D01*
X1681672Y466483D01*
X1681755Y466774D01*
X1681672Y467066D01*
X1681422Y467316D01*
X1681130Y467399D01*
X1679839D01*
G01X1683897Y466066D02*
Y468566D01*
X1683397Y468066D01*
G01Y466066D02*
X1684397D01*
G01X1686914D02*
X1686997Y466608D01*
X1687122Y467066D01*
X1687289Y467483D01*
X1687497Y467941D01*
X1687830Y468566D01*
X1686164D01*
G01X1661846Y507631D02*
Y510131D01*
X1662887D01*
X1663221Y510006D01*
X1663429Y509839D01*
X1663512Y509506D01*
X1663429Y509173D01*
X1663179Y508964D01*
X1662887Y508839D01*
X1661846D01*
G01X1662887D02*
X1663512Y507631D01*
G01X1665779D02*
X1666071Y507673D01*
X1666404Y507798D01*
X1666612Y508006D01*
X1666696Y508298D01*
X1666612Y508589D01*
X1666362Y508839D01*
X1665987Y508964D01*
X1665571D01*
X1665321Y509048D01*
X1665112Y509256D01*
X1665029Y509548D01*
X1665154Y509839D01*
X1665446Y510048D01*
X1665779Y510131D01*
X1666112Y510048D01*
X1666404Y509839D01*
X1666529Y509548D01*
X1666446Y509256D01*
X1666237Y509048D01*
X1665987Y508964D01*
X1665571D01*
X1665196Y508839D01*
X1664946Y508589D01*
X1664862Y508298D01*
X1664946Y508006D01*
X1665154Y507798D01*
X1665487Y507673D01*
X1665779Y507631D01*
G01X1669212Y508964D02*
X1669379Y509089D01*
X1669504Y509298D01*
X1669587Y509589D01*
X1669504Y509839D01*
X1669337Y510006D01*
X1669046Y510131D01*
X1667921D01*
Y507631D01*
X1669296D01*
X1669587Y507798D01*
X1669754Y508048D01*
X1669837Y508339D01*
X1669754Y508631D01*
X1669504Y508881D01*
X1669212Y508964D01*
X1667921D01*
G01X1671896Y507631D02*
X1671979Y508173D01*
X1672104Y508631D01*
X1672271Y509048D01*
X1672479Y509506D01*
X1672812Y510131D01*
X1671146D01*
G01X1661726Y511931D02*
Y514431D01*
X1662767D01*
X1663101Y514306D01*
X1663309Y514139D01*
X1663392Y513806D01*
X1663309Y513473D01*
X1663059Y513264D01*
X1662767Y513139D01*
X1661726D01*
G01X1662767D02*
X1663392Y511931D01*
G01X1665659D02*
X1665951Y511973D01*
X1666284Y512098D01*
X1666492Y512306D01*
X1666576Y512598D01*
X1666492Y512889D01*
X1666242Y513139D01*
X1665867Y513264D01*
X1665451D01*
X1665201Y513348D01*
X1664992Y513556D01*
X1664909Y513848D01*
X1665034Y514139D01*
X1665326Y514348D01*
X1665659Y514431D01*
X1665992Y514348D01*
X1666284Y514139D01*
X1666409Y513848D01*
X1666326Y513556D01*
X1666117Y513348D01*
X1665867Y513264D01*
X1665451D01*
X1665076Y513139D01*
X1664826Y512889D01*
X1664742Y512598D01*
X1664826Y512306D01*
X1665034Y512098D01*
X1665367Y511973D01*
X1665659Y511931D01*
G01X1669092Y513264D02*
X1669259Y513389D01*
X1669384Y513598D01*
X1669467Y513889D01*
X1669384Y514139D01*
X1669217Y514306D01*
X1668926Y514431D01*
X1667801D01*
Y511931D01*
X1669176D01*
X1669467Y512098D01*
X1669634Y512348D01*
X1669717Y512639D01*
X1669634Y512931D01*
X1669384Y513181D01*
X1669092Y513264D01*
X1667801D01*
G01X1671067Y512973D02*
X1671359Y513264D01*
X1671609Y513431D01*
X1671942Y513514D01*
X1672234Y513431D01*
X1672442Y513264D01*
X1672609Y513014D01*
X1672651Y512723D01*
X1672609Y512473D01*
X1672442Y512223D01*
X1672192Y512014D01*
X1671901Y511931D01*
X1671567Y512014D01*
X1671276Y512264D01*
X1671109Y512639D01*
X1671067Y513056D01*
X1671151Y513598D01*
X1671276Y513889D01*
X1671484Y514181D01*
X1671776Y514389D01*
X1672067Y514431D01*
X1672359Y514348D01*
X1672567Y514139D01*
G01X1701000Y507417D02*
X1698500D01*
Y508458D01*
X1698625Y508792D01*
X1698792Y509000D01*
X1699125Y509083D01*
X1699458Y509000D01*
X1699667Y508750D01*
X1699792Y508458D01*
Y507417D01*
G01Y508458D02*
X1701000Y509083D01*
G01Y511350D02*
X1700958Y511642D01*
X1700833Y511975D01*
X1700625Y512183D01*
X1700333Y512267D01*
X1700042Y512183D01*
X1699792Y511933D01*
X1699667Y511558D01*
Y511142D01*
X1699583Y510892D01*
X1699375Y510683D01*
X1699083Y510600D01*
X1698792Y510725D01*
X1698583Y511017D01*
X1698500Y511350D01*
X1698583Y511683D01*
X1698792Y511975D01*
X1699083Y512100D01*
X1699375Y512017D01*
X1699583Y511808D01*
X1699667Y511558D01*
Y511142D01*
X1699792Y510767D01*
X1700042Y510517D01*
X1700333Y510433D01*
X1700625Y510517D01*
X1700833Y510725D01*
X1700958Y511058D01*
X1701000Y511350D01*
G01X1699667Y514783D02*
X1699542Y514950D01*
X1699333Y515075D01*
X1699042Y515158D01*
X1698792Y515075D01*
X1698625Y514908D01*
X1698500Y514617D01*
Y513492D01*
X1701000D01*
Y514867D01*
X1700833Y515158D01*
X1700583Y515325D01*
X1700292Y515408D01*
X1700000Y515325D01*
X1699750Y515075D01*
X1699667Y514783D01*
Y513492D01*
G01X1701000Y518050D02*
X1698500D01*
X1700292Y516508D01*
Y518592D01*
G01X1697334Y505167D02*
X1694834D01*
Y506208D01*
X1694959Y506542D01*
X1695126Y506750D01*
X1695459Y506833D01*
X1695792Y506750D01*
X1696001Y506500D01*
X1696126Y506208D01*
Y505167D01*
G01Y506208D02*
X1697334Y506833D01*
G01Y509100D02*
X1697292Y509392D01*
X1697167Y509725D01*
X1696959Y509933D01*
X1696667Y510017D01*
X1696376Y509933D01*
X1696126Y509683D01*
X1696001Y509308D01*
Y508892D01*
X1695917Y508642D01*
X1695709Y508433D01*
X1695417Y508350D01*
X1695126Y508475D01*
X1694917Y508767D01*
X1694834Y509100D01*
X1694917Y509433D01*
X1695126Y509725D01*
X1695417Y509850D01*
X1695709Y509767D01*
X1695917Y509558D01*
X1696001Y509308D01*
Y508892D01*
X1696126Y508517D01*
X1696376Y508267D01*
X1696667Y508183D01*
X1696959Y508267D01*
X1697167Y508475D01*
X1697292Y508808D01*
X1697334Y509100D01*
G01Y513033D02*
Y511367D01*
X1694834D01*
Y513033D01*
G01X1696042Y512367D02*
Y511367D01*
G01X1697334Y515300D02*
X1694834D01*
X1695334Y514800D01*
G01X1697334D02*
Y515800D01*
G01X1695251Y517608D02*
X1695001Y517858D01*
X1694876Y518150D01*
X1694834Y518483D01*
X1694917Y518900D01*
X1695126Y519192D01*
X1695376Y519275D01*
X1695626Y519233D01*
X1695834Y519067D01*
X1696251Y518233D01*
X1696542Y517858D01*
X1696959Y517608D01*
X1697334Y517525D01*
Y519275D01*
G01X1673764Y475966D02*
Y478466D01*
X1674805D01*
X1675139Y478341D01*
X1675347Y478174D01*
X1675430Y477841D01*
X1675347Y477508D01*
X1675097Y477299D01*
X1674805Y477174D01*
X1673764D01*
G01X1674805D02*
X1675430Y475966D01*
G01X1677697D02*
X1677989Y476008D01*
X1678322Y476133D01*
X1678530Y476341D01*
X1678614Y476633D01*
X1678530Y476924D01*
X1678280Y477174D01*
X1677905Y477299D01*
X1677489D01*
X1677239Y477383D01*
X1677030Y477591D01*
X1676947Y477883D01*
X1677072Y478174D01*
X1677364Y478383D01*
X1677697Y478466D01*
X1678030Y478383D01*
X1678322Y478174D01*
X1678447Y477883D01*
X1678364Y477591D01*
X1678155Y477383D01*
X1677905Y477299D01*
X1677489D01*
X1677114Y477174D01*
X1676864Y476924D01*
X1676780Y476633D01*
X1676864Y476341D01*
X1677072Y476133D01*
X1677405Y476008D01*
X1677697Y475966D01*
G01X1681130Y477299D02*
X1681297Y477424D01*
X1681422Y477633D01*
X1681505Y477924D01*
X1681422Y478174D01*
X1681255Y478341D01*
X1680964Y478466D01*
X1679839D01*
Y475966D01*
X1681214D01*
X1681505Y476133D01*
X1681672Y476383D01*
X1681755Y476674D01*
X1681672Y476966D01*
X1681422Y477216D01*
X1681130Y477299D01*
X1679839D01*
G01X1683897Y475966D02*
Y478466D01*
X1683397Y477966D01*
G01Y475966D02*
X1684397D01*
G01X1686997D02*
Y478466D01*
X1686497Y477966D01*
G01Y475966D02*
X1687497D01*
G01X1673764Y479566D02*
Y482066D01*
X1674805D01*
X1675139Y481941D01*
X1675347Y481774D01*
X1675430Y481441D01*
X1675347Y481108D01*
X1675097Y480899D01*
X1674805Y480774D01*
X1673764D01*
G01X1674805D02*
X1675430Y479566D01*
G01X1677697D02*
X1677989Y479608D01*
X1678322Y479733D01*
X1678530Y479941D01*
X1678614Y480233D01*
X1678530Y480524D01*
X1678280Y480774D01*
X1677905Y480899D01*
X1677489D01*
X1677239Y480983D01*
X1677030Y481191D01*
X1676947Y481483D01*
X1677072Y481774D01*
X1677364Y481983D01*
X1677697Y482066D01*
X1678030Y481983D01*
X1678322Y481774D01*
X1678447Y481483D01*
X1678364Y481191D01*
X1678155Y480983D01*
X1677905Y480899D01*
X1677489D01*
X1677114Y480774D01*
X1676864Y480524D01*
X1676780Y480233D01*
X1676864Y479941D01*
X1677072Y479733D01*
X1677405Y479608D01*
X1677697Y479566D01*
G01X1681130Y480899D02*
X1681297Y481024D01*
X1681422Y481233D01*
X1681505Y481524D01*
X1681422Y481774D01*
X1681255Y481941D01*
X1680964Y482066D01*
X1679839D01*
Y479566D01*
X1681214D01*
X1681505Y479733D01*
X1681672Y479983D01*
X1681755Y480274D01*
X1681672Y480566D01*
X1681422Y480816D01*
X1681130Y480899D01*
X1679839D01*
G01X1683897Y479566D02*
Y482066D01*
X1683397Y481566D01*
G01Y479566D02*
X1684397D01*
G01X1686997Y482066D02*
X1686664Y481983D01*
X1686414Y481774D01*
X1686247Y481524D01*
X1686122Y481191D01*
X1686080Y480816D01*
X1686122Y480441D01*
X1686247Y480108D01*
X1686414Y479858D01*
X1686664Y479649D01*
X1686997Y479566D01*
X1687330Y479649D01*
X1687580Y479858D01*
X1687747Y480108D01*
X1687872Y480441D01*
X1687914Y480816D01*
X1687872Y481191D01*
X1687747Y481524D01*
X1687580Y481774D01*
X1687330Y481983D01*
X1686997Y482066D01*
G01X1661517Y503700D02*
Y506200D01*
X1662558D01*
X1662892Y506075D01*
X1663100Y505908D01*
X1663183Y505575D01*
X1663100Y505242D01*
X1662850Y505033D01*
X1662558Y504908D01*
X1661517D01*
G01X1662558D02*
X1663183Y503700D01*
G01X1665450D02*
X1665742Y503742D01*
X1666075Y503867D01*
X1666283Y504075D01*
X1666367Y504367D01*
X1666283Y504658D01*
X1666033Y504908D01*
X1665658Y505033D01*
X1665242D01*
X1664992Y505117D01*
X1664783Y505325D01*
X1664700Y505617D01*
X1664825Y505908D01*
X1665117Y506117D01*
X1665450Y506200D01*
X1665783Y506117D01*
X1666075Y505908D01*
X1666200Y505617D01*
X1666117Y505325D01*
X1665908Y505117D01*
X1665658Y505033D01*
X1665242D01*
X1664867Y504908D01*
X1664617Y504658D01*
X1664533Y504367D01*
X1664617Y504075D01*
X1664825Y503867D01*
X1665158Y503742D01*
X1665450Y503700D01*
G01X1668883Y505033D02*
X1669050Y505158D01*
X1669175Y505367D01*
X1669258Y505658D01*
X1669175Y505908D01*
X1669008Y506075D01*
X1668717Y506200D01*
X1667592D01*
Y503700D01*
X1668967D01*
X1669258Y503867D01*
X1669425Y504117D01*
X1669508Y504408D01*
X1669425Y504700D01*
X1669175Y504950D01*
X1668883Y505033D01*
X1667592D01*
G01X1671650Y503700D02*
X1671942Y503742D01*
X1672275Y503867D01*
X1672483Y504075D01*
X1672567Y504367D01*
X1672483Y504658D01*
X1672233Y504908D01*
X1671858Y505033D01*
X1671442D01*
X1671192Y505117D01*
X1670983Y505325D01*
X1670900Y505617D01*
X1671025Y505908D01*
X1671317Y506117D01*
X1671650Y506200D01*
X1671983Y506117D01*
X1672275Y505908D01*
X1672400Y505617D01*
X1672317Y505325D01*
X1672108Y505117D01*
X1671858Y505033D01*
X1671442D01*
X1671067Y504908D01*
X1670817Y504658D01*
X1670733Y504367D01*
X1670817Y504075D01*
X1671025Y503867D01*
X1671358Y503742D01*
X1671650Y503700D01*
G01X1704677Y509268D02*
X1704552Y509018D01*
X1704469Y508726D01*
Y508393D01*
X1704594Y508018D01*
X1704802Y507726D01*
X1705052Y507518D01*
X1705469Y507351D01*
X1705844Y507309D01*
X1706219Y507393D01*
X1706469Y507518D01*
X1706719Y507768D01*
X1706886Y508059D01*
X1706969Y508351D01*
Y508643D01*
X1706886Y508934D01*
X1706761Y509184D01*
X1706594Y509393D01*
G01X1706969Y511451D02*
X1706927Y511743D01*
X1706802Y512076D01*
X1706594Y512284D01*
X1706302Y512368D01*
X1706011Y512284D01*
X1705761Y512034D01*
X1705636Y511659D01*
Y511243D01*
X1705552Y510993D01*
X1705344Y510784D01*
X1705052Y510701D01*
X1704761Y510826D01*
X1704552Y511118D01*
X1704469Y511451D01*
X1704552Y511784D01*
X1704761Y512076D01*
X1705052Y512201D01*
X1705344Y512118D01*
X1705552Y511909D01*
X1705636Y511659D01*
Y511243D01*
X1705761Y510868D01*
X1706011Y510618D01*
X1706302Y510534D01*
X1706594Y510618D01*
X1706802Y510826D01*
X1706927Y511159D01*
X1706969Y511451D01*
G01X1705636Y514884D02*
X1705511Y515051D01*
X1705302Y515176D01*
X1705011Y515259D01*
X1704761Y515176D01*
X1704594Y515009D01*
X1704469Y514718D01*
Y513593D01*
X1706969D01*
Y514968D01*
X1706802Y515259D01*
X1706552Y515426D01*
X1706261Y515509D01*
X1705969Y515426D01*
X1705719Y515176D01*
X1705636Y514884D01*
Y513593D01*
G01X1706594Y516734D02*
X1706802Y516984D01*
X1706927Y517276D01*
X1706969Y517651D01*
X1706886Y518026D01*
X1706719Y518318D01*
X1706427Y518526D01*
X1706094Y518568D01*
X1705761Y518484D01*
X1705552Y518276D01*
X1705386Y517984D01*
X1705344Y517693D01*
X1705386Y517401D01*
X1705552Y517026D01*
X1704469Y517151D01*
Y518276D01*
G01X1684067Y503059D02*
X1683817Y503184D01*
X1683525Y503267D01*
X1683192D01*
X1682817Y503142D01*
X1682525Y502934D01*
X1682317Y502684D01*
X1682150Y502267D01*
X1682108Y501892D01*
X1682192Y501517D01*
X1682317Y501267D01*
X1682567Y501017D01*
X1682858Y500850D01*
X1683150Y500767D01*
X1683442D01*
X1683733Y500850D01*
X1683983Y500975D01*
X1684192Y501142D01*
G01X1686250Y500767D02*
X1686542Y500809D01*
X1686875Y500934D01*
X1687083Y501142D01*
X1687167Y501434D01*
X1687083Y501725D01*
X1686833Y501975D01*
X1686458Y502100D01*
X1686042D01*
X1685792Y502184D01*
X1685583Y502392D01*
X1685500Y502684D01*
X1685625Y502975D01*
X1685917Y503184D01*
X1686250Y503267D01*
X1686583Y503184D01*
X1686875Y502975D01*
X1687000Y502684D01*
X1686917Y502392D01*
X1686708Y502184D01*
X1686458Y502100D01*
X1686042D01*
X1685667Y501975D01*
X1685417Y501725D01*
X1685333Y501434D01*
X1685417Y501142D01*
X1685625Y500934D01*
X1685958Y500809D01*
X1686250Y500767D01*
G01X1689683Y502100D02*
X1689850Y502225D01*
X1689975Y502434D01*
X1690058Y502725D01*
X1689975Y502975D01*
X1689808Y503142D01*
X1689517Y503267D01*
X1688392D01*
Y500767D01*
X1689767D01*
X1690058Y500934D01*
X1690225Y501184D01*
X1690308Y501475D01*
X1690225Y501767D01*
X1689975Y502017D01*
X1689683Y502100D01*
X1688392D01*
G01X1692450Y500767D02*
X1692742Y500809D01*
X1693075Y500934D01*
X1693283Y501142D01*
X1693367Y501434D01*
X1693283Y501725D01*
X1693033Y501975D01*
X1692658Y502100D01*
X1692242D01*
X1691992Y502184D01*
X1691783Y502392D01*
X1691700Y502684D01*
X1691825Y502975D01*
X1692117Y503184D01*
X1692450Y503267D01*
X1692783Y503184D01*
X1693075Y502975D01*
X1693200Y502684D01*
X1693117Y502392D01*
X1692908Y502184D01*
X1692658Y502100D01*
X1692242D01*
X1691867Y501975D01*
X1691617Y501725D01*
X1691533Y501434D01*
X1691617Y501142D01*
X1691825Y500934D01*
X1692158Y500809D01*
X1692450Y500767D01*
G01X1703883Y503400D02*
X1702217D01*
Y505900D01*
X1703883D01*
G01X1703217Y504692D02*
X1702217D01*
G01X1705233Y505900D02*
Y504108D01*
X1705400Y503733D01*
X1705733Y503483D01*
X1706150Y503400D01*
X1706567Y503483D01*
X1706900Y503733D01*
X1707067Y504108D01*
Y505900D01*
G01X1709250Y503400D02*
X1709542Y503442D01*
X1709875Y503567D01*
X1710083Y503775D01*
X1710167Y504067D01*
X1710083Y504358D01*
X1709833Y504608D01*
X1709458Y504733D01*
X1709042D01*
X1708792Y504817D01*
X1708583Y505025D01*
X1708500Y505317D01*
X1708625Y505608D01*
X1708917Y505817D01*
X1709250Y505900D01*
X1709583Y505817D01*
X1709875Y505608D01*
X1710000Y505317D01*
X1709917Y505025D01*
X1709708Y504817D01*
X1709458Y504733D01*
X1709042D01*
X1708667Y504608D01*
X1708417Y504358D01*
X1708333Y504067D01*
X1708417Y503775D01*
X1708625Y503567D01*
X1708958Y503442D01*
X1709250Y503400D01*
G01X1712683Y504733D02*
X1712850Y504858D01*
X1712975Y505067D01*
X1713058Y505358D01*
X1712975Y505608D01*
X1712808Y505775D01*
X1712517Y505900D01*
X1711392D01*
Y503400D01*
X1712767D01*
X1713058Y503567D01*
X1713225Y503817D01*
X1713308Y504108D01*
X1713225Y504400D01*
X1712975Y504650D01*
X1712683Y504733D01*
X1711392D01*
G01X1715450Y503400D02*
Y505900D01*
X1714950Y505400D01*
G01Y503400D02*
X1715950D01*
G01X1662139Y480421D02*
X1662369Y480731D01*
X1662637Y480886D01*
X1662944Y480938D01*
X1663327Y480835D01*
X1663595Y480576D01*
X1663672Y480266D01*
X1663634Y479956D01*
X1663480Y479698D01*
X1662714Y479181D01*
X1662369Y478820D01*
X1662139Y478303D01*
X1662062Y477838D01*
X1663672D01*
G01X1666427D02*
Y480938D01*
X1665009Y478716D01*
X1666925D01*
G01X1661322Y519183D02*
X1661552Y519493D01*
X1661820Y519648D01*
X1662127Y519700D01*
X1662510Y519597D01*
X1662778Y519338D01*
X1662855Y519028D01*
X1662817Y518718D01*
X1662663Y518460D01*
X1661897Y517943D01*
X1661552Y517582D01*
X1661322Y517065D01*
X1661245Y516600D01*
X1662855D01*
G01X1658820Y474031D02*
X1659028Y473781D01*
X1659278Y473614D01*
X1659570Y473531D01*
X1659903Y473614D01*
X1660153Y473781D01*
X1660403Y474031D01*
X1660486Y474364D01*
Y476031D01*
G01X1662753Y473531D02*
X1663045Y473573D01*
X1663378Y473698D01*
X1663586Y473906D01*
X1663670Y474198D01*
X1663586Y474489D01*
X1663336Y474739D01*
X1662961Y474864D01*
X1662545D01*
X1662295Y474948D01*
X1662086Y475156D01*
X1662003Y475448D01*
X1662128Y475739D01*
X1662420Y475948D01*
X1662753Y476031D01*
X1663086Y475948D01*
X1663378Y475739D01*
X1663503Y475448D01*
X1663420Y475156D01*
X1663211Y474948D01*
X1662961Y474864D01*
X1662545D01*
X1662170Y474739D01*
X1661920Y474489D01*
X1661836Y474198D01*
X1661920Y473906D01*
X1662128Y473698D01*
X1662461Y473573D01*
X1662753Y473531D01*
G01X1666186Y474864D02*
X1666353Y474989D01*
X1666478Y475198D01*
X1666561Y475489D01*
X1666478Y475739D01*
X1666311Y475906D01*
X1666020Y476031D01*
X1664895D01*
Y473531D01*
X1666270D01*
X1666561Y473698D01*
X1666728Y473948D01*
X1666811Y474239D01*
X1666728Y474531D01*
X1666478Y474781D01*
X1666186Y474864D01*
X1664895D01*
G01X1668953Y473531D02*
Y476031D01*
X1668453Y475531D01*
G01Y473531D02*
X1669453D01*
G01X1652467Y529588D02*
X1657324D01*
Y525541D01*
G01Y476362D02*
Y472305D01*
X1652467D01*
G01X1707350Y484667D02*
X1707017Y484709D01*
X1706725Y484875D01*
X1706475Y485125D01*
X1706308Y485417D01*
X1706225Y485750D01*
Y486084D01*
X1706308Y486417D01*
X1706475Y486709D01*
X1706725Y486959D01*
X1707017Y487125D01*
X1707350Y487167D01*
X1707683Y487125D01*
X1707975Y486959D01*
X1708225Y486709D01*
X1708392Y486417D01*
X1708475Y486084D01*
Y485750D01*
X1708392Y485417D01*
X1708225Y485125D01*
X1707975Y484875D01*
X1707683Y484709D01*
X1707350Y484667D01*
G01X1707683Y485334D02*
X1708183Y484667D01*
G01X1710450D02*
X1710742Y484709D01*
X1711075Y484834D01*
X1711283Y485042D01*
X1711367Y485334D01*
X1711283Y485625D01*
X1711033Y485875D01*
X1710658Y486000D01*
X1710242D01*
X1709992Y486084D01*
X1709783Y486292D01*
X1709700Y486584D01*
X1709825Y486875D01*
X1710117Y487084D01*
X1710450Y487167D01*
X1710783Y487084D01*
X1711075Y486875D01*
X1711200Y486584D01*
X1711117Y486292D01*
X1710908Y486084D01*
X1710658Y486000D01*
X1710242D01*
X1709867Y485875D01*
X1709617Y485625D01*
X1709533Y485334D01*
X1709617Y485042D01*
X1709825Y484834D01*
X1710158Y484709D01*
X1710450Y484667D01*
G01X1713883Y486000D02*
X1714050Y486125D01*
X1714175Y486334D01*
X1714258Y486625D01*
X1714175Y486875D01*
X1714008Y487042D01*
X1713717Y487167D01*
X1712592D01*
Y484667D01*
X1713967D01*
X1714258Y484834D01*
X1714425Y485084D01*
X1714508Y485375D01*
X1714425Y485667D01*
X1714175Y485917D01*
X1713883Y486000D01*
X1712592D01*
G01X1716650Y484667D02*
Y487167D01*
X1716150Y486667D01*
G01Y484667D02*
X1717150D01*
G01X1720466Y489067D02*
X1707080D01*
G01X1720466Y502453D02*
X1707080D01*
G01X1794234Y545585D02*
Y520685D01*
X1654034D01*
Y545585D01*
X1794234D01*
G01X1703545Y547613D02*
X1703852Y547355D01*
X1704197Y547200D01*
X1704503D01*
X1704810Y547355D01*
X1705040Y547613D01*
X1705155Y547975D01*
X1705078Y548337D01*
X1704887Y548647D01*
X1704542Y548853D01*
X1704082Y548957D01*
X1703813Y549163D01*
X1703698Y549525D01*
X1703775Y549887D01*
X1703967Y550145D01*
X1704235Y550300D01*
X1704503D01*
X1704772Y550197D01*
X1705002Y549938D01*
G01X1706492Y547200D02*
X1707450Y550300D01*
X1708408Y547200D01*
G01X1708063Y548285D02*
X1706837D01*
G01X1710550Y550300D02*
Y547200D01*
G01X1709668Y550300D02*
X1711432D01*
G01X1712692Y547200D02*
X1713650Y550300D01*
X1714608Y547200D01*
G01X1714263Y548285D02*
X1713037D01*
G01X1719850Y547200D02*
Y550300D01*
X1719390Y549680D01*
G01Y547200D02*
X1720310D01*
G01X1722107Y547820D02*
X1722337Y547458D01*
X1722643Y547252D01*
X1722988Y547200D01*
X1723295Y547252D01*
X1723602Y547510D01*
X1723793Y547820D01*
X1723832Y548130D01*
X1723755Y548492D01*
X1723487Y548750D01*
X1723218Y548853D01*
X1722873D01*
G01X1723218D02*
X1723448Y549008D01*
X1723640Y549267D01*
X1723717Y549577D01*
X1723640Y549887D01*
X1723448Y550145D01*
X1723103Y550300D01*
X1722758Y550248D01*
X1722413Y550042D01*
G01X1728383Y547200D02*
Y550300D01*
X1729303D01*
X1729610Y550145D01*
X1729840Y549783D01*
X1729917Y549370D01*
X1729840Y548957D01*
X1729648Y548647D01*
X1729303Y548492D01*
X1728383D01*
G01X1731790Y550300D02*
X1732710D01*
G01X1732250D02*
Y547200D01*
G01X1731790D02*
X1732710D01*
G01X1734468D02*
Y550300D01*
X1736232Y547200D01*
Y550300D01*
G01X1742393Y550042D02*
X1742163Y550197D01*
X1741895Y550300D01*
X1741588D01*
X1741243Y550145D01*
X1740975Y549887D01*
X1740783Y549577D01*
X1740630Y549060D01*
X1740592Y548595D01*
X1740668Y548130D01*
X1740783Y547820D01*
X1741013Y547510D01*
X1741282Y547303D01*
X1741550Y547200D01*
X1741818D01*
X1742087Y547303D01*
X1742317Y547458D01*
X1742508Y547665D01*
G01X1744650Y547200D02*
X1744343Y547252D01*
X1744075Y547458D01*
X1743845Y547768D01*
X1743692Y548130D01*
X1743615Y548543D01*
Y548957D01*
X1743692Y549370D01*
X1743845Y549732D01*
X1744075Y550042D01*
X1744343Y550248D01*
X1744650Y550300D01*
X1744957Y550248D01*
X1745225Y550042D01*
X1745455Y549732D01*
X1745608Y549370D01*
X1745685Y548957D01*
Y548543D01*
X1745608Y548130D01*
X1745455Y547768D01*
X1745225Y547458D01*
X1744957Y547252D01*
X1744650Y547200D01*
G01X1746868D02*
Y550300D01*
X1748632Y547200D01*
Y550300D01*
G01X1749968Y547200D02*
Y550300D01*
X1751732Y547200D01*
Y550300D01*
G01X1670850Y551800D02*
Y554900D01*
X1670390Y554280D01*
G01Y551800D02*
X1671310D01*
G01X1673107D02*
Y554900D01*
X1673873D01*
X1674180Y554745D01*
X1674410Y554538D01*
X1674602Y554228D01*
X1674755Y553867D01*
X1674793Y553350D01*
X1674755Y552833D01*
X1674602Y552472D01*
X1674410Y552162D01*
X1674180Y551955D01*
X1673873Y551800D01*
X1673107D01*
G01X1677050D02*
Y554900D01*
X1676590Y554280D01*
G01Y551800D02*
X1677510D01*
G01X1758167Y5700D02*
Y8200D01*
X1759208D01*
X1759542Y8075D01*
X1759750Y7908D01*
X1759833Y7575D01*
X1759750Y7242D01*
X1759500Y7033D01*
X1759208Y6908D01*
X1758167D01*
G01X1759208D02*
X1759833Y5700D01*
G01X1762017D02*
X1762100Y6242D01*
X1762225Y6700D01*
X1762392Y7117D01*
X1762600Y7575D01*
X1762933Y8200D01*
X1761267D01*
G01X1764283Y5700D02*
Y8200D01*
X1765117D01*
X1765450Y8075D01*
X1765700Y7908D01*
X1765908Y7658D01*
X1766075Y7367D01*
X1766117Y6950D01*
X1766075Y6533D01*
X1765908Y6242D01*
X1765700Y5992D01*
X1765450Y5825D01*
X1765117Y5700D01*
X1764283D01*
G01X1767383Y6200D02*
X1767633Y5908D01*
X1767967Y5742D01*
X1768342Y5700D01*
X1768675Y5742D01*
X1769008Y5950D01*
X1769217Y6200D01*
X1769258Y6450D01*
X1769175Y6742D01*
X1768883Y6950D01*
X1768592Y7033D01*
X1768217D01*
G01X1768592D02*
X1768842Y7158D01*
X1769050Y7367D01*
X1769133Y7617D01*
X1769050Y7867D01*
X1768842Y8075D01*
X1768467Y8200D01*
X1768092Y8158D01*
X1767717Y7992D01*
G01X1771400Y8200D02*
X1771067Y8117D01*
X1770817Y7908D01*
X1770650Y7658D01*
X1770525Y7325D01*
X1770483Y6950D01*
X1770525Y6575D01*
X1770650Y6242D01*
X1770817Y5992D01*
X1771067Y5783D01*
X1771400Y5700D01*
X1771733Y5783D01*
X1771983Y5992D01*
X1772150Y6242D01*
X1772275Y6575D01*
X1772317Y6950D01*
X1772275Y7325D01*
X1772150Y7658D01*
X1771983Y7908D01*
X1771733Y8117D01*
X1771400Y8200D01*
G01X1729217Y5550D02*
Y8050D01*
X1730258D01*
X1730592Y7925D01*
X1730800Y7758D01*
X1730883Y7425D01*
X1730800Y7092D01*
X1730550Y6883D01*
X1730258Y6758D01*
X1729217D01*
G01X1730258D02*
X1730883Y5550D01*
G01X1732358Y7633D02*
X1732608Y7883D01*
X1732900Y8008D01*
X1733233Y8050D01*
X1733650Y7967D01*
X1733942Y7758D01*
X1734025Y7508D01*
X1733983Y7258D01*
X1733817Y7050D01*
X1732983Y6633D01*
X1732608Y6342D01*
X1732358Y5925D01*
X1732275Y5550D01*
X1734025D01*
G01X1735417D02*
Y8050D01*
X1736417D01*
X1736750Y7925D01*
X1737000Y7633D01*
X1737083Y7300D01*
X1737000Y6967D01*
X1736792Y6717D01*
X1736417Y6592D01*
X1735417D01*
G01X1739350Y5550D02*
Y8050D01*
X1738850Y7550D01*
G01Y5550D02*
X1739850D01*
G01X1741742Y5842D02*
X1742033Y5633D01*
X1742367Y5550D01*
X1742700Y5633D01*
X1742992Y5883D01*
X1743200Y6258D01*
X1743283Y6633D01*
Y7092D01*
X1743200Y7467D01*
X1742992Y7800D01*
X1742742Y7967D01*
X1742450Y8050D01*
X1742117Y7967D01*
X1741867Y7800D01*
X1741700Y7550D01*
X1741617Y7217D01*
X1741700Y6925D01*
X1741908Y6633D01*
X1742158Y6467D01*
X1742450Y6425D01*
X1742783Y6508D01*
X1743033Y6717D01*
X1743283Y7092D01*
G01X1759858Y-19821D02*
Y-16721D01*
X1759398Y-17341D01*
G01Y-19821D02*
X1760318D01*
G01X1762958D02*
Y-16721D01*
X1762498Y-17341D01*
G01Y-19821D02*
X1763418D01*
G01X1762500Y-250D02*
X1759400D01*
X1760020Y-710D01*
G01X1762500D02*
Y210D01*
G01X1759917Y2122D02*
X1759607Y2352D01*
X1759452Y2620D01*
X1759400Y2927D01*
X1759503Y3310D01*
X1759762Y3578D01*
X1760072Y3655D01*
X1760382Y3617D01*
X1760640Y3463D01*
X1761157Y2697D01*
X1761518Y2352D01*
X1762035Y2122D01*
X1762500Y2045D01*
Y3655D01*
G01X1726720Y1400D02*
X1726928Y1150D01*
X1727178Y983D01*
X1727470Y900D01*
X1727803Y983D01*
X1728053Y1150D01*
X1728303Y1400D01*
X1728386Y1733D01*
Y3400D01*
G01X1730653Y900D02*
X1730945Y942D01*
X1731278Y1067D01*
X1731486Y1275D01*
X1731570Y1567D01*
X1731486Y1858D01*
X1731236Y2108D01*
X1730861Y2233D01*
X1730445D01*
X1730195Y2317D01*
X1729986Y2525D01*
X1729903Y2817D01*
X1730028Y3108D01*
X1730320Y3317D01*
X1730653Y3400D01*
X1730986Y3317D01*
X1731278Y3108D01*
X1731403Y2817D01*
X1731320Y2525D01*
X1731111Y2317D01*
X1730861Y2233D01*
X1730445D01*
X1730070Y2108D01*
X1729820Y1858D01*
X1729736Y1567D01*
X1729820Y1275D01*
X1730028Y1067D01*
X1730361Y942D01*
X1730653Y900D01*
G01X1734003Y2150D02*
X1734836D01*
Y1400D01*
X1734586Y1150D01*
X1734295Y983D01*
X1733878Y900D01*
X1733461Y983D01*
X1733170Y1150D01*
X1732920Y1400D01*
X1732753Y1692D01*
X1732670Y2025D01*
Y2317D01*
X1732753Y2567D01*
X1732920Y2858D01*
X1733170Y3108D01*
X1733420Y3275D01*
X1733753Y3400D01*
X1734045D01*
X1734378Y3317D01*
X1734628Y3150D01*
G01X1736061Y2983D02*
X1736311Y3233D01*
X1736603Y3358D01*
X1736936Y3400D01*
X1737353Y3317D01*
X1737645Y3108D01*
X1737728Y2858D01*
X1737686Y2608D01*
X1737520Y2400D01*
X1736686Y1983D01*
X1736311Y1692D01*
X1736061Y1275D01*
X1735978Y900D01*
X1737728D01*
G01X1758003Y-200D02*
Y-201D01*
G01Y-19800D02*
Y-19799D01*
G01X1761752Y-2661D02*
X1761982Y-2351D01*
X1762250Y-2196D01*
X1762557Y-2144D01*
X1762940Y-2247D01*
X1763208Y-2506D01*
X1763285Y-2816D01*
X1763247Y-3126D01*
X1763093Y-3384D01*
X1762327Y-3901D01*
X1761982Y-4262D01*
X1761752Y-4779D01*
X1761675Y-5244D01*
X1763285D01*
G01X1766387Y1720D02*
X1766595Y1470D01*
X1766845Y1303D01*
X1767137Y1220D01*
X1767470Y1303D01*
X1767720Y1470D01*
X1767970Y1720D01*
X1768053Y2053D01*
Y3720D01*
G01X1769612Y1512D02*
X1769903Y1303D01*
X1770237Y1220D01*
X1770570Y1303D01*
X1770862Y1553D01*
X1771070Y1928D01*
X1771153Y2303D01*
Y2762D01*
X1771070Y3137D01*
X1770862Y3470D01*
X1770612Y3637D01*
X1770320Y3720D01*
X1769987Y3637D01*
X1769737Y3470D01*
X1769570Y3220D01*
X1769487Y2887D01*
X1769570Y2595D01*
X1769778Y2303D01*
X1770028Y2137D01*
X1770320Y2095D01*
X1770653Y2178D01*
X1770903Y2387D01*
X1771153Y2762D01*
G01X1773670Y2470D02*
X1774503D01*
Y1720D01*
X1774253Y1470D01*
X1773962Y1303D01*
X1773545Y1220D01*
X1773128Y1303D01*
X1772837Y1470D01*
X1772587Y1720D01*
X1772420Y2012D01*
X1772337Y2345D01*
Y2637D01*
X1772420Y2887D01*
X1772587Y3178D01*
X1772837Y3428D01*
X1773087Y3595D01*
X1773420Y3720D01*
X1773712D01*
X1774045Y3637D01*
X1774295Y3470D01*
G01X1776520Y1220D02*
Y3720D01*
X1776020Y3220D01*
G01Y1220D02*
X1777020D01*
G01X1824504Y50D02*
Y-20050D01*
X1764504D01*
Y50D01*
X1824504D01*
G01X1714267Y41800D02*
X1717600Y48800D01*
X1720933Y41800D01*
G01X1719733Y44250D02*
X1715467D01*
G01X1723267Y41800D02*
Y48800D01*
X1725933D01*
X1727000Y48450D01*
X1727800Y47983D01*
X1728467Y47283D01*
X1729000Y46467D01*
X1729133Y45300D01*
X1729000Y44133D01*
X1728467Y43317D01*
X1727800Y42616D01*
X1727000Y42150D01*
X1725933Y41800D01*
X1723267D01*
G01X1723200Y40600D02*
X1730200D01*
G01X1713400D02*
X1720500D01*
G01X1731100Y41100D02*
Y66800D01*
X1726700D01*
Y71100D01*
X1716500D01*
G01X1716630Y79617D02*
X1714130D01*
Y80658D01*
X1714255Y80992D01*
X1714422Y81200D01*
X1714755Y81283D01*
X1715088Y81200D01*
X1715297Y80950D01*
X1715422Y80658D01*
Y79617D01*
G01Y80658D02*
X1716630Y81283D01*
G01Y83550D02*
X1714130D01*
X1714630Y83050D01*
G01X1716630D02*
Y84050D01*
G01X1714130Y86650D02*
X1714213Y86317D01*
X1714422Y86067D01*
X1714672Y85900D01*
X1715005Y85775D01*
X1715380Y85733D01*
X1715755Y85775D01*
X1716088Y85900D01*
X1716338Y86067D01*
X1716547Y86317D01*
X1716630Y86650D01*
X1716547Y86983D01*
X1716338Y87233D01*
X1716088Y87400D01*
X1715755Y87525D01*
X1715380Y87567D01*
X1715005Y87525D01*
X1714672Y87400D01*
X1714422Y87233D01*
X1714213Y86983D01*
X1714130Y86650D01*
G01Y88500D02*
X1716630Y89083D01*
X1714130Y89750D01*
X1716630Y90417D01*
X1714130Y91000D01*
G01X1714547Y92058D02*
X1714297Y92308D01*
X1714172Y92600D01*
X1714130Y92933D01*
X1714213Y93350D01*
X1714422Y93642D01*
X1714672Y93725D01*
X1714922Y93683D01*
X1715130Y93517D01*
X1715547Y92683D01*
X1715838Y92308D01*
X1716255Y92058D01*
X1716630Y91975D01*
Y93725D01*
G01X1740770Y71587D02*
X1738270D01*
Y72628D01*
X1738395Y72962D01*
X1738562Y73170D01*
X1738895Y73253D01*
X1739228Y73170D01*
X1739437Y72920D01*
X1739562Y72628D01*
Y71587D01*
G01Y72628D02*
X1740770Y73253D01*
G01Y75520D02*
X1738270D01*
X1738770Y75020D01*
G01X1740770D02*
Y76020D01*
G01X1738270Y78620D02*
X1738353Y78287D01*
X1738562Y78037D01*
X1738812Y77870D01*
X1739145Y77745D01*
X1739520Y77703D01*
X1739895Y77745D01*
X1740228Y77870D01*
X1740478Y78037D01*
X1740687Y78287D01*
X1740770Y78620D01*
X1740687Y78953D01*
X1740478Y79203D01*
X1740228Y79370D01*
X1739895Y79495D01*
X1739520Y79537D01*
X1739145Y79495D01*
X1738812Y79370D01*
X1738562Y79203D01*
X1738353Y78953D01*
X1738270Y78620D01*
G01Y80470D02*
X1740770Y81053D01*
X1738270Y81720D01*
X1740770Y82387D01*
X1738270Y82970D01*
G01X1740770Y84820D02*
X1738270D01*
X1738770Y84320D01*
G01X1740770D02*
Y85320D01*
G01X1733770Y71587D02*
X1731270D01*
Y72628D01*
X1731395Y72962D01*
X1731562Y73170D01*
X1731895Y73253D01*
X1732228Y73170D01*
X1732437Y72920D01*
X1732562Y72628D01*
Y71587D01*
G01Y72628D02*
X1733770Y73253D01*
G01X1731687Y74728D02*
X1731437Y74978D01*
X1731312Y75270D01*
X1731270Y75603D01*
X1731353Y76020D01*
X1731562Y76312D01*
X1731812Y76395D01*
X1732062Y76353D01*
X1732270Y76187D01*
X1732687Y75353D01*
X1732978Y74978D01*
X1733395Y74728D01*
X1733770Y74645D01*
Y76395D01*
G01X1733395Y77703D02*
X1733603Y77953D01*
X1733728Y78245D01*
X1733770Y78620D01*
X1733687Y78995D01*
X1733520Y79287D01*
X1733228Y79495D01*
X1732895Y79537D01*
X1732562Y79453D01*
X1732353Y79245D01*
X1732187Y78953D01*
X1732145Y78662D01*
X1732187Y78370D01*
X1732353Y77995D01*
X1731270Y78120D01*
Y79245D01*
G01Y80470D02*
X1733770Y81053D01*
X1731270Y81720D01*
X1733770Y82387D01*
X1731270Y82970D01*
G01X1733770Y84820D02*
X1731270D01*
X1731770Y84320D01*
G01X1733770D02*
Y85320D01*
G01Y88420D02*
X1731270D01*
X1733062Y86878D01*
Y88962D01*
G01X1731687Y90228D02*
X1731437Y90478D01*
X1731312Y90770D01*
X1731270Y91103D01*
X1731353Y91520D01*
X1731562Y91812D01*
X1731812Y91895D01*
X1732062Y91853D01*
X1732270Y91687D01*
X1732687Y90853D01*
X1732978Y90478D01*
X1733395Y90228D01*
X1733770Y90145D01*
Y91895D01*
G01X1735767Y40900D02*
Y43400D01*
X1736808D01*
X1737142Y43275D01*
X1737350Y43108D01*
X1737433Y42775D01*
X1737350Y42442D01*
X1737100Y42233D01*
X1736808Y42108D01*
X1735767D01*
G01X1736808D02*
X1737433Y40900D01*
G01X1738992Y41192D02*
X1739283Y40983D01*
X1739617Y40900D01*
X1739950Y40983D01*
X1740242Y41233D01*
X1740450Y41608D01*
X1740533Y41983D01*
Y42442D01*
X1740450Y42817D01*
X1740242Y43150D01*
X1739992Y43317D01*
X1739700Y43400D01*
X1739367Y43317D01*
X1739117Y43150D01*
X1738950Y42900D01*
X1738867Y42567D01*
X1738950Y42275D01*
X1739158Y41983D01*
X1739408Y41817D01*
X1739700Y41775D01*
X1740033Y41858D01*
X1740283Y42067D01*
X1740533Y42442D01*
G01X1743050Y42150D02*
X1743883D01*
Y41400D01*
X1743633Y41150D01*
X1743342Y40983D01*
X1742925Y40900D01*
X1742508Y40983D01*
X1742217Y41150D01*
X1741967Y41400D01*
X1741800Y41692D01*
X1741717Y42025D01*
Y42317D01*
X1741800Y42567D01*
X1741967Y42858D01*
X1742217Y43108D01*
X1742467Y43275D01*
X1742800Y43400D01*
X1743092D01*
X1743425Y43317D01*
X1743675Y43150D01*
G01X1744983Y41400D02*
X1745233Y41108D01*
X1745567Y40942D01*
X1745942Y40900D01*
X1746275Y40942D01*
X1746608Y41150D01*
X1746817Y41400D01*
X1746858Y41650D01*
X1746775Y41942D01*
X1746483Y42150D01*
X1746192Y42233D01*
X1745817D01*
G01X1746192D02*
X1746442Y42358D01*
X1746650Y42567D01*
X1746733Y42817D01*
X1746650Y43067D01*
X1746442Y43275D01*
X1746067Y43400D01*
X1745692Y43358D01*
X1745317Y43192D01*
G01X1749500Y40900D02*
Y43400D01*
X1747958Y41608D01*
X1750042D01*
G01X1731967Y57700D02*
Y60200D01*
X1733008D01*
X1733342Y60075D01*
X1733550Y59908D01*
X1733633Y59575D01*
X1733550Y59242D01*
X1733300Y59033D01*
X1733008Y58908D01*
X1731967D01*
G01X1733008D02*
X1733633Y57700D01*
G01X1735108Y59783D02*
X1735358Y60033D01*
X1735650Y60158D01*
X1735983Y60200D01*
X1736400Y60117D01*
X1736692Y59908D01*
X1736775Y59658D01*
X1736733Y59408D01*
X1736567Y59200D01*
X1735733Y58783D01*
X1735358Y58492D01*
X1735108Y58075D01*
X1735025Y57700D01*
X1736775D01*
G01X1738083Y60200D02*
Y58408D01*
X1738250Y58033D01*
X1738583Y57783D01*
X1739000Y57700D01*
X1739417Y57783D01*
X1739750Y58033D01*
X1739917Y58408D01*
Y60200D01*
G01X1742600Y57700D02*
Y60200D01*
X1741058Y58408D01*
X1743142D01*
G01X1745200Y60200D02*
X1744867Y60117D01*
X1744617Y59908D01*
X1744450Y59658D01*
X1744325Y59325D01*
X1744283Y58950D01*
X1744325Y58575D01*
X1744450Y58242D01*
X1744617Y57992D01*
X1744867Y57783D01*
X1745200Y57700D01*
X1745533Y57783D01*
X1745783Y57992D01*
X1745950Y58242D01*
X1746075Y58575D01*
X1746117Y58950D01*
X1746075Y59325D01*
X1745950Y59658D01*
X1745783Y59908D01*
X1745533Y60117D01*
X1745200Y60200D01*
G01X1735767Y44400D02*
Y46900D01*
X1736808D01*
X1737142Y46775D01*
X1737350Y46608D01*
X1737433Y46275D01*
X1737350Y45942D01*
X1737100Y45733D01*
X1736808Y45608D01*
X1735767D01*
G01X1736808D02*
X1737433Y44400D01*
G01X1738908Y46483D02*
X1739158Y46733D01*
X1739450Y46858D01*
X1739783Y46900D01*
X1740200Y46817D01*
X1740492Y46608D01*
X1740575Y46358D01*
X1740533Y46108D01*
X1740367Y45900D01*
X1739533Y45483D01*
X1739158Y45192D01*
X1738908Y44775D01*
X1738825Y44400D01*
X1740575D01*
G01X1741883Y46900D02*
Y45108D01*
X1742050Y44733D01*
X1742383Y44483D01*
X1742800Y44400D01*
X1743217Y44483D01*
X1743550Y44733D01*
X1743717Y45108D01*
Y46900D01*
G01X1744983Y44775D02*
X1745233Y44567D01*
X1745525Y44442D01*
X1745900Y44400D01*
X1746275Y44483D01*
X1746567Y44650D01*
X1746775Y44942D01*
X1746817Y45275D01*
X1746733Y45608D01*
X1746525Y45817D01*
X1746233Y45983D01*
X1745942Y46025D01*
X1745650Y45983D01*
X1745275Y45817D01*
X1745400Y46900D01*
X1746525D01*
G01X1749000Y44400D02*
Y46900D01*
X1748500Y46400D01*
G01Y44400D02*
X1749500D01*
G01X1755167Y43300D02*
Y45800D01*
X1756208D01*
X1756542Y45675D01*
X1756750Y45508D01*
X1756833Y45175D01*
X1756750Y44842D01*
X1756500Y44633D01*
X1756208Y44508D01*
X1755167D01*
G01X1756208D02*
X1756833Y43300D01*
G01X1758308Y45383D02*
X1758558Y45633D01*
X1758850Y45758D01*
X1759183Y45800D01*
X1759600Y45717D01*
X1759892Y45508D01*
X1759975Y45258D01*
X1759933Y45008D01*
X1759767Y44800D01*
X1758933Y44383D01*
X1758558Y44092D01*
X1758308Y43675D01*
X1758225Y43300D01*
X1759975D01*
G01X1761283Y43675D02*
X1761533Y43467D01*
X1761825Y43342D01*
X1762200Y43300D01*
X1762575Y43383D01*
X1762867Y43550D01*
X1763075Y43842D01*
X1763117Y44175D01*
X1763033Y44508D01*
X1762825Y44717D01*
X1762533Y44883D01*
X1762242Y44925D01*
X1761950Y44883D01*
X1761575Y44717D01*
X1761700Y45800D01*
X1762825D01*
G01X1764050D02*
X1764633Y43300D01*
X1765300Y45800D01*
X1765967Y43300D01*
X1766550Y45800D01*
G01X1768400Y43300D02*
Y45800D01*
X1767900Y45300D01*
G01Y43300D02*
X1768900D01*
G01X1770583Y43675D02*
X1770833Y43467D01*
X1771125Y43342D01*
X1771500Y43300D01*
X1771875Y43383D01*
X1772167Y43550D01*
X1772375Y43842D01*
X1772417Y44175D01*
X1772333Y44508D01*
X1772125Y44717D01*
X1771833Y44883D01*
X1771542Y44925D01*
X1771250Y44883D01*
X1770875Y44717D01*
X1771000Y45800D01*
X1772125D01*
G01X1773683Y43800D02*
X1773933Y43508D01*
X1774267Y43342D01*
X1774642Y43300D01*
X1774975Y43342D01*
X1775308Y43550D01*
X1775517Y43800D01*
X1775558Y44050D01*
X1775475Y44342D01*
X1775183Y44550D01*
X1774892Y44633D01*
X1774517D01*
G01X1774892D02*
X1775142Y44758D01*
X1775350Y44967D01*
X1775433Y45217D01*
X1775350Y45467D01*
X1775142Y45675D01*
X1774767Y45800D01*
X1774392Y45758D01*
X1774017Y45592D01*
G01X1755867Y71100D02*
Y73600D01*
X1756908D01*
X1757242Y73475D01*
X1757450Y73308D01*
X1757533Y72975D01*
X1757450Y72642D01*
X1757200Y72433D01*
X1756908Y72308D01*
X1755867D01*
G01X1756908D02*
X1757533Y71100D01*
G01X1759092Y71392D02*
X1759383Y71183D01*
X1759717Y71100D01*
X1760050Y71183D01*
X1760342Y71433D01*
X1760550Y71808D01*
X1760633Y72183D01*
Y72642D01*
X1760550Y73017D01*
X1760342Y73350D01*
X1760092Y73517D01*
X1759800Y73600D01*
X1759467Y73517D01*
X1759217Y73350D01*
X1759050Y73100D01*
X1758967Y72767D01*
X1759050Y72475D01*
X1759258Y72183D01*
X1759508Y72017D01*
X1759800Y71975D01*
X1760133Y72058D01*
X1760383Y72267D01*
X1760633Y72642D01*
G01X1761650Y73600D02*
X1762233Y71100D01*
X1762900Y73600D01*
X1763567Y71100D01*
X1764150Y73600D01*
G01X1765083Y71600D02*
X1765333Y71308D01*
X1765667Y71142D01*
X1766042Y71100D01*
X1766375Y71142D01*
X1766708Y71350D01*
X1766917Y71600D01*
X1766958Y71850D01*
X1766875Y72142D01*
X1766583Y72350D01*
X1766292Y72433D01*
X1765917D01*
G01X1766292D02*
X1766542Y72558D01*
X1766750Y72767D01*
X1766833Y73017D01*
X1766750Y73267D01*
X1766542Y73475D01*
X1766167Y73600D01*
X1765792Y73558D01*
X1765417Y73392D01*
G01X1768308Y73183D02*
X1768558Y73433D01*
X1768850Y73558D01*
X1769183Y73600D01*
X1769600Y73517D01*
X1769892Y73308D01*
X1769975Y73058D01*
X1769933Y72808D01*
X1769767Y72600D01*
X1768933Y72183D01*
X1768558Y71892D01*
X1768308Y71475D01*
X1768225Y71100D01*
X1769975D01*
G01X1755867Y67600D02*
Y70100D01*
X1756908D01*
X1757242Y69975D01*
X1757450Y69808D01*
X1757533Y69475D01*
X1757450Y69142D01*
X1757200Y68933D01*
X1756908Y68808D01*
X1755867D01*
G01X1756908D02*
X1757533Y67600D01*
G01X1759092Y67892D02*
X1759383Y67683D01*
X1759717Y67600D01*
X1760050Y67683D01*
X1760342Y67933D01*
X1760550Y68308D01*
X1760633Y68683D01*
Y69142D01*
X1760550Y69517D01*
X1760342Y69850D01*
X1760092Y70017D01*
X1759800Y70100D01*
X1759467Y70017D01*
X1759217Y69850D01*
X1759050Y69600D01*
X1758967Y69267D01*
X1759050Y68975D01*
X1759258Y68683D01*
X1759508Y68517D01*
X1759800Y68475D01*
X1760133Y68558D01*
X1760383Y68767D01*
X1760633Y69142D01*
G01X1761650Y70100D02*
X1762233Y67600D01*
X1762900Y70100D01*
X1763567Y67600D01*
X1764150Y70100D01*
G01X1766000Y67600D02*
Y70100D01*
X1765500Y69600D01*
G01Y67600D02*
X1766500D01*
G01X1768308Y69683D02*
X1768558Y69933D01*
X1768850Y70058D01*
X1769183Y70100D01*
X1769600Y70017D01*
X1769892Y69808D01*
X1769975Y69558D01*
X1769933Y69308D01*
X1769767Y69100D01*
X1768933Y68683D01*
X1768558Y68392D01*
X1768308Y67975D01*
X1768225Y67600D01*
X1769975D01*
G01X1749720Y59537D02*
X1747220D01*
Y60578D01*
X1747345Y60912D01*
X1747512Y61120D01*
X1747845Y61203D01*
X1748178Y61120D01*
X1748387Y60870D01*
X1748512Y60578D01*
Y59537D01*
G01Y60578D02*
X1749720Y61203D01*
G01Y63470D02*
X1747220D01*
X1747720Y62970D01*
G01X1749720D02*
Y63970D01*
G01X1747220Y65320D02*
X1749720Y65903D01*
X1747220Y66570D01*
X1749720Y67237D01*
X1747220Y67820D01*
G01X1749428Y68962D02*
X1749637Y69253D01*
X1749720Y69587D01*
X1749637Y69920D01*
X1749387Y70212D01*
X1749012Y70420D01*
X1748637Y70503D01*
X1748178D01*
X1747803Y70420D01*
X1747470Y70212D01*
X1747303Y69962D01*
X1747220Y69670D01*
X1747303Y69337D01*
X1747470Y69087D01*
X1747720Y68920D01*
X1748053Y68837D01*
X1748345Y68920D01*
X1748637Y69128D01*
X1748803Y69378D01*
X1748845Y69670D01*
X1748762Y70003D01*
X1748553Y70253D01*
X1748178Y70503D01*
G01X1718667Y90710D02*
Y93210D01*
X1719708D01*
X1720042Y93085D01*
X1720250Y92918D01*
X1720333Y92585D01*
X1720250Y92252D01*
X1720000Y92043D01*
X1719708Y91918D01*
X1718667D01*
G01X1719708D02*
X1720333Y90710D01*
G01X1722600D02*
Y93210D01*
X1722100Y92710D01*
G01Y90710D02*
X1723100D01*
G01X1724783Y93210D02*
Y91418D01*
X1724950Y91043D01*
X1725283Y90793D01*
X1725700Y90710D01*
X1726117Y90793D01*
X1726450Y91043D01*
X1726617Y91418D01*
Y93210D01*
G01X1728800Y90710D02*
Y93210D01*
X1728300Y92710D01*
G01Y90710D02*
X1729300D01*
G01X1755083Y42300D02*
Y40508D01*
X1755250Y40133D01*
X1755583Y39883D01*
X1756000Y39800D01*
X1756417Y39883D01*
X1756750Y40133D01*
X1756917Y40508D01*
Y42300D01*
G01X1758308Y41883D02*
X1758558Y42133D01*
X1758850Y42258D01*
X1759183Y42300D01*
X1759600Y42217D01*
X1759892Y42008D01*
X1759975Y41758D01*
X1759933Y41508D01*
X1759767Y41300D01*
X1758933Y40883D01*
X1758558Y40592D01*
X1758308Y40175D01*
X1758225Y39800D01*
X1759975D01*
G01X1761283Y40175D02*
X1761533Y39967D01*
X1761825Y39842D01*
X1762200Y39800D01*
X1762575Y39883D01*
X1762867Y40050D01*
X1763075Y40342D01*
X1763117Y40675D01*
X1763033Y41008D01*
X1762825Y41217D01*
X1762533Y41383D01*
X1762242Y41425D01*
X1761950Y41383D01*
X1761575Y41217D01*
X1761700Y42300D01*
X1762825D01*
G01X1764050D02*
X1764633Y39800D01*
X1765300Y42300D01*
X1765967Y39800D01*
X1766550Y42300D01*
G01X1767692Y40092D02*
X1767983Y39883D01*
X1768317Y39800D01*
X1768650Y39883D01*
X1768942Y40133D01*
X1769150Y40508D01*
X1769233Y40883D01*
Y41342D01*
X1769150Y41717D01*
X1768942Y42050D01*
X1768692Y42217D01*
X1768400Y42300D01*
X1768067Y42217D01*
X1767817Y42050D01*
X1767650Y41800D01*
X1767567Y41467D01*
X1767650Y41175D01*
X1767858Y40883D01*
X1768108Y40717D01*
X1768400Y40675D01*
X1768733Y40758D01*
X1768983Y40967D01*
X1769233Y41342D01*
G01X1734978Y73337D02*
X1734853Y73087D01*
X1734770Y72795D01*
Y72462D01*
X1734895Y72087D01*
X1735103Y71795D01*
X1735353Y71587D01*
X1735770Y71420D01*
X1736145Y71378D01*
X1736520Y71462D01*
X1736770Y71587D01*
X1737020Y71837D01*
X1737187Y72128D01*
X1737270Y72420D01*
Y72712D01*
X1737187Y73003D01*
X1737062Y73253D01*
X1736895Y73462D01*
G01X1737270Y75520D02*
X1734770D01*
X1735270Y75020D01*
G01X1737270D02*
Y76020D01*
G01X1734770Y78620D02*
X1734853Y78287D01*
X1735062Y78037D01*
X1735312Y77870D01*
X1735645Y77745D01*
X1736020Y77703D01*
X1736395Y77745D01*
X1736728Y77870D01*
X1736978Y78037D01*
X1737187Y78287D01*
X1737270Y78620D01*
X1737187Y78953D01*
X1736978Y79203D01*
X1736728Y79370D01*
X1736395Y79495D01*
X1736020Y79537D01*
X1735645Y79495D01*
X1735312Y79370D01*
X1735062Y79203D01*
X1734853Y78953D01*
X1734770Y78620D01*
G01Y80470D02*
X1737270Y81053D01*
X1734770Y81720D01*
X1737270Y82387D01*
X1734770Y82970D01*
G01X1736770Y83903D02*
X1737062Y84153D01*
X1737228Y84487D01*
X1737270Y84862D01*
X1737228Y85195D01*
X1737020Y85528D01*
X1736770Y85737D01*
X1736520Y85778D01*
X1736228Y85695D01*
X1736020Y85403D01*
X1735937Y85112D01*
Y84737D01*
G01Y85112D02*
X1735812Y85362D01*
X1735603Y85570D01*
X1735353Y85653D01*
X1735103Y85570D01*
X1734895Y85362D01*
X1734770Y84987D01*
X1734812Y84612D01*
X1734978Y84237D01*
G01X1750808Y77167D02*
X1750683Y76917D01*
X1750600Y76625D01*
Y76292D01*
X1750725Y75917D01*
X1750933Y75625D01*
X1751183Y75417D01*
X1751600Y75250D01*
X1751975Y75208D01*
X1752350Y75292D01*
X1752600Y75417D01*
X1752850Y75667D01*
X1753017Y75958D01*
X1753100Y76250D01*
Y76542D01*
X1753017Y76833D01*
X1752892Y77083D01*
X1752725Y77292D01*
G01X1751017Y78558D02*
X1750767Y78808D01*
X1750642Y79100D01*
X1750600Y79433D01*
X1750683Y79850D01*
X1750892Y80142D01*
X1751142Y80225D01*
X1751392Y80183D01*
X1751600Y80017D01*
X1752017Y79183D01*
X1752308Y78808D01*
X1752725Y78558D01*
X1753100Y78475D01*
Y80225D01*
G01X1752725Y81533D02*
X1752933Y81783D01*
X1753058Y82075D01*
X1753100Y82450D01*
X1753017Y82825D01*
X1752850Y83117D01*
X1752558Y83325D01*
X1752225Y83367D01*
X1751892Y83283D01*
X1751683Y83075D01*
X1751517Y82783D01*
X1751475Y82492D01*
X1751517Y82200D01*
X1751683Y81825D01*
X1750600Y81950D01*
Y83075D01*
G01Y84300D02*
X1753100Y84883D01*
X1750600Y85550D01*
X1753100Y86217D01*
X1750600Y86800D01*
G01X1753100Y88650D02*
X1750600D01*
X1751100Y88150D01*
G01X1753100D02*
Y89150D01*
G01X1752725Y90833D02*
X1752933Y91083D01*
X1753058Y91375D01*
X1753100Y91750D01*
X1753017Y92125D01*
X1752850Y92417D01*
X1752558Y92625D01*
X1752225Y92667D01*
X1751892Y92583D01*
X1751683Y92375D01*
X1751517Y92083D01*
X1751475Y91792D01*
X1751517Y91500D01*
X1751683Y91125D01*
X1750600Y91250D01*
Y92375D01*
G01X1747308Y77167D02*
X1747183Y76917D01*
X1747100Y76625D01*
Y76292D01*
X1747225Y75917D01*
X1747433Y75625D01*
X1747683Y75417D01*
X1748100Y75250D01*
X1748475Y75208D01*
X1748850Y75292D01*
X1749100Y75417D01*
X1749350Y75667D01*
X1749517Y75958D01*
X1749600Y76250D01*
Y76542D01*
X1749517Y76833D01*
X1749392Y77083D01*
X1749225Y77292D01*
G01X1747517Y78558D02*
X1747267Y78808D01*
X1747142Y79100D01*
X1747100Y79433D01*
X1747183Y79850D01*
X1747392Y80142D01*
X1747642Y80225D01*
X1747892Y80183D01*
X1748100Y80017D01*
X1748517Y79183D01*
X1748808Y78808D01*
X1749225Y78558D01*
X1749600Y78475D01*
Y80225D01*
G01X1749225Y81533D02*
X1749433Y81783D01*
X1749558Y82075D01*
X1749600Y82450D01*
X1749517Y82825D01*
X1749350Y83117D01*
X1749058Y83325D01*
X1748725Y83367D01*
X1748392Y83283D01*
X1748183Y83075D01*
X1748017Y82783D01*
X1747975Y82492D01*
X1748017Y82200D01*
X1748183Y81825D01*
X1747100Y81950D01*
Y83075D01*
G01Y84300D02*
X1749600Y84883D01*
X1747100Y85550D01*
X1749600Y86217D01*
X1747100Y86800D01*
G01X1749600Y88650D02*
X1747100D01*
X1747600Y88150D01*
G01X1749600D02*
Y89150D01*
G01Y92250D02*
X1747100D01*
X1748892Y90708D01*
Y92792D01*
G01X1750928Y61287D02*
X1750803Y61037D01*
X1750720Y60745D01*
Y60412D01*
X1750845Y60037D01*
X1751053Y59745D01*
X1751303Y59537D01*
X1751720Y59370D01*
X1752095Y59328D01*
X1752470Y59412D01*
X1752720Y59537D01*
X1752970Y59787D01*
X1753137Y60078D01*
X1753220Y60370D01*
Y60662D01*
X1753137Y60953D01*
X1753012Y61203D01*
X1752845Y61412D01*
G01X1752928Y62762D02*
X1753137Y63053D01*
X1753220Y63387D01*
X1753137Y63720D01*
X1752887Y64012D01*
X1752512Y64220D01*
X1752137Y64303D01*
X1751678D01*
X1751303Y64220D01*
X1750970Y64012D01*
X1750803Y63762D01*
X1750720Y63470D01*
X1750803Y63137D01*
X1750970Y62887D01*
X1751220Y62720D01*
X1751553Y62637D01*
X1751845Y62720D01*
X1752137Y62928D01*
X1752303Y63178D01*
X1752345Y63470D01*
X1752262Y63803D01*
X1752053Y64053D01*
X1751678Y64303D01*
G01X1750720Y65320D02*
X1753220Y65903D01*
X1750720Y66570D01*
X1753220Y67237D01*
X1750720Y67820D01*
G01X1753220Y69670D02*
X1750720D01*
X1751220Y69170D01*
G01X1753220D02*
Y70170D01*
G01X1750720Y72770D02*
X1750803Y72437D01*
X1751012Y72187D01*
X1751262Y72020D01*
X1751595Y71895D01*
X1751970Y71853D01*
X1752345Y71895D01*
X1752678Y72020D01*
X1752928Y72187D01*
X1753137Y72437D01*
X1753220Y72770D01*
X1753137Y73103D01*
X1752928Y73353D01*
X1752678Y73520D01*
X1752345Y73645D01*
X1751970Y73687D01*
X1751595Y73645D01*
X1751262Y73520D01*
X1751012Y73353D01*
X1750803Y73103D01*
X1750720Y72770D01*
G01X1743528Y63137D02*
X1743403Y62887D01*
X1743320Y62595D01*
Y62262D01*
X1743445Y61887D01*
X1743653Y61595D01*
X1743903Y61387D01*
X1744320Y61220D01*
X1744695Y61178D01*
X1745070Y61262D01*
X1745320Y61387D01*
X1745570Y61637D01*
X1745737Y61928D01*
X1745820Y62220D01*
Y62512D01*
X1745737Y62803D01*
X1745612Y63053D01*
X1745445Y63262D01*
G01X1745820Y64487D02*
X1743320D01*
Y65528D01*
X1743445Y65862D01*
X1743612Y66070D01*
X1743945Y66153D01*
X1744278Y66070D01*
X1744487Y65820D01*
X1744612Y65528D01*
Y64487D01*
G01Y65528D02*
X1745820Y66153D01*
G01Y68420D02*
X1743320D01*
X1743820Y67920D01*
G01X1745820D02*
Y68920D01*
G01X1743320Y71520D02*
X1743403Y71187D01*
X1743612Y70937D01*
X1743862Y70770D01*
X1744195Y70645D01*
X1744570Y70603D01*
X1744945Y70645D01*
X1745278Y70770D01*
X1745528Y70937D01*
X1745737Y71187D01*
X1745820Y71520D01*
X1745737Y71853D01*
X1745528Y72103D01*
X1745278Y72270D01*
X1744945Y72395D01*
X1744570Y72437D01*
X1744195Y72395D01*
X1743862Y72270D01*
X1743612Y72103D01*
X1743403Y71853D01*
X1743320Y71520D01*
G01Y73370D02*
X1745820Y73953D01*
X1743320Y74620D01*
X1745820Y75287D01*
X1743320Y75870D01*
G01X1745820Y77720D02*
X1743320D01*
X1743820Y77220D01*
G01X1745820D02*
Y78220D01*
G01X1724443Y89549D02*
Y85126D01*
G01X1726336D02*
X1722550D01*
G01X1724443Y78258D02*
Y81847D01*
X1722550D01*
X1724443Y85126D01*
X1726336Y81847D01*
X1724443D01*
G01X1775000Y63367D02*
X1772500D01*
Y64408D01*
X1772625Y64742D01*
X1772792Y64950D01*
X1773125Y65033D01*
X1773458Y64950D01*
X1773667Y64700D01*
X1773792Y64408D01*
Y63367D01*
G01Y64408D02*
X1775000Y65033D01*
G01X1774708Y66592D02*
X1774917Y66883D01*
X1775000Y67217D01*
X1774917Y67550D01*
X1774667Y67842D01*
X1774292Y68050D01*
X1773917Y68133D01*
X1773458D01*
X1773083Y68050D01*
X1772750Y67842D01*
X1772583Y67592D01*
X1772500Y67300D01*
X1772583Y66967D01*
X1772750Y66717D01*
X1773000Y66550D01*
X1773333Y66467D01*
X1773625Y66550D01*
X1773917Y66758D01*
X1774083Y67008D01*
X1774125Y67300D01*
X1774042Y67633D01*
X1773833Y67883D01*
X1773458Y68133D01*
G01X1772500Y69150D02*
X1775000Y69733D01*
X1772500Y70400D01*
X1775000Y71067D01*
X1772500Y71650D01*
G01X1774500Y72583D02*
X1774792Y72833D01*
X1774958Y73167D01*
X1775000Y73542D01*
X1774958Y73875D01*
X1774750Y74208D01*
X1774500Y74417D01*
X1774250Y74458D01*
X1773958Y74375D01*
X1773750Y74083D01*
X1773667Y73792D01*
Y73417D01*
G01Y73792D02*
X1773542Y74042D01*
X1773333Y74250D01*
X1773083Y74333D01*
X1772833Y74250D01*
X1772625Y74042D01*
X1772500Y73667D01*
X1772542Y73292D01*
X1772708Y72917D01*
G01X1775000Y76600D02*
X1772500D01*
X1773000Y76100D01*
G01X1775000D02*
Y77100D01*
G01X1773508Y49767D02*
X1773383Y49517D01*
X1773300Y49225D01*
Y48892D01*
X1773425Y48517D01*
X1773633Y48225D01*
X1773883Y48017D01*
X1774300Y47850D01*
X1774675Y47808D01*
X1775050Y47892D01*
X1775300Y48017D01*
X1775550Y48267D01*
X1775717Y48558D01*
X1775800Y48850D01*
Y49142D01*
X1775717Y49433D01*
X1775592Y49683D01*
X1775425Y49892D01*
G01X1775800Y51950D02*
X1775758Y52242D01*
X1775633Y52575D01*
X1775425Y52783D01*
X1775133Y52867D01*
X1774842Y52783D01*
X1774592Y52533D01*
X1774467Y52158D01*
Y51742D01*
X1774383Y51492D01*
X1774175Y51283D01*
X1773883Y51200D01*
X1773592Y51325D01*
X1773383Y51617D01*
X1773300Y51950D01*
X1773383Y52283D01*
X1773592Y52575D01*
X1773883Y52700D01*
X1774175Y52617D01*
X1774383Y52408D01*
X1774467Y52158D01*
Y51742D01*
X1774592Y51367D01*
X1774842Y51117D01*
X1775133Y51033D01*
X1775425Y51117D01*
X1775633Y51325D01*
X1775758Y51658D01*
X1775800Y51950D01*
G01Y54258D02*
X1773300D01*
Y55842D01*
G01X1774508Y55258D02*
Y54258D01*
G01X1775800Y58150D02*
X1775758Y58442D01*
X1775633Y58775D01*
X1775425Y58983D01*
X1775133Y59067D01*
X1774842Y58983D01*
X1774592Y58733D01*
X1774467Y58358D01*
Y57942D01*
X1774383Y57692D01*
X1774175Y57483D01*
X1773883Y57400D01*
X1773592Y57525D01*
X1773383Y57817D01*
X1773300Y58150D01*
X1773383Y58483D01*
X1773592Y58775D01*
X1773883Y58900D01*
X1774175Y58817D01*
X1774383Y58608D01*
X1774467Y58358D01*
Y57942D01*
X1774592Y57567D01*
X1774842Y57317D01*
X1775133Y57233D01*
X1775425Y57317D01*
X1775633Y57525D01*
X1775758Y57858D01*
X1775800Y58150D01*
G01X1714069Y151098D02*
X1749503D01*
Y95980D01*
X1714069D01*
Y151098D01*
G01X1793400Y106400D02*
Y117900D01*
X1805400D01*
Y125400D01*
X1802700D01*
Y132300D01*
X1790000D01*
Y147000D01*
X1784000D01*
Y155800D01*
X1772400D01*
Y180800D01*
X1724300D01*
G01X1762606Y98732D02*
X1762356Y98857D01*
X1762064Y98940D01*
X1761731D01*
X1761356Y98815D01*
X1761064Y98607D01*
X1760856Y98357D01*
X1760689Y97940D01*
X1760647Y97565D01*
X1760731Y97190D01*
X1760856Y96940D01*
X1761106Y96690D01*
X1761397Y96523D01*
X1761689Y96440D01*
X1761981D01*
X1762272Y96523D01*
X1762522Y96648D01*
X1762731Y96815D01*
G01X1764081Y96732D02*
X1764372Y96523D01*
X1764706Y96440D01*
X1765039Y96523D01*
X1765331Y96773D01*
X1765539Y97148D01*
X1765622Y97523D01*
Y97982D01*
X1765539Y98357D01*
X1765331Y98690D01*
X1765081Y98857D01*
X1764789Y98940D01*
X1764456Y98857D01*
X1764206Y98690D01*
X1764039Y98440D01*
X1763956Y98107D01*
X1764039Y97815D01*
X1764247Y97523D01*
X1764497Y97357D01*
X1764789Y97315D01*
X1765122Y97398D01*
X1765372Y97607D01*
X1765622Y97982D01*
G01X1766639Y98940D02*
X1767222Y96440D01*
X1767889Y98940D01*
X1768556Y96440D01*
X1769139Y98940D01*
G01X1770989Y96440D02*
Y98940D01*
X1770489Y98440D01*
G01Y96440D02*
X1771489D01*
G01X1773172Y96940D02*
X1773422Y96648D01*
X1773756Y96482D01*
X1774131Y96440D01*
X1774464Y96482D01*
X1774797Y96690D01*
X1775006Y96940D01*
X1775047Y97190D01*
X1774964Y97482D01*
X1774672Y97690D01*
X1774381Y97773D01*
X1774006D01*
G01X1774381D02*
X1774631Y97898D01*
X1774839Y98107D01*
X1774922Y98357D01*
X1774839Y98607D01*
X1774631Y98815D01*
X1774256Y98940D01*
X1773881Y98898D01*
X1773506Y98732D01*
G01X1762606Y102232D02*
X1762356Y102357D01*
X1762064Y102440D01*
X1761731D01*
X1761356Y102315D01*
X1761064Y102107D01*
X1760856Y101857D01*
X1760689Y101440D01*
X1760647Y101065D01*
X1760731Y100690D01*
X1760856Y100440D01*
X1761106Y100190D01*
X1761397Y100023D01*
X1761689Y99940D01*
X1761981D01*
X1762272Y100023D01*
X1762522Y100148D01*
X1762731Y100315D01*
G01X1764789Y99940D02*
Y102440D01*
X1764289Y101940D01*
G01Y99940D02*
X1765289D01*
G01X1766639Y102440D02*
X1767222Y99940D01*
X1767889Y102440D01*
X1768556Y99940D01*
X1769139Y102440D01*
G01X1770989Y99940D02*
Y102440D01*
X1770489Y101940D01*
G01Y99940D02*
X1771489D01*
G01X1773172Y100315D02*
X1773422Y100107D01*
X1773714Y99982D01*
X1774089Y99940D01*
X1774464Y100023D01*
X1774756Y100190D01*
X1774964Y100482D01*
X1775006Y100815D01*
X1774922Y101148D01*
X1774714Y101357D01*
X1774422Y101523D01*
X1774131Y101565D01*
X1773839Y101523D01*
X1773464Y101357D01*
X1773589Y102440D01*
X1774714D01*
G01X1752567Y109492D02*
X1752317Y109617D01*
X1752025Y109700D01*
X1751692D01*
X1751317Y109575D01*
X1751025Y109367D01*
X1750817Y109117D01*
X1750650Y108700D01*
X1750608Y108325D01*
X1750692Y107950D01*
X1750817Y107700D01*
X1751067Y107450D01*
X1751358Y107283D01*
X1751650Y107200D01*
X1751942D01*
X1752233Y107283D01*
X1752483Y107408D01*
X1752692Y107575D01*
G01X1753958Y109283D02*
X1754208Y109533D01*
X1754500Y109658D01*
X1754833Y109700D01*
X1755250Y109617D01*
X1755542Y109408D01*
X1755625Y109158D01*
X1755583Y108908D01*
X1755417Y108700D01*
X1754583Y108283D01*
X1754208Y107992D01*
X1753958Y107575D01*
X1753875Y107200D01*
X1755625D01*
G01X1756933Y107575D02*
X1757183Y107367D01*
X1757475Y107242D01*
X1757850Y107200D01*
X1758225Y107283D01*
X1758517Y107450D01*
X1758725Y107742D01*
X1758767Y108075D01*
X1758683Y108408D01*
X1758475Y108617D01*
X1758183Y108783D01*
X1757892Y108825D01*
X1757600Y108783D01*
X1757225Y108617D01*
X1757350Y109700D01*
X1758475D01*
G01X1759700D02*
X1760283Y107200D01*
X1760950Y109700D01*
X1761617Y107200D01*
X1762200Y109700D01*
G01X1764050Y107200D02*
Y109700D01*
X1763550Y109200D01*
G01Y107200D02*
X1764550D01*
G01X1766442Y107492D02*
X1766733Y107283D01*
X1767067Y107200D01*
X1767400Y107283D01*
X1767692Y107533D01*
X1767900Y107908D01*
X1767983Y108283D01*
Y108742D01*
X1767900Y109117D01*
X1767692Y109450D01*
X1767442Y109617D01*
X1767150Y109700D01*
X1766817Y109617D01*
X1766567Y109450D01*
X1766400Y109200D01*
X1766317Y108867D01*
X1766400Y108575D01*
X1766608Y108283D01*
X1766858Y108117D01*
X1767150Y108075D01*
X1767483Y108158D01*
X1767733Y108367D01*
X1767983Y108742D01*
G01X1752567Y105992D02*
X1752317Y106117D01*
X1752025Y106200D01*
X1751692D01*
X1751317Y106075D01*
X1751025Y105867D01*
X1750817Y105617D01*
X1750650Y105200D01*
X1750608Y104825D01*
X1750692Y104450D01*
X1750817Y104200D01*
X1751067Y103950D01*
X1751358Y103783D01*
X1751650Y103700D01*
X1751942D01*
X1752233Y103783D01*
X1752483Y103908D01*
X1752692Y104075D01*
G01X1753958Y105783D02*
X1754208Y106033D01*
X1754500Y106158D01*
X1754833Y106200D01*
X1755250Y106117D01*
X1755542Y105908D01*
X1755625Y105658D01*
X1755583Y105408D01*
X1755417Y105200D01*
X1754583Y104783D01*
X1754208Y104492D01*
X1753958Y104075D01*
X1753875Y103700D01*
X1755625D01*
G01X1756933Y104075D02*
X1757183Y103867D01*
X1757475Y103742D01*
X1757850Y103700D01*
X1758225Y103783D01*
X1758517Y103950D01*
X1758725Y104242D01*
X1758767Y104575D01*
X1758683Y104908D01*
X1758475Y105117D01*
X1758183Y105283D01*
X1757892Y105325D01*
X1757600Y105283D01*
X1757225Y105117D01*
X1757350Y106200D01*
X1758475D01*
G01X1759700D02*
X1760283Y103700D01*
X1760950Y106200D01*
X1761617Y103700D01*
X1762200Y106200D01*
G01X1763258Y104742D02*
X1763550Y105033D01*
X1763800Y105200D01*
X1764133Y105283D01*
X1764425Y105200D01*
X1764633Y105033D01*
X1764800Y104783D01*
X1764842Y104492D01*
X1764800Y104242D01*
X1764633Y103992D01*
X1764383Y103783D01*
X1764092Y103700D01*
X1763758Y103783D01*
X1763467Y104033D01*
X1763300Y104408D01*
X1763258Y104825D01*
X1763342Y105367D01*
X1763467Y105658D01*
X1763675Y105950D01*
X1763967Y106158D01*
X1764258Y106200D01*
X1764550Y106117D01*
X1764758Y105908D01*
G01X1766770Y138750D02*
Y134750D01*
X1774170D01*
G01X1766770Y134250D02*
Y130250D01*
X1774170D01*
G01X1766770Y129750D02*
Y125750D01*
X1774170D01*
G01X1766770Y125250D02*
Y121250D01*
X1774170D01*
G01X1766770Y152750D02*
Y148750D01*
X1774170D01*
G01X1766770Y148250D02*
Y144250D01*
X1774170D01*
G01X1766770Y143250D02*
Y139250D01*
X1774170D01*
G01X1723283Y155500D02*
Y153708D01*
X1723450Y153333D01*
X1723783Y153083D01*
X1724200Y153000D01*
X1724617Y153083D01*
X1724950Y153333D01*
X1725117Y153708D01*
Y155500D01*
G01X1726508Y155083D02*
X1726758Y155333D01*
X1727050Y155458D01*
X1727383Y155500D01*
X1727800Y155417D01*
X1728092Y155208D01*
X1728175Y154958D01*
X1728133Y154708D01*
X1727967Y154500D01*
X1727133Y154083D01*
X1726758Y153792D01*
X1726508Y153375D01*
X1726425Y153000D01*
X1728175D01*
G01X1729483Y153375D02*
X1729733Y153167D01*
X1730025Y153042D01*
X1730400Y153000D01*
X1730775Y153083D01*
X1731067Y153250D01*
X1731275Y153542D01*
X1731317Y153875D01*
X1731233Y154208D01*
X1731025Y154417D01*
X1730733Y154583D01*
X1730442Y154625D01*
X1730150Y154583D01*
X1729775Y154417D01*
X1729900Y155500D01*
X1731025D01*
G01X1732250D02*
X1732833Y153000D01*
X1733500Y155500D01*
X1734167Y153000D01*
X1734750Y155500D01*
G01X1735683Y153375D02*
X1735933Y153167D01*
X1736225Y153042D01*
X1736600Y153000D01*
X1736975Y153083D01*
X1737267Y153250D01*
X1737475Y153542D01*
X1737517Y153875D01*
X1737433Y154208D01*
X1737225Y154417D01*
X1736933Y154583D01*
X1736642Y154625D01*
X1736350Y154583D01*
X1735975Y154417D01*
X1736100Y155500D01*
X1737225D01*
G01X1745953Y149341D02*
X1716425D01*
Y98159D01*
X1745953D01*
Y149341D01*
G01X1740150Y215000D02*
X1739843Y215052D01*
X1739575Y215258D01*
X1739345Y215568D01*
X1739192Y215930D01*
X1739115Y216343D01*
Y216757D01*
X1739192Y217170D01*
X1739345Y217532D01*
X1739575Y217842D01*
X1739843Y218048D01*
X1740150Y218100D01*
X1740457Y218048D01*
X1740725Y217842D01*
X1740955Y217532D01*
X1741108Y217170D01*
X1741185Y216757D01*
Y216343D01*
X1741108Y215930D01*
X1740955Y215568D01*
X1740725Y215258D01*
X1740457Y215052D01*
X1740150Y215000D01*
G01X1744093Y217842D02*
X1743863Y217997D01*
X1743595Y218100D01*
X1743288D01*
X1742943Y217945D01*
X1742675Y217687D01*
X1742483Y217377D01*
X1742330Y216860D01*
X1742292Y216395D01*
X1742368Y215930D01*
X1742483Y215620D01*
X1742713Y215310D01*
X1742982Y215103D01*
X1743250Y215000D01*
X1743518D01*
X1743787Y215103D01*
X1744017Y215258D01*
X1744208Y215465D01*
G01X1745583Y215000D02*
Y218100D01*
X1746503D01*
X1746810Y217945D01*
X1747040Y217583D01*
X1747117Y217170D01*
X1747040Y216757D01*
X1746848Y216447D01*
X1746503Y216292D01*
X1745583D01*
G01X1748300Y213967D02*
X1750600D01*
G01X1751553Y215000D02*
Y218100D01*
X1752550Y215517D01*
X1753547Y218100D01*
Y215000D01*
G01X1756417D02*
X1754883D01*
Y218100D01*
X1756417D01*
G01X1755803Y216602D02*
X1754883D01*
G01X1758022Y218100D02*
X1759478D01*
X1758022Y215000D01*
X1759478D01*
G01X1761122Y218100D02*
X1762578D01*
X1761122Y215000D01*
X1762578D01*
G01X1763800Y213967D02*
X1766100D01*
G01X1768893Y217842D02*
X1768663Y217997D01*
X1768395Y218100D01*
X1768088D01*
X1767743Y217945D01*
X1767475Y217687D01*
X1767283Y217377D01*
X1767130Y216860D01*
X1767092Y216395D01*
X1767168Y215930D01*
X1767283Y215620D01*
X1767513Y215310D01*
X1767782Y215103D01*
X1768050Y215000D01*
X1768318D01*
X1768587Y215103D01*
X1768817Y215258D01*
X1769008Y215465D01*
G01X1771150Y215000D02*
X1770843Y215052D01*
X1770575Y215258D01*
X1770345Y215568D01*
X1770192Y215930D01*
X1770115Y216343D01*
Y216757D01*
X1770192Y217170D01*
X1770345Y217532D01*
X1770575Y217842D01*
X1770843Y218048D01*
X1771150Y218100D01*
X1771457Y218048D01*
X1771725Y217842D01*
X1771955Y217532D01*
X1772108Y217170D01*
X1772185Y216757D01*
Y216343D01*
X1772108Y215930D01*
X1771955Y215568D01*
X1771725Y215258D01*
X1771457Y215052D01*
X1771150Y215000D01*
G01X1773368D02*
Y218100D01*
X1775132Y215000D01*
Y218100D01*
G01X1776468Y215000D02*
Y218100D01*
X1778232Y215000D01*
Y218100D01*
G01X1783857Y216653D02*
X1784010Y216808D01*
X1784125Y217067D01*
X1784202Y217428D01*
X1784125Y217738D01*
X1783972Y217945D01*
X1783703Y218100D01*
X1782668D01*
Y215000D01*
X1783933D01*
X1784202Y215207D01*
X1784355Y215517D01*
X1784432Y215878D01*
X1784355Y216240D01*
X1784125Y216550D01*
X1783857Y216653D01*
X1782668D01*
G01X1753967Y163900D02*
Y170900D01*
G01X1759033D02*
X1753967Y166583D01*
G01X1759833Y163900D02*
X1756233Y168567D01*
G01X1721809Y212675D02*
X1722039Y212985D01*
X1722307Y213140D01*
X1722614Y213192D01*
X1722997Y213089D01*
X1723265Y212830D01*
X1723342Y212520D01*
X1723304Y212210D01*
X1723150Y211952D01*
X1722384Y211435D01*
X1722039Y211074D01*
X1721809Y210557D01*
X1721732Y210092D01*
X1723342D01*
G01X1719924Y218558D02*
X1720132Y218308D01*
X1720382Y218141D01*
X1720674Y218058D01*
X1721007Y218141D01*
X1721257Y218308D01*
X1721507Y218558D01*
X1721590Y218891D01*
Y220558D01*
G01X1723857Y218058D02*
X1724149Y218100D01*
X1724482Y218225D01*
X1724690Y218433D01*
X1724774Y218725D01*
X1724690Y219016D01*
X1724440Y219266D01*
X1724065Y219391D01*
X1723649D01*
X1723399Y219475D01*
X1723190Y219683D01*
X1723107Y219975D01*
X1723232Y220266D01*
X1723524Y220475D01*
X1723857Y220558D01*
X1724190Y220475D01*
X1724482Y220266D01*
X1724607Y219975D01*
X1724524Y219683D01*
X1724315Y219475D01*
X1724065Y219391D01*
X1723649D01*
X1723274Y219266D01*
X1723024Y219016D01*
X1722940Y218725D01*
X1723024Y218433D01*
X1723232Y218225D01*
X1723565Y218100D01*
X1723857Y218058D01*
G01X1727790D02*
X1726124D01*
Y220558D01*
X1727790D01*
G01X1727124Y219350D02*
X1726124D01*
G01X1730557Y218058D02*
Y220558D01*
X1729015Y218766D01*
X1731099D01*
G01X1734689Y167831D02*
X1738689D01*
Y175231D01*
G01X1730189Y167831D02*
X1734189D01*
Y175231D01*
G01X1725689Y167831D02*
X1729689D01*
Y175231D01*
G01X1721189Y167831D02*
X1725189D01*
Y175231D01*
G01X1721189Y160331D02*
X1725189D01*
Y167731D01*
G01X1725689Y160331D02*
X1729689D01*
Y167731D01*
G01X1730189Y160331D02*
X1734189D01*
Y167731D01*
G01X1734689Y160331D02*
X1738689D01*
Y167731D01*
G01X1716689Y160331D02*
X1720689D01*
Y167731D01*
G01X1716689Y167781D02*
X1720689D01*
Y175181D01*
G01X1748490Y254073D02*
X1748183Y254125D01*
X1747915Y254331D01*
X1747685Y254641D01*
X1747532Y255003D01*
X1747455Y255416D01*
Y255830D01*
X1747532Y256243D01*
X1747685Y256605D01*
X1747915Y256915D01*
X1748183Y257121D01*
X1748490Y257173D01*
X1748797Y257121D01*
X1749065Y256915D01*
X1749295Y256605D01*
X1749448Y256243D01*
X1749525Y255830D01*
Y255416D01*
X1749448Y255003D01*
X1749295Y254641D01*
X1749065Y254331D01*
X1748797Y254125D01*
X1748490Y254073D01*
G01X1752433Y256915D02*
X1752203Y257070D01*
X1751935Y257173D01*
X1751628D01*
X1751283Y257018D01*
X1751015Y256760D01*
X1750823Y256450D01*
X1750670Y255933D01*
X1750632Y255468D01*
X1750708Y255003D01*
X1750823Y254693D01*
X1751053Y254383D01*
X1751322Y254176D01*
X1751590Y254073D01*
X1751858D01*
X1752127Y254176D01*
X1752357Y254331D01*
X1752548Y254538D01*
G01X1753923Y254073D02*
Y257173D01*
X1754843D01*
X1755150Y257018D01*
X1755380Y256656D01*
X1755457Y256243D01*
X1755380Y255830D01*
X1755188Y255520D01*
X1754843Y255365D01*
X1753923D01*
G01X1756640Y253040D02*
X1758940D01*
G01X1759893Y254073D02*
Y257173D01*
X1760890Y254590D01*
X1761887Y257173D01*
Y254073D01*
G01X1764757D02*
X1763223D01*
Y257173D01*
X1764757D01*
G01X1764143Y255675D02*
X1763223D01*
G01X1766362Y257173D02*
X1767818D01*
X1766362Y254073D01*
X1767818D01*
G01X1769462Y257173D02*
X1770918D01*
X1769462Y254073D01*
X1770918D01*
G01X1772140Y253040D02*
X1774440D01*
G01X1777233Y256915D02*
X1777003Y257070D01*
X1776735Y257173D01*
X1776428D01*
X1776083Y257018D01*
X1775815Y256760D01*
X1775623Y256450D01*
X1775470Y255933D01*
X1775432Y255468D01*
X1775508Y255003D01*
X1775623Y254693D01*
X1775853Y254383D01*
X1776122Y254176D01*
X1776390Y254073D01*
X1776658D01*
X1776927Y254176D01*
X1777157Y254331D01*
X1777348Y254538D01*
G01X1779490Y254073D02*
X1779183Y254125D01*
X1778915Y254331D01*
X1778685Y254641D01*
X1778532Y255003D01*
X1778455Y255416D01*
Y255830D01*
X1778532Y256243D01*
X1778685Y256605D01*
X1778915Y256915D01*
X1779183Y257121D01*
X1779490Y257173D01*
X1779797Y257121D01*
X1780065Y256915D01*
X1780295Y256605D01*
X1780448Y256243D01*
X1780525Y255830D01*
Y255416D01*
X1780448Y255003D01*
X1780295Y254641D01*
X1780065Y254331D01*
X1779797Y254125D01*
X1779490Y254073D01*
G01X1781708D02*
Y257173D01*
X1783472Y254073D01*
Y257173D01*
G01X1784808Y254073D02*
Y257173D01*
X1786572Y254073D01*
Y257173D01*
G01X1792733Y256915D02*
X1792503Y257070D01*
X1792235Y257173D01*
X1791928D01*
X1791583Y257018D01*
X1791315Y256760D01*
X1791123Y256450D01*
X1790970Y255933D01*
X1790932Y255468D01*
X1791008Y255003D01*
X1791123Y254693D01*
X1791353Y254383D01*
X1791622Y254176D01*
X1791890Y254073D01*
X1792158D01*
X1792427Y254176D01*
X1792657Y254331D01*
X1792848Y254538D01*
G01X1729445Y252614D02*
X1729675Y252252D01*
X1729981Y252046D01*
X1730326Y251994D01*
X1730633Y252046D01*
X1730940Y252304D01*
X1731131Y252614D01*
X1731170Y252924D01*
X1731093Y253286D01*
X1730825Y253544D01*
X1730556Y253647D01*
X1730211D01*
G01X1730556D02*
X1730786Y253802D01*
X1730978Y254061D01*
X1731055Y254371D01*
X1730978Y254681D01*
X1730786Y254939D01*
X1730441Y255094D01*
X1730096Y255042D01*
X1729751Y254836D01*
G01X1732545Y252614D02*
X1732775Y252252D01*
X1733081Y252046D01*
X1733426Y251994D01*
X1733733Y252046D01*
X1734040Y252304D01*
X1734231Y252614D01*
X1734270Y252924D01*
X1734193Y253286D01*
X1733925Y253544D01*
X1733656Y253647D01*
X1733311D01*
G01X1733656D02*
X1733886Y253802D01*
X1734078Y254061D01*
X1734155Y254371D01*
X1734078Y254681D01*
X1733886Y254939D01*
X1733541Y255094D01*
X1733196Y255042D01*
X1732851Y254836D01*
G01X1732149Y221749D02*
X1721162D01*
Y231630D01*
G01Y239230D02*
Y249112D01*
X1732149D01*
G01X1721400Y433466D02*
Y436566D01*
X1720940Y435946D01*
G01Y433466D02*
X1721860D01*
G01X1723772Y436049D02*
X1724002Y436359D01*
X1724270Y436514D01*
X1724577Y436566D01*
X1724960Y436463D01*
X1725228Y436204D01*
X1725305Y435894D01*
X1725267Y435584D01*
X1725113Y435326D01*
X1724347Y434809D01*
X1724002Y434448D01*
X1723772Y433931D01*
X1723695Y433466D01*
X1725305D01*
G01X1727600Y436566D02*
X1727293Y436463D01*
X1727063Y436204D01*
X1726910Y435894D01*
X1726795Y435481D01*
X1726757Y435016D01*
X1726795Y434551D01*
X1726910Y434138D01*
X1727063Y433828D01*
X1727293Y433569D01*
X1727600Y433466D01*
X1727907Y433569D01*
X1728137Y433828D01*
X1728290Y434138D01*
X1728405Y434551D01*
X1728443Y435016D01*
X1728405Y435481D01*
X1728290Y435894D01*
X1728137Y436204D01*
X1727907Y436463D01*
X1727600Y436566D01*
G01X1731204Y437497D02*
X1721362D01*
Y447340D01*
G01Y455017D02*
Y464860D01*
X1731204D01*
G01X1757750Y467900D02*
X1757443Y467952D01*
X1757175Y468158D01*
X1756945Y468468D01*
X1756792Y468830D01*
X1756715Y469243D01*
Y469657D01*
X1756792Y470070D01*
X1756945Y470432D01*
X1757175Y470742D01*
X1757443Y470948D01*
X1757750Y471000D01*
X1758057Y470948D01*
X1758325Y470742D01*
X1758555Y470432D01*
X1758708Y470070D01*
X1758785Y469657D01*
Y469243D01*
X1758708Y468830D01*
X1758555Y468468D01*
X1758325Y468158D01*
X1758057Y467952D01*
X1757750Y467900D01*
G01X1761693Y470742D02*
X1761463Y470897D01*
X1761195Y471000D01*
X1760888D01*
X1760543Y470845D01*
X1760275Y470587D01*
X1760083Y470277D01*
X1759930Y469760D01*
X1759892Y469295D01*
X1759968Y468830D01*
X1760083Y468520D01*
X1760313Y468210D01*
X1760582Y468003D01*
X1760850Y467900D01*
X1761118D01*
X1761387Y468003D01*
X1761617Y468158D01*
X1761808Y468365D01*
G01X1763183Y467900D02*
Y471000D01*
X1764103D01*
X1764410Y470845D01*
X1764640Y470483D01*
X1764717Y470070D01*
X1764640Y469657D01*
X1764448Y469347D01*
X1764103Y469192D01*
X1763183D01*
G01X1765900Y466867D02*
X1768200D01*
G01X1769153Y467900D02*
Y471000D01*
X1770150Y468417D01*
X1771147Y471000D01*
Y467900D01*
G01X1774017D02*
X1772483D01*
Y471000D01*
X1774017D01*
G01X1773403Y469502D02*
X1772483D01*
G01X1775622Y471000D02*
X1777078D01*
X1775622Y467900D01*
X1777078D01*
G01X1778722Y471000D02*
X1780178D01*
X1778722Y467900D01*
X1780178D01*
G01X1781400Y466867D02*
X1783700D01*
G01X1786493Y470742D02*
X1786263Y470897D01*
X1785995Y471000D01*
X1785688D01*
X1785343Y470845D01*
X1785075Y470587D01*
X1784883Y470277D01*
X1784730Y469760D01*
X1784692Y469295D01*
X1784768Y468830D01*
X1784883Y468520D01*
X1785113Y468210D01*
X1785382Y468003D01*
X1785650Y467900D01*
X1785918D01*
X1786187Y468003D01*
X1786417Y468158D01*
X1786608Y468365D01*
G01X1788750Y467900D02*
X1788443Y467952D01*
X1788175Y468158D01*
X1787945Y468468D01*
X1787792Y468830D01*
X1787715Y469243D01*
Y469657D01*
X1787792Y470070D01*
X1787945Y470432D01*
X1788175Y470742D01*
X1788443Y470948D01*
X1788750Y471000D01*
X1789057Y470948D01*
X1789325Y470742D01*
X1789555Y470432D01*
X1789708Y470070D01*
X1789785Y469657D01*
Y469243D01*
X1789708Y468830D01*
X1789555Y468468D01*
X1789325Y468158D01*
X1789057Y467952D01*
X1788750Y467900D01*
G01X1790968D02*
Y471000D01*
X1792732Y467900D01*
Y471000D01*
G01X1794068Y467900D02*
Y471000D01*
X1795832Y467900D01*
Y471000D01*
G01X1800192Y467900D02*
X1801150Y471000D01*
X1802108Y467900D01*
G01X1801763Y468985D02*
X1800537D01*
G01X1770228Y496129D02*
X1769978Y496254D01*
X1769686Y496337D01*
X1769353D01*
X1768978Y496212D01*
X1768686Y496004D01*
X1768478Y495754D01*
X1768311Y495337D01*
X1768269Y494962D01*
X1768353Y494587D01*
X1768478Y494337D01*
X1768728Y494087D01*
X1769019Y493920D01*
X1769311Y493837D01*
X1769603D01*
X1769894Y493920D01*
X1770144Y494045D01*
X1770353Y494212D01*
G01X1771703Y494129D02*
X1771994Y493920D01*
X1772328Y493837D01*
X1772661Y493920D01*
X1772953Y494170D01*
X1773161Y494545D01*
X1773244Y494920D01*
Y495379D01*
X1773161Y495754D01*
X1772953Y496087D01*
X1772703Y496254D01*
X1772411Y496337D01*
X1772078Y496254D01*
X1771828Y496087D01*
X1771661Y495837D01*
X1771578Y495504D01*
X1771661Y495212D01*
X1771869Y494920D01*
X1772119Y494754D01*
X1772411Y494712D01*
X1772744Y494795D01*
X1772994Y495004D01*
X1773244Y495379D01*
G01X1775844Y495170D02*
X1776011Y495295D01*
X1776136Y495504D01*
X1776219Y495795D01*
X1776136Y496045D01*
X1775969Y496212D01*
X1775678Y496337D01*
X1774553D01*
Y493837D01*
X1775928D01*
X1776219Y494004D01*
X1776386Y494254D01*
X1776469Y494545D01*
X1776386Y494837D01*
X1776136Y495087D01*
X1775844Y495170D01*
X1774553D01*
G01X1777819Y495920D02*
X1778069Y496170D01*
X1778361Y496295D01*
X1778694Y496337D01*
X1779111Y496254D01*
X1779403Y496045D01*
X1779486Y495795D01*
X1779444Y495545D01*
X1779278Y495337D01*
X1778444Y494920D01*
X1778069Y494629D01*
X1777819Y494212D01*
X1777736Y493837D01*
X1779486D01*
G01X1730208Y494367D02*
X1730083Y494117D01*
X1730000Y493825D01*
Y493492D01*
X1730125Y493117D01*
X1730333Y492825D01*
X1730583Y492617D01*
X1731000Y492450D01*
X1731375Y492408D01*
X1731750Y492492D01*
X1732000Y492617D01*
X1732250Y492867D01*
X1732417Y493158D01*
X1732500Y493450D01*
Y493742D01*
X1732417Y494033D01*
X1732292Y494283D01*
X1732125Y494492D01*
G01X1732500Y496550D02*
X1732458Y496842D01*
X1732333Y497175D01*
X1732125Y497383D01*
X1731833Y497467D01*
X1731542Y497383D01*
X1731292Y497133D01*
X1731167Y496758D01*
Y496342D01*
X1731083Y496092D01*
X1730875Y495883D01*
X1730583Y495800D01*
X1730292Y495925D01*
X1730083Y496217D01*
X1730000Y496550D01*
X1730083Y496883D01*
X1730292Y497175D01*
X1730583Y497300D01*
X1730875Y497217D01*
X1731083Y497008D01*
X1731167Y496758D01*
Y496342D01*
X1731292Y495967D01*
X1731542Y495717D01*
X1731833Y495633D01*
X1732125Y495717D01*
X1732333Y495925D01*
X1732458Y496258D01*
X1732500Y496550D01*
G01X1731167Y499983D02*
X1731042Y500150D01*
X1730833Y500275D01*
X1730542Y500358D01*
X1730292Y500275D01*
X1730125Y500108D01*
X1730000Y499817D01*
Y498692D01*
X1732500D01*
Y500067D01*
X1732333Y500358D01*
X1732083Y500525D01*
X1731792Y500608D01*
X1731500Y500525D01*
X1731250Y500275D01*
X1731167Y499983D01*
Y498692D01*
G01X1731458Y501958D02*
X1731167Y502250D01*
X1731000Y502500D01*
X1730917Y502833D01*
X1731000Y503125D01*
X1731167Y503333D01*
X1731417Y503500D01*
X1731708Y503542D01*
X1731958Y503500D01*
X1732208Y503333D01*
X1732417Y503083D01*
X1732500Y502792D01*
X1732417Y502458D01*
X1732167Y502167D01*
X1731792Y502000D01*
X1731375Y501958D01*
X1730833Y502042D01*
X1730542Y502167D01*
X1730250Y502375D01*
X1730042Y502667D01*
X1730000Y502958D01*
X1730083Y503250D01*
X1730292Y503458D01*
G01X1754606Y502752D02*
X1754481Y502502D01*
X1754398Y502210D01*
Y501877D01*
X1754523Y501502D01*
X1754731Y501210D01*
X1754981Y501002D01*
X1755398Y500835D01*
X1755773Y500793D01*
X1756148Y500877D01*
X1756398Y501002D01*
X1756648Y501252D01*
X1756815Y501543D01*
X1756898Y501835D01*
Y502127D01*
X1756815Y502418D01*
X1756690Y502668D01*
X1756523Y502877D01*
G01X1756606Y504227D02*
X1756815Y504518D01*
X1756898Y504852D01*
X1756815Y505185D01*
X1756565Y505477D01*
X1756190Y505685D01*
X1755815Y505768D01*
X1755356D01*
X1754981Y505685D01*
X1754648Y505477D01*
X1754481Y505227D01*
X1754398Y504935D01*
X1754481Y504602D01*
X1754648Y504352D01*
X1754898Y504185D01*
X1755231Y504102D01*
X1755523Y504185D01*
X1755815Y504393D01*
X1755981Y504643D01*
X1756023Y504935D01*
X1755940Y505268D01*
X1755731Y505518D01*
X1755356Y505768D01*
G01X1755565Y508368D02*
X1755440Y508535D01*
X1755231Y508660D01*
X1754940Y508743D01*
X1754690Y508660D01*
X1754523Y508493D01*
X1754398Y508202D01*
Y507077D01*
X1756898D01*
Y508452D01*
X1756731Y508743D01*
X1756481Y508910D01*
X1756190Y508993D01*
X1755898Y508910D01*
X1755648Y508660D01*
X1755565Y508368D01*
Y507077D01*
G01X1756898Y511135D02*
X1754398D01*
X1754898Y510635D01*
G01X1756898D02*
Y511635D01*
G01X1725408Y490367D02*
X1725283Y490117D01*
X1725200Y489825D01*
Y489492D01*
X1725325Y489117D01*
X1725533Y488825D01*
X1725783Y488617D01*
X1726200Y488450D01*
X1726575Y488408D01*
X1726950Y488492D01*
X1727200Y488617D01*
X1727450Y488867D01*
X1727617Y489158D01*
X1727700Y489450D01*
Y489742D01*
X1727617Y490033D01*
X1727492Y490283D01*
X1727325Y490492D01*
G01X1727700Y492550D02*
X1727658Y492842D01*
X1727533Y493175D01*
X1727325Y493383D01*
X1727033Y493467D01*
X1726742Y493383D01*
X1726492Y493133D01*
X1726367Y492758D01*
Y492342D01*
X1726283Y492092D01*
X1726075Y491883D01*
X1725783Y491800D01*
X1725492Y491925D01*
X1725283Y492217D01*
X1725200Y492550D01*
X1725283Y492883D01*
X1725492Y493175D01*
X1725783Y493300D01*
X1726075Y493217D01*
X1726283Y493008D01*
X1726367Y492758D01*
Y492342D01*
X1726492Y491967D01*
X1726742Y491717D01*
X1727033Y491633D01*
X1727325Y491717D01*
X1727533Y491925D01*
X1727658Y492258D01*
X1727700Y492550D01*
G01X1726367Y495983D02*
X1726242Y496150D01*
X1726033Y496275D01*
X1725742Y496358D01*
X1725492Y496275D01*
X1725325Y496108D01*
X1725200Y495817D01*
Y494692D01*
X1727700D01*
Y496067D01*
X1727533Y496358D01*
X1727283Y496525D01*
X1726992Y496608D01*
X1726700Y496525D01*
X1726450Y496275D01*
X1726367Y495983D01*
Y494692D01*
G01X1727700Y498667D02*
X1727158Y498750D01*
X1726700Y498875D01*
X1726283Y499042D01*
X1725825Y499250D01*
X1725200Y499583D01*
Y497917D01*
G01X1768778Y490087D02*
Y492587D01*
X1770362D01*
G01X1769778Y491379D02*
X1768778D01*
G01X1771962Y490379D02*
X1772253Y490170D01*
X1772587Y490087D01*
X1772920Y490170D01*
X1773212Y490420D01*
X1773420Y490795D01*
X1773503Y491170D01*
Y491629D01*
X1773420Y492004D01*
X1773212Y492337D01*
X1772962Y492504D01*
X1772670Y492587D01*
X1772337Y492504D01*
X1772087Y492337D01*
X1771920Y492087D01*
X1771837Y491754D01*
X1771920Y491462D01*
X1772128Y491170D01*
X1772378Y491004D01*
X1772670Y490962D01*
X1773003Y491045D01*
X1773253Y491254D01*
X1773503Y491629D01*
G01X1776103Y491420D02*
X1776270Y491545D01*
X1776395Y491754D01*
X1776478Y492045D01*
X1776395Y492295D01*
X1776228Y492462D01*
X1775937Y492587D01*
X1774812D01*
Y490087D01*
X1776187D01*
X1776478Y490254D01*
X1776645Y490504D01*
X1776728Y490795D01*
X1776645Y491087D01*
X1776395Y491337D01*
X1776103Y491420D01*
X1774812D01*
G01X1778870Y490087D02*
Y492587D01*
X1778370Y492087D01*
G01Y490087D02*
X1779370D01*
G01X1721422Y465953D02*
Y469053D01*
X1720962Y468433D01*
G01Y465953D02*
X1721882D01*
G01X1724522D02*
Y469053D01*
X1724062Y468433D01*
G01Y465953D02*
X1724982D01*
G01X1726970Y466315D02*
X1727239Y466056D01*
X1727545Y465953D01*
X1727852Y466056D01*
X1728120Y466366D01*
X1728312Y466831D01*
X1728389Y467296D01*
Y467865D01*
X1728312Y468330D01*
X1728120Y468743D01*
X1727890Y468950D01*
X1727622Y469053D01*
X1727315Y468950D01*
X1727085Y468743D01*
X1726932Y468433D01*
X1726855Y468020D01*
X1726932Y467658D01*
X1727124Y467296D01*
X1727354Y467090D01*
X1727622Y467038D01*
X1727929Y467141D01*
X1728159Y467400D01*
X1728389Y467865D01*
G01X1752934Y501158D02*
X1750434D01*
Y502742D01*
G01X1751642Y502158D02*
Y501158D01*
G01X1752934Y505050D02*
X1752892Y505342D01*
X1752767Y505675D01*
X1752559Y505883D01*
X1752267Y505967D01*
X1751976Y505883D01*
X1751726Y505633D01*
X1751601Y505258D01*
Y504842D01*
X1751517Y504592D01*
X1751309Y504383D01*
X1751017Y504300D01*
X1750726Y504425D01*
X1750517Y504717D01*
X1750434Y505050D01*
X1750517Y505383D01*
X1750726Y505675D01*
X1751017Y505800D01*
X1751309Y505717D01*
X1751517Y505508D01*
X1751601Y505258D01*
Y504842D01*
X1751726Y504467D01*
X1751976Y504217D01*
X1752267Y504133D01*
X1752559Y504217D01*
X1752767Y504425D01*
X1752892Y504758D01*
X1752934Y505050D01*
G01X1751601Y508483D02*
X1751476Y508650D01*
X1751267Y508775D01*
X1750976Y508858D01*
X1750726Y508775D01*
X1750559Y508608D01*
X1750434Y508317D01*
Y507192D01*
X1752934D01*
Y508567D01*
X1752767Y508858D01*
X1752517Y509025D01*
X1752226Y509108D01*
X1751934Y509025D01*
X1751684Y508775D01*
X1751601Y508483D01*
Y507192D01*
G01X1752934Y511250D02*
X1750434D01*
X1750934Y510750D01*
G01X1752934D02*
Y511750D01*
G01X1739080Y518920D02*
Y501420D01*
X1748280D01*
Y518920D01*
X1739080D01*
G01X1720867Y557400D02*
Y559900D01*
X1721908D01*
X1722242Y559775D01*
X1722450Y559608D01*
X1722533Y559275D01*
X1722450Y558942D01*
X1722200Y558733D01*
X1721908Y558608D01*
X1720867D01*
G01X1721908D02*
X1722533Y557400D01*
G01X1724008Y559483D02*
X1724258Y559733D01*
X1724550Y559858D01*
X1724883Y559900D01*
X1725300Y559817D01*
X1725592Y559608D01*
X1725675Y559358D01*
X1725633Y559108D01*
X1725467Y558900D01*
X1724633Y558483D01*
X1724258Y558192D01*
X1724008Y557775D01*
X1723925Y557400D01*
X1725675D01*
G01X1726983Y557775D02*
X1727233Y557567D01*
X1727525Y557442D01*
X1727900Y557400D01*
X1728275Y557483D01*
X1728567Y557650D01*
X1728775Y557942D01*
X1728817Y558275D01*
X1728733Y558608D01*
X1728525Y558817D01*
X1728233Y558983D01*
X1727942Y559025D01*
X1727650Y558983D01*
X1727275Y558817D01*
X1727400Y559900D01*
X1728525D01*
G01X1729750D02*
X1730333Y557400D01*
X1731000Y559900D01*
X1731667Y557400D01*
X1732250Y559900D01*
G01X1734100Y557400D02*
Y559900D01*
X1733600Y559400D01*
G01Y557400D02*
X1734600D01*
G01X1737117D02*
X1737200Y557942D01*
X1737325Y558400D01*
X1737492Y558817D01*
X1737700Y559275D01*
X1738033Y559900D01*
X1736367D01*
G01X1740217Y557400D02*
X1740300Y557942D01*
X1740425Y558400D01*
X1740592Y558817D01*
X1740800Y559275D01*
X1741133Y559900D01*
X1739467D01*
G01X1714300Y566033D02*
X1716092D01*
X1716467Y566200D01*
X1716717Y566533D01*
X1716800Y566950D01*
X1716717Y567367D01*
X1716467Y567700D01*
X1716092Y567867D01*
X1714300D01*
G01X1714717Y569258D02*
X1714467Y569508D01*
X1714342Y569800D01*
X1714300Y570133D01*
X1714383Y570550D01*
X1714592Y570842D01*
X1714842Y570925D01*
X1715092Y570883D01*
X1715300Y570717D01*
X1715717Y569883D01*
X1716008Y569508D01*
X1716425Y569258D01*
X1716800Y569175D01*
Y570925D01*
G01X1716425Y572233D02*
X1716633Y572483D01*
X1716758Y572775D01*
X1716800Y573150D01*
X1716717Y573525D01*
X1716550Y573817D01*
X1716258Y574025D01*
X1715925Y574067D01*
X1715592Y573983D01*
X1715383Y573775D01*
X1715217Y573483D01*
X1715175Y573192D01*
X1715217Y572900D01*
X1715383Y572525D01*
X1714300Y572650D01*
Y573775D01*
G01Y575000D02*
X1716800Y575583D01*
X1714300Y576250D01*
X1716800Y576917D01*
X1714300Y577500D01*
G01X1716800Y579350D02*
X1714300D01*
X1714800Y578850D01*
G01X1716800D02*
Y579850D01*
G01X1716508Y581742D02*
X1716717Y582033D01*
X1716800Y582367D01*
X1716717Y582700D01*
X1716467Y582992D01*
X1716092Y583200D01*
X1715717Y583283D01*
X1715258D01*
X1714883Y583200D01*
X1714550Y582992D01*
X1714383Y582742D01*
X1714300Y582450D01*
X1714383Y582117D01*
X1714550Y581867D01*
X1714800Y581700D01*
X1715133Y581617D01*
X1715425Y581700D01*
X1715717Y581908D01*
X1715883Y582158D01*
X1715925Y582450D01*
X1715842Y582783D01*
X1715633Y583033D01*
X1715258Y583283D01*
G01X1752467Y578192D02*
X1752217Y578317D01*
X1751925Y578400D01*
X1751592D01*
X1751217Y578275D01*
X1750925Y578067D01*
X1750717Y577817D01*
X1750550Y577400D01*
X1750508Y577025D01*
X1750592Y576650D01*
X1750717Y576400D01*
X1750967Y576150D01*
X1751258Y575983D01*
X1751550Y575900D01*
X1751842D01*
X1752133Y575983D01*
X1752383Y576108D01*
X1752592Y576275D01*
G01X1753858Y577983D02*
X1754108Y578233D01*
X1754400Y578358D01*
X1754733Y578400D01*
X1755150Y578317D01*
X1755442Y578108D01*
X1755525Y577858D01*
X1755483Y577608D01*
X1755317Y577400D01*
X1754483Y576983D01*
X1754108Y576692D01*
X1753858Y576275D01*
X1753775Y575900D01*
X1755525D01*
G01X1756833Y576275D02*
X1757083Y576067D01*
X1757375Y575942D01*
X1757750Y575900D01*
X1758125Y575983D01*
X1758417Y576150D01*
X1758625Y576442D01*
X1758667Y576775D01*
X1758583Y577108D01*
X1758375Y577317D01*
X1758083Y577483D01*
X1757792Y577525D01*
X1757500Y577483D01*
X1757125Y577317D01*
X1757250Y578400D01*
X1758375D01*
G01X1759600D02*
X1760183Y575900D01*
X1760850Y578400D01*
X1761517Y575900D01*
X1762100Y578400D01*
G01X1763242Y576192D02*
X1763533Y575983D01*
X1763867Y575900D01*
X1764200Y575983D01*
X1764492Y576233D01*
X1764700Y576608D01*
X1764783Y576983D01*
Y577442D01*
X1764700Y577817D01*
X1764492Y578150D01*
X1764242Y578317D01*
X1763950Y578400D01*
X1763617Y578317D01*
X1763367Y578150D01*
X1763200Y577900D01*
X1763117Y577567D01*
X1763200Y577275D01*
X1763408Y576983D01*
X1763658Y576817D01*
X1763950Y576775D01*
X1764283Y576858D01*
X1764533Y577067D01*
X1764783Y577442D01*
G01X1766258Y577983D02*
X1766508Y578233D01*
X1766800Y578358D01*
X1767133Y578400D01*
X1767550Y578317D01*
X1767842Y578108D01*
X1767925Y577858D01*
X1767883Y577608D01*
X1767717Y577400D01*
X1766883Y576983D01*
X1766508Y576692D01*
X1766258Y576275D01*
X1766175Y575900D01*
X1767925D01*
G01X1718608Y566467D02*
X1718483Y566217D01*
X1718400Y565925D01*
Y565592D01*
X1718525Y565217D01*
X1718733Y564925D01*
X1718983Y564717D01*
X1719400Y564550D01*
X1719775Y564508D01*
X1720150Y564592D01*
X1720400Y564717D01*
X1720650Y564967D01*
X1720817Y565258D01*
X1720900Y565550D01*
Y565842D01*
X1720817Y566133D01*
X1720692Y566383D01*
X1720525Y566592D01*
G01X1718817Y567858D02*
X1718567Y568108D01*
X1718442Y568400D01*
X1718400Y568733D01*
X1718483Y569150D01*
X1718692Y569442D01*
X1718942Y569525D01*
X1719192Y569483D01*
X1719400Y569317D01*
X1719817Y568483D01*
X1720108Y568108D01*
X1720525Y567858D01*
X1720900Y567775D01*
Y569525D01*
G01X1720525Y570833D02*
X1720733Y571083D01*
X1720858Y571375D01*
X1720900Y571750D01*
X1720817Y572125D01*
X1720650Y572417D01*
X1720358Y572625D01*
X1720025Y572667D01*
X1719692Y572583D01*
X1719483Y572375D01*
X1719317Y572083D01*
X1719275Y571792D01*
X1719317Y571500D01*
X1719483Y571125D01*
X1718400Y571250D01*
Y572375D01*
G01Y573600D02*
X1720900Y574183D01*
X1718400Y574850D01*
X1720900Y575517D01*
X1718400Y576100D01*
G01X1720900Y577950D02*
X1718400D01*
X1718900Y577450D01*
G01X1720900D02*
Y578450D01*
G01X1718400Y581050D02*
X1718483Y580717D01*
X1718692Y580467D01*
X1718942Y580300D01*
X1719275Y580175D01*
X1719650Y580133D01*
X1720025Y580175D01*
X1720358Y580300D01*
X1720608Y580467D01*
X1720817Y580717D01*
X1720900Y581050D01*
X1720817Y581383D01*
X1720608Y581633D01*
X1720358Y581800D01*
X1720025Y581925D01*
X1719650Y581967D01*
X1719275Y581925D01*
X1718942Y581800D01*
X1718692Y581633D01*
X1718483Y581383D01*
X1718400Y581050D01*
G01X1720900Y584150D02*
X1718400D01*
X1718900Y583650D01*
G01X1720900D02*
Y584650D01*
G01X1752933Y552700D02*
Y550908D01*
X1753100Y550533D01*
X1753433Y550283D01*
X1753850Y550200D01*
X1754267Y550283D01*
X1754600Y550533D01*
X1754767Y550908D01*
Y552700D01*
G01X1756158Y552283D02*
X1756408Y552533D01*
X1756700Y552658D01*
X1757033Y552700D01*
X1757450Y552617D01*
X1757742Y552408D01*
X1757825Y552158D01*
X1757783Y551908D01*
X1757617Y551700D01*
X1756783Y551283D01*
X1756408Y550992D01*
X1756158Y550575D01*
X1756075Y550200D01*
X1757825D01*
G01X1759133Y550575D02*
X1759383Y550367D01*
X1759675Y550242D01*
X1760050Y550200D01*
X1760425Y550283D01*
X1760717Y550450D01*
X1760925Y550742D01*
X1760967Y551075D01*
X1760883Y551408D01*
X1760675Y551617D01*
X1760383Y551783D01*
X1760092Y551825D01*
X1759800Y551783D01*
X1759425Y551617D01*
X1759550Y552700D01*
X1760675D01*
G01X1761900D02*
X1762483Y550200D01*
X1763150Y552700D01*
X1763817Y550200D01*
X1764400Y552700D01*
G01X1766250Y550200D02*
Y552700D01*
X1765750Y552200D01*
G01Y550200D02*
X1766750D01*
G01X1769350Y552700D02*
X1769017Y552617D01*
X1768767Y552408D01*
X1768600Y552158D01*
X1768475Y551825D01*
X1768433Y551450D01*
X1768475Y551075D01*
X1768600Y550742D01*
X1768767Y550492D01*
X1769017Y550283D01*
X1769350Y550200D01*
X1769683Y550283D01*
X1769933Y550492D01*
X1770100Y550742D01*
X1770225Y551075D01*
X1770267Y551450D01*
X1770225Y551825D01*
X1770100Y552158D01*
X1769933Y552408D01*
X1769683Y552617D01*
X1769350Y552700D01*
G01X1767421Y553815D02*
X1756021D01*
Y574155D01*
X1767421D01*
Y553815D01*
G01X1762971D02*
Y558265D01*
X1760471D01*
Y553815D01*
G01X1766250Y579230D02*
X1754850D01*
Y599570D01*
X1766250D01*
Y579230D01*
G01X1761800D02*
Y583680D01*
X1759300D01*
Y579230D01*
G01X1746735Y622600D02*
X1747042Y622342D01*
X1747387Y622187D01*
X1747693D01*
X1748000Y622342D01*
X1748230Y622600D01*
X1748345Y622962D01*
X1748268Y623324D01*
X1748077Y623634D01*
X1747732Y623840D01*
X1747272Y623944D01*
X1747003Y624150D01*
X1746888Y624512D01*
X1746965Y624874D01*
X1747157Y625132D01*
X1747425Y625287D01*
X1747693D01*
X1747962Y625184D01*
X1748192Y624925D01*
G01X1749682Y622187D02*
X1750640Y625287D01*
X1751598Y622187D01*
G01X1751253Y623272D02*
X1750027D01*
G01X1753740Y625287D02*
Y622187D01*
G01X1752858Y625287D02*
X1754622D01*
G01X1755882Y622187D02*
X1756840Y625287D01*
X1757798Y622187D01*
G01X1757453Y623272D02*
X1756227D01*
G01X1759748Y621154D02*
X1759365Y621670D01*
X1759173Y622187D01*
Y624254D01*
X1759365Y624770D01*
X1759748Y625287D01*
G01X1762197Y622652D02*
X1762427Y622394D01*
X1762695Y622239D01*
X1763040Y622187D01*
X1763385Y622290D01*
X1763653Y622497D01*
X1763845Y622859D01*
X1763883Y623272D01*
X1763807Y623685D01*
X1763615Y623944D01*
X1763347Y624150D01*
X1763078Y624202D01*
X1762810Y624150D01*
X1762465Y623944D01*
X1762580Y625287D01*
X1763615D01*
G01X1766140Y622084D02*
X1766063Y622135D01*
Y622239D01*
X1766140Y622290D01*
X1766217Y622239D01*
Y622135D01*
X1766140Y622084D01*
G01Y623479D02*
X1766063Y623530D01*
Y623634D01*
X1766140Y623685D01*
X1766217Y623634D01*
Y623530D01*
X1766140Y623479D01*
G01X1768512Y624770D02*
X1768742Y625080D01*
X1769010Y625235D01*
X1769317Y625287D01*
X1769700Y625184D01*
X1769968Y624925D01*
X1770045Y624615D01*
X1770007Y624305D01*
X1769853Y624047D01*
X1769087Y623530D01*
X1768742Y623169D01*
X1768512Y622652D01*
X1768435Y622187D01*
X1770045D01*
G01X1772532Y621154D02*
X1772915Y621670D01*
X1773107Y622187D01*
Y624254D01*
X1772915Y624770D01*
X1772532Y625287D01*
G01X1730267Y613000D02*
Y615500D01*
X1731308D01*
X1731642Y615375D01*
X1731850Y615208D01*
X1731933Y614875D01*
X1731850Y614542D01*
X1731600Y614333D01*
X1731308Y614208D01*
X1730267D01*
G01X1731308D02*
X1731933Y613000D01*
G01X1733408Y615083D02*
X1733658Y615333D01*
X1733950Y615458D01*
X1734283Y615500D01*
X1734700Y615417D01*
X1734992Y615208D01*
X1735075Y614958D01*
X1735033Y614708D01*
X1734867Y614500D01*
X1734033Y614083D01*
X1733658Y613792D01*
X1733408Y613375D01*
X1733325Y613000D01*
X1735075D01*
G01X1736383Y613375D02*
X1736633Y613167D01*
X1736925Y613042D01*
X1737300Y613000D01*
X1737675Y613083D01*
X1737967Y613250D01*
X1738175Y613542D01*
X1738217Y613875D01*
X1738133Y614208D01*
X1737925Y614417D01*
X1737633Y614583D01*
X1737342Y614625D01*
X1737050Y614583D01*
X1736675Y614417D01*
X1736800Y615500D01*
X1737925D01*
G01X1739150D02*
X1739733Y613000D01*
X1740400Y615500D01*
X1741067Y613000D01*
X1741650Y615500D01*
G01X1743500Y613000D02*
Y615500D01*
X1743000Y615000D01*
G01Y613000D02*
X1744000D01*
G01X1745808Y614042D02*
X1746100Y614333D01*
X1746350Y614500D01*
X1746683Y614583D01*
X1746975Y614500D01*
X1747183Y614333D01*
X1747350Y614083D01*
X1747392Y613792D01*
X1747350Y613542D01*
X1747183Y613292D01*
X1746933Y613083D01*
X1746642Y613000D01*
X1746308Y613083D01*
X1746017Y613333D01*
X1745850Y613708D01*
X1745808Y614125D01*
X1745892Y614667D01*
X1746017Y614958D01*
X1746225Y615250D01*
X1746517Y615458D01*
X1746808Y615500D01*
X1747100Y615417D01*
X1747308Y615208D01*
G01X1749700Y613000D02*
Y615500D01*
X1749200Y615000D01*
G01Y613000D02*
X1750200D01*
G01X1730267Y609500D02*
Y612000D01*
X1731308D01*
X1731642Y611875D01*
X1731850Y611708D01*
X1731933Y611375D01*
X1731850Y611042D01*
X1731600Y610833D01*
X1731308Y610708D01*
X1730267D01*
G01X1731308D02*
X1731933Y609500D01*
G01X1733408Y611583D02*
X1733658Y611833D01*
X1733950Y611958D01*
X1734283Y612000D01*
X1734700Y611917D01*
X1734992Y611708D01*
X1735075Y611458D01*
X1735033Y611208D01*
X1734867Y611000D01*
X1734033Y610583D01*
X1733658Y610292D01*
X1733408Y609875D01*
X1733325Y609500D01*
X1735075D01*
G01X1736383Y609875D02*
X1736633Y609667D01*
X1736925Y609542D01*
X1737300Y609500D01*
X1737675Y609583D01*
X1737967Y609750D01*
X1738175Y610042D01*
X1738217Y610375D01*
X1738133Y610708D01*
X1737925Y610917D01*
X1737633Y611083D01*
X1737342Y611125D01*
X1737050Y611083D01*
X1736675Y610917D01*
X1736800Y612000D01*
X1737925D01*
G01X1739150D02*
X1739733Y609500D01*
X1740400Y612000D01*
X1741067Y609500D01*
X1741650Y612000D01*
G01X1743500Y609500D02*
Y612000D01*
X1743000Y611500D01*
G01Y609500D02*
X1744000D01*
G01X1745808Y610542D02*
X1746100Y610833D01*
X1746350Y611000D01*
X1746683Y611083D01*
X1746975Y611000D01*
X1747183Y610833D01*
X1747350Y610583D01*
X1747392Y610292D01*
X1747350Y610042D01*
X1747183Y609792D01*
X1746933Y609583D01*
X1746642Y609500D01*
X1746308Y609583D01*
X1746017Y609833D01*
X1745850Y610208D01*
X1745808Y610625D01*
X1745892Y611167D01*
X1746017Y611458D01*
X1746225Y611750D01*
X1746517Y611958D01*
X1746808Y612000D01*
X1747100Y611917D01*
X1747308Y611708D01*
G01X1749700Y612000D02*
X1749367Y611917D01*
X1749117Y611708D01*
X1748950Y611458D01*
X1748825Y611125D01*
X1748783Y610750D01*
X1748825Y610375D01*
X1748950Y610042D01*
X1749117Y609792D01*
X1749367Y609583D01*
X1749700Y609500D01*
X1750033Y609583D01*
X1750283Y609792D01*
X1750450Y610042D01*
X1750575Y610375D01*
X1750617Y610750D01*
X1750575Y611125D01*
X1750450Y611458D01*
X1750283Y611708D01*
X1750033Y611917D01*
X1749700Y612000D01*
G01X1715600Y594117D02*
X1713100D01*
Y595158D01*
X1713225Y595492D01*
X1713392Y595700D01*
X1713725Y595783D01*
X1714058Y595700D01*
X1714267Y595450D01*
X1714392Y595158D01*
Y594117D01*
G01Y595158D02*
X1715600Y595783D01*
G01X1713517Y597258D02*
X1713267Y597508D01*
X1713142Y597800D01*
X1713100Y598133D01*
X1713183Y598550D01*
X1713392Y598842D01*
X1713642Y598925D01*
X1713892Y598883D01*
X1714100Y598717D01*
X1714517Y597883D01*
X1714808Y597508D01*
X1715225Y597258D01*
X1715600Y597175D01*
Y598925D01*
G01X1715225Y600233D02*
X1715433Y600483D01*
X1715558Y600775D01*
X1715600Y601150D01*
X1715517Y601525D01*
X1715350Y601817D01*
X1715058Y602025D01*
X1714725Y602067D01*
X1714392Y601983D01*
X1714183Y601775D01*
X1714017Y601483D01*
X1713975Y601192D01*
X1714017Y600900D01*
X1714183Y600525D01*
X1713100Y600650D01*
Y601775D01*
G01Y603000D02*
X1715600Y603583D01*
X1713100Y604250D01*
X1715600Y604917D01*
X1713100Y605500D01*
G01X1715600Y607350D02*
X1713100D01*
X1713600Y606850D01*
G01X1715600D02*
Y607850D01*
G01Y610367D02*
X1715058Y610450D01*
X1714600Y610575D01*
X1714183Y610742D01*
X1713725Y610950D01*
X1713100Y611283D01*
Y609617D01*
G01Y613550D02*
X1713183Y613217D01*
X1713392Y612967D01*
X1713642Y612800D01*
X1713975Y612675D01*
X1714350Y612633D01*
X1714725Y612675D01*
X1715058Y612800D01*
X1715308Y612967D01*
X1715517Y613217D01*
X1715600Y613550D01*
X1715517Y613883D01*
X1715308Y614133D01*
X1715058Y614300D01*
X1714725Y614425D01*
X1714350Y614467D01*
X1713975Y614425D01*
X1713642Y614300D01*
X1713392Y614133D01*
X1713183Y613883D01*
X1713100Y613550D01*
G01X1754957Y610940D02*
Y613440D01*
X1755998D01*
X1756332Y613315D01*
X1756540Y613148D01*
X1756623Y612815D01*
X1756540Y612482D01*
X1756290Y612273D01*
X1755998Y612148D01*
X1754957D01*
G01X1755998D02*
X1756623Y610940D01*
G01X1758098Y613023D02*
X1758348Y613273D01*
X1758640Y613398D01*
X1758973Y613440D01*
X1759390Y613357D01*
X1759682Y613148D01*
X1759765Y612898D01*
X1759723Y612648D01*
X1759557Y612440D01*
X1758723Y612023D01*
X1758348Y611732D01*
X1758098Y611315D01*
X1758015Y610940D01*
X1759765D01*
G01X1761073Y611315D02*
X1761323Y611107D01*
X1761615Y610982D01*
X1761990Y610940D01*
X1762365Y611023D01*
X1762657Y611190D01*
X1762865Y611482D01*
X1762907Y611815D01*
X1762823Y612148D01*
X1762615Y612357D01*
X1762323Y612523D01*
X1762032Y612565D01*
X1761740Y612523D01*
X1761365Y612357D01*
X1761490Y613440D01*
X1762615D01*
G01X1763840D02*
X1764423Y610940D01*
X1765090Y613440D01*
X1765757Y610940D01*
X1766340Y613440D01*
G01X1768190Y610940D02*
Y613440D01*
X1767690Y612940D01*
G01Y610940D02*
X1768690D01*
G01X1771290D02*
X1771582Y610982D01*
X1771915Y611107D01*
X1772123Y611315D01*
X1772207Y611607D01*
X1772123Y611898D01*
X1771873Y612148D01*
X1771498Y612273D01*
X1771082D01*
X1770832Y612357D01*
X1770623Y612565D01*
X1770540Y612857D01*
X1770665Y613148D01*
X1770957Y613357D01*
X1771290Y613440D01*
X1771623Y613357D01*
X1771915Y613148D01*
X1772040Y612857D01*
X1771957Y612565D01*
X1771748Y612357D01*
X1771498Y612273D01*
X1771082D01*
X1770707Y612148D01*
X1770457Y611898D01*
X1770373Y611607D01*
X1770457Y611315D01*
X1770665Y611107D01*
X1770998Y610982D01*
X1771290Y610940D01*
G01X1774307D02*
X1774390Y611482D01*
X1774515Y611940D01*
X1774682Y612357D01*
X1774890Y612815D01*
X1775223Y613440D01*
X1773557D01*
G01X1756233Y609310D02*
Y607518D01*
X1756400Y607143D01*
X1756733Y606893D01*
X1757150Y606810D01*
X1757567Y606893D01*
X1757900Y607143D01*
X1758067Y607518D01*
Y609310D01*
G01X1759458Y608893D02*
X1759708Y609143D01*
X1760000Y609268D01*
X1760333Y609310D01*
X1760750Y609227D01*
X1761042Y609018D01*
X1761125Y608768D01*
X1761083Y608518D01*
X1760917Y608310D01*
X1760083Y607893D01*
X1759708Y607602D01*
X1759458Y607185D01*
X1759375Y606810D01*
X1761125D01*
G01X1762433Y607185D02*
X1762683Y606977D01*
X1762975Y606852D01*
X1763350Y606810D01*
X1763725Y606893D01*
X1764017Y607060D01*
X1764225Y607352D01*
X1764267Y607685D01*
X1764183Y608018D01*
X1763975Y608227D01*
X1763683Y608393D01*
X1763392Y608435D01*
X1763100Y608393D01*
X1762725Y608227D01*
X1762850Y609310D01*
X1763975D01*
G01X1765200D02*
X1765783Y606810D01*
X1766450Y609310D01*
X1767117Y606810D01*
X1767700Y609310D01*
G01X1769550Y606810D02*
Y609310D01*
X1769050Y608810D01*
G01Y606810D02*
X1770050D01*
G01X1772650D02*
Y609310D01*
X1772150Y608810D01*
G01Y606810D02*
X1773150D01*
G01X1713633Y623100D02*
Y621308D01*
X1713800Y620933D01*
X1714133Y620683D01*
X1714550Y620600D01*
X1714967Y620683D01*
X1715300Y620933D01*
X1715467Y621308D01*
Y623100D01*
G01X1716858Y622683D02*
X1717108Y622933D01*
X1717400Y623058D01*
X1717733Y623100D01*
X1718150Y623017D01*
X1718442Y622808D01*
X1718525Y622558D01*
X1718483Y622308D01*
X1718317Y622100D01*
X1717483Y621683D01*
X1717108Y621392D01*
X1716858Y620975D01*
X1716775Y620600D01*
X1718525D01*
G01X1719833Y620975D02*
X1720083Y620767D01*
X1720375Y620642D01*
X1720750Y620600D01*
X1721125Y620683D01*
X1721417Y620850D01*
X1721625Y621142D01*
X1721667Y621475D01*
X1721583Y621808D01*
X1721375Y622017D01*
X1721083Y622183D01*
X1720792Y622225D01*
X1720500Y622183D01*
X1720125Y622017D01*
X1720250Y623100D01*
X1721375D01*
G01X1722600D02*
X1723183Y620600D01*
X1723850Y623100D01*
X1724517Y620600D01*
X1725100Y623100D01*
G01X1726950Y620600D02*
Y623100D01*
X1726450Y622600D01*
G01Y620600D02*
X1727450D01*
G01X1729258Y622683D02*
X1729508Y622933D01*
X1729800Y623058D01*
X1730133Y623100D01*
X1730550Y623017D01*
X1730842Y622808D01*
X1730925Y622558D01*
X1730883Y622308D01*
X1730717Y622100D01*
X1729883Y621683D01*
X1729508Y621392D01*
X1729258Y620975D01*
X1729175Y620600D01*
X1730925D01*
G01X1721850Y594548D02*
X1719350D01*
Y596132D01*
G01X1720558Y595548D02*
Y594548D01*
G01X1720517Y598773D02*
X1720392Y598940D01*
X1720183Y599065D01*
X1719892Y599148D01*
X1719642Y599065D01*
X1719475Y598898D01*
X1719350Y598607D01*
Y597482D01*
X1721850D01*
Y598857D01*
X1721683Y599148D01*
X1721433Y599315D01*
X1721142Y599398D01*
X1720850Y599315D01*
X1720600Y599065D01*
X1720517Y598773D01*
Y597482D01*
G01X1719767Y600748D02*
X1719517Y600998D01*
X1719392Y601290D01*
X1719350Y601623D01*
X1719433Y602040D01*
X1719642Y602332D01*
X1719892Y602415D01*
X1720142Y602373D01*
X1720350Y602207D01*
X1720767Y601373D01*
X1721058Y600998D01*
X1721475Y600748D01*
X1721850Y600665D01*
Y602415D01*
G01X1721475Y603723D02*
X1721683Y603973D01*
X1721808Y604265D01*
X1721850Y604640D01*
X1721767Y605015D01*
X1721600Y605307D01*
X1721308Y605515D01*
X1720975Y605557D01*
X1720642Y605473D01*
X1720433Y605265D01*
X1720267Y604973D01*
X1720225Y604682D01*
X1720267Y604390D01*
X1720433Y604015D01*
X1719350Y604140D01*
Y605265D01*
G01Y606490D02*
X1721850Y607073D01*
X1719350Y607740D01*
X1721850Y608407D01*
X1719350Y608990D01*
G01X1719767Y610048D02*
X1719517Y610298D01*
X1719392Y610590D01*
X1719350Y610923D01*
X1719433Y611340D01*
X1719642Y611632D01*
X1719892Y611715D01*
X1720142Y611673D01*
X1720350Y611507D01*
X1720767Y610673D01*
X1721058Y610298D01*
X1721475Y610048D01*
X1721850Y609965D01*
Y611715D01*
G01X1732678Y602617D02*
X1732378D01*
G01X1725278Y606617D02*
Y602617D01*
X1732678D01*
G01X1750608Y615870D02*
Y618370D01*
X1752192D01*
G01X1751608Y617162D02*
X1750608D01*
G01X1754833Y617203D02*
X1755000Y617328D01*
X1755125Y617537D01*
X1755208Y617828D01*
X1755125Y618078D01*
X1754958Y618245D01*
X1754667Y618370D01*
X1753542D01*
Y615870D01*
X1754917D01*
X1755208Y616037D01*
X1755375Y616287D01*
X1755458Y616578D01*
X1755375Y616870D01*
X1755125Y617120D01*
X1754833Y617203D01*
X1753542D01*
G01X1756808Y617953D02*
X1757058Y618203D01*
X1757350Y618328D01*
X1757683Y618370D01*
X1758100Y618287D01*
X1758392Y618078D01*
X1758475Y617828D01*
X1758433Y617578D01*
X1758267Y617370D01*
X1757433Y616953D01*
X1757058Y616662D01*
X1756808Y616245D01*
X1756725Y615870D01*
X1758475D01*
G01X1759783Y616245D02*
X1760033Y616037D01*
X1760325Y615912D01*
X1760700Y615870D01*
X1761075Y615953D01*
X1761367Y616120D01*
X1761575Y616412D01*
X1761617Y616745D01*
X1761533Y617078D01*
X1761325Y617287D01*
X1761033Y617453D01*
X1760742Y617495D01*
X1760450Y617453D01*
X1760075Y617287D01*
X1760200Y618370D01*
X1761325D01*
G01X1762550D02*
X1763133Y615870D01*
X1763800Y618370D01*
X1764467Y615870D01*
X1765050Y618370D01*
G01X1766900Y615870D02*
Y618370D01*
X1766400Y617870D01*
G01Y615870D02*
X1767400D01*
G01X1748936Y601249D02*
X1748636D01*
G01X1741536Y605249D02*
Y601249D01*
X1748936D01*
G01X1832757Y-20560D02*
Y-18060D01*
X1833798D01*
X1834132Y-18185D01*
X1834340Y-18352D01*
X1834423Y-18685D01*
X1834340Y-19018D01*
X1834090Y-19227D01*
X1833798Y-19352D01*
X1832757D01*
G01X1833798D02*
X1834423Y-20560D01*
G01X1835982Y-20268D02*
X1836273Y-20477D01*
X1836607Y-20560D01*
X1836940Y-20477D01*
X1837232Y-20227D01*
X1837440Y-19852D01*
X1837523Y-19477D01*
Y-19018D01*
X1837440Y-18643D01*
X1837232Y-18310D01*
X1836982Y-18143D01*
X1836690Y-18060D01*
X1836357Y-18143D01*
X1836107Y-18310D01*
X1835940Y-18560D01*
X1835857Y-18893D01*
X1835940Y-19185D01*
X1836148Y-19477D01*
X1836398Y-19643D01*
X1836690Y-19685D01*
X1837023Y-19602D01*
X1837273Y-19393D01*
X1837523Y-19018D01*
G01X1840040Y-19310D02*
X1840873D01*
Y-20060D01*
X1840623Y-20310D01*
X1840332Y-20477D01*
X1839915Y-20560D01*
X1839498Y-20477D01*
X1839207Y-20310D01*
X1838957Y-20060D01*
X1838790Y-19768D01*
X1838707Y-19435D01*
Y-19143D01*
X1838790Y-18893D01*
X1838957Y-18602D01*
X1839207Y-18352D01*
X1839457Y-18185D01*
X1839790Y-18060D01*
X1840082D01*
X1840415Y-18143D01*
X1840665Y-18310D01*
G01X1841973Y-20060D02*
X1842223Y-20352D01*
X1842557Y-20518D01*
X1842932Y-20560D01*
X1843265Y-20518D01*
X1843598Y-20310D01*
X1843807Y-20060D01*
X1843848Y-19810D01*
X1843765Y-19518D01*
X1843473Y-19310D01*
X1843182Y-19227D01*
X1842807D01*
G01X1843182D02*
X1843432Y-19102D01*
X1843640Y-18893D01*
X1843723Y-18643D01*
X1843640Y-18393D01*
X1843432Y-18185D01*
X1843057Y-18060D01*
X1842682Y-18102D01*
X1842307Y-18268D01*
G01X1845073Y-20185D02*
X1845323Y-20393D01*
X1845615Y-20518D01*
X1845990Y-20560D01*
X1846365Y-20477D01*
X1846657Y-20310D01*
X1846865Y-20018D01*
X1846907Y-19685D01*
X1846823Y-19352D01*
X1846615Y-19143D01*
X1846323Y-18977D01*
X1846032Y-18935D01*
X1845740Y-18977D01*
X1845365Y-19143D01*
X1845490Y-18060D01*
X1846615D01*
G01X1827255Y-3947D02*
Y-1447D01*
X1828296D01*
X1828630Y-1572D01*
X1828838Y-1739D01*
X1828921Y-2072D01*
X1828838Y-2405D01*
X1828588Y-2614D01*
X1828296Y-2739D01*
X1827255D01*
G01X1828296D02*
X1828921Y-3947D01*
G01X1830480Y-3655D02*
X1830771Y-3864D01*
X1831105Y-3947D01*
X1831438Y-3864D01*
X1831730Y-3614D01*
X1831938Y-3239D01*
X1832021Y-2864D01*
Y-2405D01*
X1831938Y-2030D01*
X1831730Y-1697D01*
X1831480Y-1530D01*
X1831188Y-1447D01*
X1830855Y-1530D01*
X1830605Y-1697D01*
X1830438Y-1947D01*
X1830355Y-2280D01*
X1830438Y-2572D01*
X1830646Y-2864D01*
X1830896Y-3030D01*
X1831188Y-3072D01*
X1831521Y-2989D01*
X1831771Y-2780D01*
X1832021Y-2405D01*
G01X1834538Y-2697D02*
X1835371D01*
Y-3447D01*
X1835121Y-3697D01*
X1834830Y-3864D01*
X1834413Y-3947D01*
X1833996Y-3864D01*
X1833705Y-3697D01*
X1833455Y-3447D01*
X1833288Y-3155D01*
X1833205Y-2822D01*
Y-2530D01*
X1833288Y-2280D01*
X1833455Y-1989D01*
X1833705Y-1739D01*
X1833955Y-1572D01*
X1834288Y-1447D01*
X1834580D01*
X1834913Y-1530D01*
X1835163Y-1697D01*
G01X1836596Y-1864D02*
X1836846Y-1614D01*
X1837138Y-1489D01*
X1837471Y-1447D01*
X1837888Y-1530D01*
X1838180Y-1739D01*
X1838263Y-1989D01*
X1838221Y-2239D01*
X1838055Y-2447D01*
X1837221Y-2864D01*
X1836846Y-3155D01*
X1836596Y-3572D01*
X1836513Y-3947D01*
X1838263D01*
G01X1839696Y-2905D02*
X1839988Y-2614D01*
X1840238Y-2447D01*
X1840571Y-2364D01*
X1840863Y-2447D01*
X1841071Y-2614D01*
X1841238Y-2864D01*
X1841280Y-3155D01*
X1841238Y-3405D01*
X1841071Y-3655D01*
X1840821Y-3864D01*
X1840530Y-3947D01*
X1840196Y-3864D01*
X1839905Y-3614D01*
X1839738Y-3239D01*
X1839696Y-2822D01*
X1839780Y-2280D01*
X1839905Y-1989D01*
X1840113Y-1697D01*
X1840405Y-1489D01*
X1840696Y-1447D01*
X1840988Y-1530D01*
X1841196Y-1739D01*
G01X1780587Y1120D02*
Y3620D01*
X1781628D01*
X1781962Y3495D01*
X1782170Y3328D01*
X1782253Y2995D01*
X1782170Y2662D01*
X1781920Y2453D01*
X1781628Y2328D01*
X1780587D01*
G01X1781628D02*
X1782253Y1120D01*
G01X1784520D02*
X1784812Y1162D01*
X1785145Y1287D01*
X1785353Y1495D01*
X1785437Y1787D01*
X1785353Y2078D01*
X1785103Y2328D01*
X1784728Y2453D01*
X1784312D01*
X1784062Y2537D01*
X1783853Y2745D01*
X1783770Y3037D01*
X1783895Y3328D01*
X1784187Y3537D01*
X1784520Y3620D01*
X1784853Y3537D01*
X1785145Y3328D01*
X1785270Y3037D01*
X1785187Y2745D01*
X1784978Y2537D01*
X1784728Y2453D01*
X1784312D01*
X1783937Y2328D01*
X1783687Y2078D01*
X1783603Y1787D01*
X1783687Y1495D01*
X1783895Y1287D01*
X1784228Y1162D01*
X1784520Y1120D01*
G01X1787953Y2453D02*
X1788120Y2578D01*
X1788245Y2787D01*
X1788328Y3078D01*
X1788245Y3328D01*
X1788078Y3495D01*
X1787787Y3620D01*
X1786662D01*
Y1120D01*
X1788037D01*
X1788328Y1287D01*
X1788495Y1537D01*
X1788578Y1828D01*
X1788495Y2120D01*
X1788245Y2370D01*
X1787953Y2453D01*
X1786662D01*
G01X1789928Y3203D02*
X1790178Y3453D01*
X1790470Y3578D01*
X1790803Y3620D01*
X1791220Y3537D01*
X1791512Y3328D01*
X1791595Y3078D01*
X1791553Y2828D01*
X1791387Y2620D01*
X1790553Y2203D01*
X1790178Y1912D01*
X1789928Y1495D01*
X1789845Y1120D01*
X1791595D01*
G01X1793028Y2162D02*
X1793320Y2453D01*
X1793570Y2620D01*
X1793903Y2703D01*
X1794195Y2620D01*
X1794403Y2453D01*
X1794570Y2203D01*
X1794612Y1912D01*
X1794570Y1662D01*
X1794403Y1412D01*
X1794153Y1203D01*
X1793862Y1120D01*
X1793528Y1203D01*
X1793237Y1453D01*
X1793070Y1828D01*
X1793028Y2245D01*
X1793112Y2787D01*
X1793237Y3078D01*
X1793445Y3370D01*
X1793737Y3578D01*
X1794028Y3620D01*
X1794320Y3537D01*
X1794528Y3328D01*
G01X1796587Y1120D02*
Y3620D01*
X1797628D01*
X1797962Y3495D01*
X1798170Y3328D01*
X1798253Y2995D01*
X1798170Y2662D01*
X1797920Y2453D01*
X1797628Y2328D01*
X1796587D01*
G01X1797628D02*
X1798253Y1120D01*
G01X1800520D02*
X1800812Y1162D01*
X1801145Y1287D01*
X1801353Y1495D01*
X1801437Y1787D01*
X1801353Y2078D01*
X1801103Y2328D01*
X1800728Y2453D01*
X1800312D01*
X1800062Y2537D01*
X1799853Y2745D01*
X1799770Y3037D01*
X1799895Y3328D01*
X1800187Y3537D01*
X1800520Y3620D01*
X1800853Y3537D01*
X1801145Y3328D01*
X1801270Y3037D01*
X1801187Y2745D01*
X1800978Y2537D01*
X1800728Y2453D01*
X1800312D01*
X1799937Y2328D01*
X1799687Y2078D01*
X1799603Y1787D01*
X1799687Y1495D01*
X1799895Y1287D01*
X1800228Y1162D01*
X1800520Y1120D01*
G01X1803953Y2453D02*
X1804120Y2578D01*
X1804245Y2787D01*
X1804328Y3078D01*
X1804245Y3328D01*
X1804078Y3495D01*
X1803787Y3620D01*
X1802662D01*
Y1120D01*
X1804037D01*
X1804328Y1287D01*
X1804495Y1537D01*
X1804578Y1828D01*
X1804495Y2120D01*
X1804245Y2370D01*
X1803953Y2453D01*
X1802662D01*
G01X1805928Y3203D02*
X1806178Y3453D01*
X1806470Y3578D01*
X1806803Y3620D01*
X1807220Y3537D01*
X1807512Y3328D01*
X1807595Y3078D01*
X1807553Y2828D01*
X1807387Y2620D01*
X1806553Y2203D01*
X1806178Y1912D01*
X1805928Y1495D01*
X1805845Y1120D01*
X1807595D01*
G01X1810320D02*
Y3620D01*
X1808778Y1828D01*
X1810862D01*
G01X1775567Y4600D02*
Y7100D01*
X1776608D01*
X1776942Y6975D01*
X1777150Y6808D01*
X1777233Y6475D01*
X1777150Y6142D01*
X1776900Y5933D01*
X1776608Y5808D01*
X1775567D01*
G01X1776608D02*
X1777233Y4600D01*
G01X1778542D02*
Y7100D01*
X1780458Y4600D01*
Y7100D01*
G01X1782600Y4600D02*
X1782892Y4642D01*
X1783225Y4767D01*
X1783433Y4975D01*
X1783517Y5267D01*
X1783433Y5558D01*
X1783183Y5808D01*
X1782808Y5933D01*
X1782392D01*
X1782142Y6017D01*
X1781933Y6225D01*
X1781850Y6517D01*
X1781975Y6808D01*
X1782267Y7017D01*
X1782600Y7100D01*
X1782933Y7017D01*
X1783225Y6808D01*
X1783350Y6517D01*
X1783267Y6225D01*
X1783058Y6017D01*
X1782808Y5933D01*
X1782392D01*
X1782017Y5808D01*
X1781767Y5558D01*
X1781683Y5267D01*
X1781767Y4975D01*
X1781975Y4767D01*
X1782308Y4642D01*
X1782600Y4600D01*
G01X1784908D02*
Y7100D01*
X1786492D01*
G01X1785908Y5892D02*
X1784908D01*
G01X1788800Y4600D02*
Y7100D01*
X1788300Y6600D01*
G01Y4600D02*
X1789300D01*
G01X1836503Y5513D02*
X1836253Y5638D01*
X1835961Y5721D01*
X1835628D01*
X1835253Y5596D01*
X1834961Y5388D01*
X1834753Y5138D01*
X1834586Y4721D01*
X1834544Y4346D01*
X1834628Y3971D01*
X1834753Y3721D01*
X1835003Y3471D01*
X1835294Y3304D01*
X1835586Y3221D01*
X1835878D01*
X1836169Y3304D01*
X1836419Y3429D01*
X1836628Y3596D01*
G01X1837978Y3513D02*
X1838269Y3304D01*
X1838603Y3221D01*
X1838936Y3304D01*
X1839228Y3554D01*
X1839436Y3929D01*
X1839519Y4304D01*
Y4763D01*
X1839436Y5138D01*
X1839228Y5471D01*
X1838978Y5638D01*
X1838686Y5721D01*
X1838353Y5638D01*
X1838103Y5471D01*
X1837936Y5221D01*
X1837853Y4888D01*
X1837936Y4596D01*
X1838144Y4304D01*
X1838394Y4138D01*
X1838686Y4096D01*
X1839019Y4179D01*
X1839269Y4388D01*
X1839519Y4763D01*
G01X1842036Y4471D02*
X1842869D01*
Y3721D01*
X1842619Y3471D01*
X1842328Y3304D01*
X1841911Y3221D01*
X1841494Y3304D01*
X1841203Y3471D01*
X1840953Y3721D01*
X1840786Y4013D01*
X1840703Y4346D01*
Y4638D01*
X1840786Y4888D01*
X1840953Y5179D01*
X1841203Y5429D01*
X1841453Y5596D01*
X1841786Y5721D01*
X1842078D01*
X1842411Y5638D01*
X1842661Y5471D01*
G01X1844094Y5304D02*
X1844344Y5554D01*
X1844636Y5679D01*
X1844969Y5721D01*
X1845386Y5638D01*
X1845678Y5429D01*
X1845761Y5179D01*
X1845719Y4929D01*
X1845553Y4721D01*
X1844719Y4304D01*
X1844344Y4013D01*
X1844094Y3596D01*
X1844011Y3221D01*
X1845761D01*
G01X1847194Y5304D02*
X1847444Y5554D01*
X1847736Y5679D01*
X1848069Y5721D01*
X1848486Y5638D01*
X1848778Y5429D01*
X1848861Y5179D01*
X1848819Y4929D01*
X1848653Y4721D01*
X1847819Y4304D01*
X1847444Y4013D01*
X1847194Y3596D01*
X1847111Y3221D01*
X1848861D01*
G01X1826538Y-20254D02*
Y-17154D01*
X1826078Y-17774D01*
G01Y-20254D02*
X1826998D01*
G01X1829638D02*
Y-17154D01*
X1829178Y-17774D01*
G01Y-20254D02*
X1830098D01*
G01X1818860Y896D02*
Y3996D01*
X1818400Y3376D01*
G01Y896D02*
X1819320D01*
G01X1821232Y3479D02*
X1821462Y3789D01*
X1821730Y3944D01*
X1822037Y3996D01*
X1822420Y3893D01*
X1822688Y3634D01*
X1822765Y3324D01*
X1822727Y3014D01*
X1822573Y2756D01*
X1821807Y2239D01*
X1821462Y1878D01*
X1821232Y1361D01*
X1821155Y896D01*
X1822765D01*
G01X1824004Y-200D02*
Y-201D01*
G01Y-19800D02*
Y-19799D01*
G01X1817747Y81757D02*
X1817592Y81910D01*
X1817333Y82025D01*
X1816972Y82102D01*
X1816662Y82025D01*
X1816455Y81872D01*
X1816300Y81603D01*
Y80568D01*
X1819400D01*
Y81833D01*
X1819193Y82102D01*
X1818883Y82255D01*
X1818522Y82332D01*
X1818160Y82255D01*
X1817850Y82025D01*
X1817747Y81757D01*
Y80568D01*
G01X1819400Y83553D02*
X1816300D01*
X1818883Y84550D01*
X1816300Y85547D01*
X1819400D01*
G01X1816558Y88493D02*
X1816403Y88263D01*
X1816300Y87995D01*
Y87688D01*
X1816455Y87343D01*
X1816713Y87075D01*
X1817023Y86883D01*
X1817540Y86730D01*
X1818005Y86692D01*
X1818470Y86768D01*
X1818780Y86883D01*
X1819090Y87113D01*
X1819297Y87382D01*
X1819400Y87650D01*
Y87918D01*
X1819297Y88187D01*
X1819142Y88417D01*
X1818935Y88608D01*
G01X1819400Y93122D02*
X1816300D01*
Y94578D01*
G01X1817798Y94042D02*
Y93122D01*
G01X1819400Y95992D02*
X1816300Y96950D01*
X1819400Y97908D01*
G01X1818315Y97563D02*
Y96337D01*
G01X1816300Y99207D02*
X1818522D01*
X1818987Y99360D01*
X1819297Y99667D01*
X1819400Y100050D01*
X1819297Y100433D01*
X1818987Y100740D01*
X1818522Y100893D01*
X1816300D01*
G01Y102383D02*
X1819400D01*
Y103917D01*
G01X1816300Y106250D02*
X1819400D01*
G01X1816300Y105368D02*
Y107132D01*
G01X1830300Y100600D02*
Y100001D01*
X1830299Y100000D01*
X1821901D01*
X1821900Y99999D01*
Y78601D01*
X1821901Y78600D01*
X1876695D01*
Y74953D01*
X1902208D01*
G01X1798067Y91292D02*
X1797817Y91417D01*
X1797525Y91500D01*
X1797192D01*
X1796817Y91375D01*
X1796525Y91167D01*
X1796317Y90917D01*
X1796150Y90500D01*
X1796108Y90125D01*
X1796192Y89750D01*
X1796317Y89500D01*
X1796567Y89250D01*
X1796858Y89083D01*
X1797150Y89000D01*
X1797442D01*
X1797733Y89083D01*
X1797983Y89208D01*
X1798192Y89375D01*
G01X1800250Y89000D02*
Y91500D01*
X1799750Y91000D01*
G01Y89000D02*
X1800750D01*
G01X1802100Y91500D02*
X1802683Y89000D01*
X1803350Y91500D01*
X1804017Y89000D01*
X1804600Y91500D01*
G01X1806367Y89000D02*
X1806450Y89542D01*
X1806575Y90000D01*
X1806742Y90417D01*
X1806950Y90875D01*
X1807283Y91500D01*
X1805617D01*
G01X1798067Y94792D02*
X1797817Y94917D01*
X1797525Y95000D01*
X1797192D01*
X1796817Y94875D01*
X1796525Y94667D01*
X1796317Y94417D01*
X1796150Y94000D01*
X1796108Y93625D01*
X1796192Y93250D01*
X1796317Y93000D01*
X1796567Y92750D01*
X1796858Y92583D01*
X1797150Y92500D01*
X1797442D01*
X1797733Y92583D01*
X1797983Y92708D01*
X1798192Y92875D01*
G01X1799542Y92792D02*
X1799833Y92583D01*
X1800167Y92500D01*
X1800500Y92583D01*
X1800792Y92833D01*
X1801000Y93208D01*
X1801083Y93583D01*
Y94042D01*
X1801000Y94417D01*
X1800792Y94750D01*
X1800542Y94917D01*
X1800250Y95000D01*
X1799917Y94917D01*
X1799667Y94750D01*
X1799500Y94500D01*
X1799417Y94167D01*
X1799500Y93875D01*
X1799708Y93583D01*
X1799958Y93417D01*
X1800250Y93375D01*
X1800583Y93458D01*
X1800833Y93667D01*
X1801083Y94042D01*
G01X1802100Y95000D02*
X1802683Y92500D01*
X1803350Y95000D01*
X1804017Y92500D01*
X1804600Y95000D01*
G01X1805533Y92875D02*
X1805783Y92667D01*
X1806075Y92542D01*
X1806450Y92500D01*
X1806825Y92583D01*
X1807117Y92750D01*
X1807325Y93042D01*
X1807367Y93375D01*
X1807283Y93708D01*
X1807075Y93917D01*
X1806783Y94083D01*
X1806492Y94125D01*
X1806200Y94083D01*
X1805825Y93917D01*
X1805950Y95000D01*
X1807075D01*
G01X1778900Y92000D02*
X1774900D01*
Y84600D01*
G01X1820241Y54815D02*
X1820116Y54565D01*
X1820033Y54273D01*
Y53940D01*
X1820158Y53565D01*
X1820366Y53273D01*
X1820616Y53065D01*
X1821033Y52898D01*
X1821408Y52856D01*
X1821783Y52940D01*
X1822033Y53065D01*
X1822283Y53315D01*
X1822450Y53606D01*
X1822533Y53898D01*
Y54190D01*
X1822450Y54481D01*
X1822325Y54731D01*
X1822158Y54940D01*
G01X1822533Y56998D02*
X1822491Y57290D01*
X1822366Y57623D01*
X1822158Y57831D01*
X1821866Y57915D01*
X1821575Y57831D01*
X1821325Y57581D01*
X1821200Y57206D01*
Y56790D01*
X1821116Y56540D01*
X1820908Y56331D01*
X1820616Y56248D01*
X1820325Y56373D01*
X1820116Y56665D01*
X1820033Y56998D01*
X1820116Y57331D01*
X1820325Y57623D01*
X1820616Y57748D01*
X1820908Y57665D01*
X1821116Y57456D01*
X1821200Y57206D01*
Y56790D01*
X1821325Y56415D01*
X1821575Y56165D01*
X1821866Y56081D01*
X1822158Y56165D01*
X1822366Y56373D01*
X1822491Y56706D01*
X1822533Y56998D01*
G01Y59306D02*
X1820033D01*
Y60890D01*
G01X1821241Y60306D02*
Y59306D01*
G01X1822533Y63198D02*
X1820033D01*
X1820533Y62698D01*
G01X1822533D02*
Y63698D01*
G01Y66798D02*
X1820033D01*
X1821825Y65256D01*
Y67340D01*
G01X1799600Y79800D02*
Y68600D01*
G01X1817600Y79800D02*
X1799600D01*
G01X1817600Y68600D02*
Y79800D01*
G01X1799600Y41400D02*
Y52600D01*
G01X1817600Y41400D02*
X1799600D01*
G01X1817600Y52600D02*
Y41400D01*
G01X1795800Y52600D02*
Y41400D01*
G01D02*
X1777800D01*
G01D02*
Y52600D01*
G01X1795800Y68600D02*
Y79800D01*
G01D02*
X1777800D01*
G01D02*
Y68600D01*
G01X1829650Y72118D02*
X1865950D01*
Y40618D01*
X1829650D01*
Y72118D01*
G01X1781383Y80700D02*
X1779717D01*
Y83200D01*
X1781383D01*
G01X1780717Y81992D02*
X1779717D01*
G01X1782733Y83200D02*
Y81408D01*
X1782900Y81033D01*
X1783233Y80783D01*
X1783650Y80700D01*
X1784067Y80783D01*
X1784400Y81033D01*
X1784567Y81408D01*
Y83200D01*
G01X1785958Y82783D02*
X1786208Y83033D01*
X1786500Y83158D01*
X1786833Y83200D01*
X1787250Y83117D01*
X1787542Y82908D01*
X1787625Y82658D01*
X1787583Y82408D01*
X1787417Y82200D01*
X1786583Y81783D01*
X1786208Y81492D01*
X1785958Y81075D01*
X1785875Y80700D01*
X1787625D01*
G01X1788933Y81075D02*
X1789183Y80867D01*
X1789475Y80742D01*
X1789850Y80700D01*
X1790225Y80783D01*
X1790517Y80950D01*
X1790725Y81242D01*
X1790767Y81575D01*
X1790683Y81908D01*
X1790475Y82117D01*
X1790183Y82283D01*
X1789892Y82325D01*
X1789600Y82283D01*
X1789225Y82117D01*
X1789350Y83200D01*
X1790475D01*
G01X1792158Y80700D02*
Y83200D01*
X1793742D01*
G01X1793158Y81992D02*
X1792158D01*
G01X1795258Y82783D02*
X1795508Y83033D01*
X1795800Y83158D01*
X1796133Y83200D01*
X1796550Y83117D01*
X1796842Y82908D01*
X1796925Y82658D01*
X1796883Y82408D01*
X1796717Y82200D01*
X1795883Y81783D01*
X1795508Y81492D01*
X1795258Y81075D01*
X1795175Y80700D01*
X1796925D01*
G01X1808707Y129903D02*
X1808860Y130058D01*
X1808975Y130317D01*
X1809052Y130678D01*
X1808975Y130988D01*
X1808822Y131195D01*
X1808553Y131350D01*
X1807518D01*
Y128250D01*
X1808783D01*
X1809052Y128457D01*
X1809205Y128767D01*
X1809282Y129128D01*
X1809205Y129490D01*
X1808975Y129800D01*
X1808707Y129903D01*
X1807518D01*
G01X1810503Y128250D02*
Y131350D01*
X1811500Y128767D01*
X1812497Y131350D01*
Y128250D01*
G01X1815443Y131092D02*
X1815213Y131247D01*
X1814945Y131350D01*
X1814638D01*
X1814293Y131195D01*
X1814025Y130937D01*
X1813833Y130627D01*
X1813680Y130110D01*
X1813642Y129645D01*
X1813718Y129180D01*
X1813833Y128870D01*
X1814063Y128560D01*
X1814332Y128353D01*
X1814600Y128250D01*
X1814868D01*
X1815137Y128353D01*
X1815367Y128508D01*
X1815558Y128715D01*
G01X1816550Y127217D02*
X1818850D01*
G01X1819995Y128250D02*
Y131350D01*
G01X1821605D02*
Y128250D01*
G01Y129800D02*
X1819995D01*
G01X1824667Y128250D02*
X1823133D01*
Y131350D01*
X1824667D01*
G01X1824053Y129852D02*
X1823133D01*
G01X1826042Y128250D02*
X1827000Y131350D01*
X1827958Y128250D01*
G01X1827613Y129335D02*
X1826387D01*
G01X1829333Y128250D02*
Y131350D01*
X1830292D01*
X1830598Y131195D01*
X1830790Y130988D01*
X1830867Y130575D01*
X1830790Y130162D01*
X1830560Y129903D01*
X1830292Y129748D01*
X1829333D01*
G01X1830292D02*
X1830867Y128250D01*
G01X1833200Y131350D02*
Y128250D01*
G01X1832318Y131350D02*
X1834082D01*
G01X1836607Y129903D02*
X1836760Y130058D01*
X1836875Y130317D01*
X1836952Y130678D01*
X1836875Y130988D01*
X1836722Y131195D01*
X1836453Y131350D01*
X1835418D01*
Y128250D01*
X1836683D01*
X1836952Y128457D01*
X1837105Y128767D01*
X1837182Y129128D01*
X1837105Y129490D01*
X1836875Y129800D01*
X1836607Y129903D01*
X1835418D01*
G01X1840167Y128250D02*
X1838633D01*
Y131350D01*
X1840167D01*
G01X1839553Y129852D02*
X1838633D01*
G01X1841542Y128250D02*
X1842500Y131350D01*
X1843458Y128250D01*
G01X1843113Y129335D02*
X1841887D01*
G01X1845600Y131350D02*
Y128250D01*
G01X1844718Y131350D02*
X1846482D01*
G01X1787800Y108100D02*
X1788700D01*
Y105200D01*
X1792100D01*
G01X1830300Y104100D02*
Y110800D01*
X1854380D01*
Y122643D01*
X1864230D01*
Y137707D01*
G01X1829657Y151142D02*
X1829407Y151267D01*
X1829115Y151350D01*
X1828782D01*
X1828407Y151225D01*
X1828115Y151017D01*
X1827907Y150767D01*
X1827740Y150350D01*
X1827698Y149975D01*
X1827782Y149600D01*
X1827907Y149350D01*
X1828157Y149100D01*
X1828448Y148933D01*
X1828740Y148850D01*
X1829032D01*
X1829323Y148933D01*
X1829573Y149058D01*
X1829782Y149225D01*
G01X1831132Y149142D02*
X1831423Y148933D01*
X1831757Y148850D01*
X1832090Y148933D01*
X1832382Y149183D01*
X1832590Y149558D01*
X1832673Y149933D01*
Y150392D01*
X1832590Y150767D01*
X1832382Y151100D01*
X1832132Y151267D01*
X1831840Y151350D01*
X1831507Y151267D01*
X1831257Y151100D01*
X1831090Y150850D01*
X1831007Y150517D01*
X1831090Y150225D01*
X1831298Y149933D01*
X1831548Y149767D01*
X1831840Y149725D01*
X1832173Y149808D01*
X1832423Y150017D01*
X1832673Y150392D01*
G01X1834148Y148850D02*
Y151350D01*
X1835732D01*
G01X1835148Y150142D02*
X1834148D01*
G01X1838040Y148850D02*
Y151350D01*
X1837540Y150850D01*
G01Y148850D02*
X1838540D01*
G01X1840223Y149350D02*
X1840473Y149058D01*
X1840807Y148892D01*
X1841182Y148850D01*
X1841515Y148892D01*
X1841848Y149100D01*
X1842057Y149350D01*
X1842098Y149600D01*
X1842015Y149892D01*
X1841723Y150100D01*
X1841432Y150183D01*
X1841057D01*
G01X1841432D02*
X1841682Y150308D01*
X1841890Y150517D01*
X1841973Y150767D01*
X1841890Y151017D01*
X1841682Y151225D01*
X1841307Y151350D01*
X1840932Y151308D01*
X1840557Y151142D01*
G01X1807617Y138860D02*
Y141360D01*
X1808658D01*
X1808992Y141235D01*
X1809200Y141068D01*
X1809283Y140735D01*
X1809200Y140402D01*
X1808950Y140193D01*
X1808658Y140068D01*
X1807617D01*
G01X1808658D02*
X1809283Y138860D01*
G01X1810842Y139152D02*
X1811133Y138943D01*
X1811467Y138860D01*
X1811800Y138943D01*
X1812092Y139193D01*
X1812300Y139568D01*
X1812383Y139943D01*
Y140402D01*
X1812300Y140777D01*
X1812092Y141110D01*
X1811842Y141277D01*
X1811550Y141360D01*
X1811217Y141277D01*
X1810967Y141110D01*
X1810800Y140860D01*
X1810717Y140527D01*
X1810800Y140235D01*
X1811008Y139943D01*
X1811258Y139777D01*
X1811550Y139735D01*
X1811883Y139818D01*
X1812133Y140027D01*
X1812383Y140402D01*
G01X1813858Y138860D02*
Y141360D01*
X1815442D01*
G01X1814858Y140152D02*
X1813858D01*
G01X1817750Y138860D02*
Y141360D01*
X1817250Y140860D01*
G01Y138860D02*
X1818250D01*
G01X1820850D02*
Y141360D01*
X1820350Y140860D01*
G01Y138860D02*
X1821350D01*
G01X1810157Y151110D02*
Y153610D01*
X1811198D01*
X1811532Y153485D01*
X1811740Y153318D01*
X1811823Y152985D01*
X1811740Y152652D01*
X1811490Y152443D01*
X1811198Y152318D01*
X1810157D01*
G01X1811198D02*
X1811823Y151110D01*
G01X1813382Y151402D02*
X1813673Y151193D01*
X1814007Y151110D01*
X1814340Y151193D01*
X1814632Y151443D01*
X1814840Y151818D01*
X1814923Y152193D01*
Y152652D01*
X1814840Y153027D01*
X1814632Y153360D01*
X1814382Y153527D01*
X1814090Y153610D01*
X1813757Y153527D01*
X1813507Y153360D01*
X1813340Y153110D01*
X1813257Y152777D01*
X1813340Y152485D01*
X1813548Y152193D01*
X1813798Y152027D01*
X1814090Y151985D01*
X1814423Y152068D01*
X1814673Y152277D01*
X1814923Y152652D01*
G01X1816398Y151110D02*
Y153610D01*
X1817982D01*
G01X1817398Y152402D02*
X1816398D01*
G01X1820290Y151110D02*
X1820582Y151152D01*
X1820915Y151277D01*
X1821123Y151485D01*
X1821207Y151777D01*
X1821123Y152068D01*
X1820873Y152318D01*
X1820498Y152443D01*
X1820082D01*
X1819832Y152527D01*
X1819623Y152735D01*
X1819540Y153027D01*
X1819665Y153318D01*
X1819957Y153527D01*
X1820290Y153610D01*
X1820623Y153527D01*
X1820915Y153318D01*
X1821040Y153027D01*
X1820957Y152735D01*
X1820748Y152527D01*
X1820498Y152443D01*
X1820082D01*
X1819707Y152318D01*
X1819457Y152068D01*
X1819373Y151777D01*
X1819457Y151485D01*
X1819665Y151277D01*
X1819998Y151152D01*
X1820290Y151110D01*
G01X1821940Y111157D02*
X1819440D01*
Y112198D01*
X1819565Y112532D01*
X1819732Y112740D01*
X1820065Y112823D01*
X1820398Y112740D01*
X1820607Y112490D01*
X1820732Y112198D01*
Y111157D01*
G01Y112198D02*
X1821940Y112823D01*
G01X1821648Y114382D02*
X1821857Y114673D01*
X1821940Y115007D01*
X1821857Y115340D01*
X1821607Y115632D01*
X1821232Y115840D01*
X1820857Y115923D01*
X1820398D01*
X1820023Y115840D01*
X1819690Y115632D01*
X1819523Y115382D01*
X1819440Y115090D01*
X1819523Y114757D01*
X1819690Y114507D01*
X1819940Y114340D01*
X1820273Y114257D01*
X1820565Y114340D01*
X1820857Y114548D01*
X1821023Y114798D01*
X1821065Y115090D01*
X1820982Y115423D01*
X1820773Y115673D01*
X1820398Y115923D01*
G01X1821940Y117398D02*
X1819440D01*
Y118982D01*
G01X1820648Y118398D02*
Y117398D01*
G01X1821940Y121290D02*
X1819440D01*
X1819940Y120790D01*
G01X1821940D02*
Y121790D01*
G01X1821440Y123473D02*
X1821732Y123723D01*
X1821898Y124057D01*
X1821940Y124432D01*
X1821898Y124765D01*
X1821690Y125098D01*
X1821440Y125307D01*
X1821190Y125348D01*
X1820898Y125265D01*
X1820690Y124973D01*
X1820607Y124682D01*
Y124307D01*
G01Y124682D02*
X1820482Y124932D01*
X1820273Y125140D01*
X1820023Y125223D01*
X1819773Y125140D01*
X1819565Y124932D01*
X1819440Y124557D01*
X1819482Y124182D01*
X1819648Y123807D01*
G01X1806500Y126967D02*
X1804000D01*
Y128008D01*
X1804125Y128342D01*
X1804292Y128550D01*
X1804625Y128633D01*
X1804958Y128550D01*
X1805167Y128300D01*
X1805292Y128008D01*
Y126967D01*
G01Y128008D02*
X1806500Y128633D01*
G01Y130900D02*
X1806458Y131192D01*
X1806333Y131525D01*
X1806125Y131733D01*
X1805833Y131817D01*
X1805542Y131733D01*
X1805292Y131483D01*
X1805167Y131108D01*
Y130692D01*
X1805083Y130442D01*
X1804875Y130233D01*
X1804583Y130150D01*
X1804292Y130275D01*
X1804083Y130567D01*
X1804000Y130900D01*
X1804083Y131233D01*
X1804292Y131525D01*
X1804583Y131650D01*
X1804875Y131567D01*
X1805083Y131358D01*
X1805167Y131108D01*
Y130692D01*
X1805292Y130317D01*
X1805542Y130067D01*
X1805833Y129983D01*
X1806125Y130067D01*
X1806333Y130275D01*
X1806458Y130608D01*
X1806500Y130900D01*
G01X1805167Y134333D02*
X1805042Y134500D01*
X1804833Y134625D01*
X1804542Y134708D01*
X1804292Y134625D01*
X1804125Y134458D01*
X1804000Y134167D01*
Y133042D01*
X1806500D01*
Y134417D01*
X1806333Y134708D01*
X1806083Y134875D01*
X1805792Y134958D01*
X1805500Y134875D01*
X1805250Y134625D01*
X1805167Y134333D01*
Y133042D01*
G01X1804417Y136308D02*
X1804167Y136558D01*
X1804042Y136850D01*
X1804000Y137183D01*
X1804083Y137600D01*
X1804292Y137892D01*
X1804542Y137975D01*
X1804792Y137933D01*
X1805000Y137767D01*
X1805417Y136933D01*
X1805708Y136558D01*
X1806125Y136308D01*
X1806500Y136225D01*
Y137975D01*
G01X1806125Y139283D02*
X1806333Y139533D01*
X1806458Y139825D01*
X1806500Y140200D01*
X1806417Y140575D01*
X1806250Y140867D01*
X1805958Y141075D01*
X1805625Y141117D01*
X1805292Y141033D01*
X1805083Y140825D01*
X1804917Y140533D01*
X1804875Y140242D01*
X1804917Y139950D01*
X1805083Y139575D01*
X1804000Y139700D01*
Y140825D01*
G01X1800867Y98800D02*
Y101300D01*
X1801908D01*
X1802242Y101175D01*
X1802450Y101008D01*
X1802533Y100675D01*
X1802450Y100342D01*
X1802200Y100133D01*
X1801908Y100008D01*
X1800867D01*
G01X1801908D02*
X1802533Y98800D01*
G01X1804092Y99092D02*
X1804383Y98883D01*
X1804717Y98800D01*
X1805050Y98883D01*
X1805342Y99133D01*
X1805550Y99508D01*
X1805633Y99883D01*
Y100342D01*
X1805550Y100717D01*
X1805342Y101050D01*
X1805092Y101217D01*
X1804800Y101300D01*
X1804467Y101217D01*
X1804217Y101050D01*
X1804050Y100800D01*
X1803967Y100467D01*
X1804050Y100175D01*
X1804258Y99883D01*
X1804508Y99717D01*
X1804800Y99675D01*
X1805133Y99758D01*
X1805383Y99967D01*
X1805633Y100342D01*
G01X1807108Y98800D02*
Y101300D01*
X1808692D01*
G01X1808108Y100092D02*
X1807108D01*
G01X1810083Y99300D02*
X1810333Y99008D01*
X1810667Y98842D01*
X1811042Y98800D01*
X1811375Y98842D01*
X1811708Y99050D01*
X1811917Y99300D01*
X1811958Y99550D01*
X1811875Y99842D01*
X1811583Y100050D01*
X1811292Y100133D01*
X1810917D01*
G01X1811292D02*
X1811542Y100258D01*
X1811750Y100467D01*
X1811833Y100717D01*
X1811750Y100967D01*
X1811542Y101175D01*
X1811167Y101300D01*
X1810792Y101258D01*
X1810417Y101092D01*
G01X1814100Y101300D02*
X1813767Y101217D01*
X1813517Y101008D01*
X1813350Y100758D01*
X1813225Y100425D01*
X1813183Y100050D01*
X1813225Y99675D01*
X1813350Y99342D01*
X1813517Y99092D01*
X1813767Y98883D01*
X1814100Y98800D01*
X1814433Y98883D01*
X1814683Y99092D01*
X1814850Y99342D01*
X1814975Y99675D01*
X1815017Y100050D01*
X1814975Y100425D01*
X1814850Y100758D01*
X1814683Y101008D01*
X1814433Y101217D01*
X1814100Y101300D01*
G01X1825380Y101587D02*
X1822880D01*
Y102628D01*
X1823005Y102962D01*
X1823172Y103170D01*
X1823505Y103253D01*
X1823838Y103170D01*
X1824047Y102920D01*
X1824172Y102628D01*
Y101587D01*
G01Y102628D02*
X1825380Y103253D01*
G01Y105520D02*
X1822880D01*
X1823380Y105020D01*
G01X1825380D02*
Y106020D01*
G01X1822880Y107703D02*
X1824672D01*
X1825047Y107870D01*
X1825297Y108203D01*
X1825380Y108620D01*
X1825297Y109037D01*
X1825047Y109370D01*
X1824672Y109537D01*
X1822880D01*
G01X1825005Y110803D02*
X1825213Y111053D01*
X1825338Y111345D01*
X1825380Y111720D01*
X1825297Y112095D01*
X1825130Y112387D01*
X1824838Y112595D01*
X1824505Y112637D01*
X1824172Y112553D01*
X1823963Y112345D01*
X1823797Y112053D01*
X1823755Y111762D01*
X1823797Y111470D01*
X1823963Y111095D01*
X1822880Y111220D01*
Y112345D01*
G01X1828880Y101587D02*
X1826380D01*
Y102628D01*
X1826505Y102962D01*
X1826672Y103170D01*
X1827005Y103253D01*
X1827338Y103170D01*
X1827547Y102920D01*
X1827672Y102628D01*
Y101587D01*
G01Y102628D02*
X1828880Y103253D01*
G01Y105520D02*
X1826380D01*
X1826880Y105020D01*
G01X1828880D02*
Y106020D01*
G01X1826380Y107703D02*
X1828172D01*
X1828547Y107870D01*
X1828797Y108203D01*
X1828880Y108620D01*
X1828797Y109037D01*
X1828547Y109370D01*
X1828172Y109537D01*
X1826380D01*
G01X1826797Y110928D02*
X1826547Y111178D01*
X1826422Y111470D01*
X1826380Y111803D01*
X1826463Y112220D01*
X1826672Y112512D01*
X1826922Y112595D01*
X1827172Y112553D01*
X1827380Y112387D01*
X1827797Y111553D01*
X1828088Y111178D01*
X1828505Y110928D01*
X1828880Y110845D01*
Y112595D01*
G01X1821217Y137292D02*
X1820967Y137417D01*
X1820675Y137500D01*
X1820342D01*
X1819967Y137375D01*
X1819675Y137167D01*
X1819467Y136917D01*
X1819300Y136500D01*
X1819258Y136125D01*
X1819342Y135750D01*
X1819467Y135500D01*
X1819717Y135250D01*
X1820008Y135083D01*
X1820300Y135000D01*
X1820592D01*
X1820883Y135083D01*
X1821133Y135208D01*
X1821342Y135375D01*
G01X1822692Y135292D02*
X1822983Y135083D01*
X1823317Y135000D01*
X1823650Y135083D01*
X1823942Y135333D01*
X1824150Y135708D01*
X1824233Y136083D01*
Y136542D01*
X1824150Y136917D01*
X1823942Y137250D01*
X1823692Y137417D01*
X1823400Y137500D01*
X1823067Y137417D01*
X1822817Y137250D01*
X1822650Y137000D01*
X1822567Y136667D01*
X1822650Y136375D01*
X1822858Y136083D01*
X1823108Y135917D01*
X1823400Y135875D01*
X1823733Y135958D01*
X1823983Y136167D01*
X1824233Y136542D01*
G01X1825250Y137500D02*
X1825833Y135000D01*
X1826500Y137500D01*
X1827167Y135000D01*
X1827750Y137500D01*
G01X1829600Y135000D02*
Y137500D01*
X1829100Y137000D01*
G01Y135000D02*
X1830100D01*
G01X1831992Y135292D02*
X1832283Y135083D01*
X1832617Y135000D01*
X1832950Y135083D01*
X1833242Y135333D01*
X1833450Y135708D01*
X1833533Y136083D01*
Y136542D01*
X1833450Y136917D01*
X1833242Y137250D01*
X1832992Y137417D01*
X1832700Y137500D01*
X1832367Y137417D01*
X1832117Y137250D01*
X1831950Y137000D01*
X1831867Y136667D01*
X1831950Y136375D01*
X1832158Y136083D01*
X1832408Y135917D01*
X1832700Y135875D01*
X1833033Y135958D01*
X1833283Y136167D01*
X1833533Y136542D01*
G01X1796250Y146300D02*
X1795917Y146342D01*
X1795625Y146508D01*
X1795375Y146758D01*
X1795208Y147050D01*
X1795125Y147383D01*
Y147717D01*
X1795208Y148050D01*
X1795375Y148342D01*
X1795625Y148592D01*
X1795917Y148758D01*
X1796250Y148800D01*
X1796583Y148758D01*
X1796875Y148592D01*
X1797125Y148342D01*
X1797292Y148050D01*
X1797375Y147717D01*
Y147383D01*
X1797292Y147050D01*
X1797125Y146758D01*
X1796875Y146508D01*
X1796583Y146342D01*
X1796250Y146300D01*
G01X1796583Y146967D02*
X1797083Y146300D01*
G01X1798642Y146592D02*
X1798933Y146383D01*
X1799267Y146300D01*
X1799600Y146383D01*
X1799892Y146633D01*
X1800100Y147008D01*
X1800183Y147383D01*
Y147842D01*
X1800100Y148217D01*
X1799892Y148550D01*
X1799642Y148717D01*
X1799350Y148800D01*
X1799017Y148717D01*
X1798767Y148550D01*
X1798600Y148300D01*
X1798517Y147967D01*
X1798600Y147675D01*
X1798808Y147383D01*
X1799058Y147217D01*
X1799350Y147175D01*
X1799683Y147258D01*
X1799933Y147467D01*
X1800183Y147842D01*
G01X1803283Y146300D02*
X1801617D01*
Y148800D01*
X1803283D01*
G01X1802617Y147592D02*
X1801617D01*
G01X1805550Y146300D02*
Y148800D01*
X1805050Y148300D01*
G01Y146300D02*
X1806050D01*
G01X1804910Y111390D02*
X1804577Y111432D01*
X1804285Y111598D01*
X1804035Y111848D01*
X1803868Y112140D01*
X1803785Y112473D01*
Y112807D01*
X1803868Y113140D01*
X1804035Y113432D01*
X1804285Y113682D01*
X1804577Y113848D01*
X1804910Y113890D01*
X1805243Y113848D01*
X1805535Y113682D01*
X1805785Y113432D01*
X1805952Y113140D01*
X1806035Y112807D01*
Y112473D01*
X1805952Y112140D01*
X1805785Y111848D01*
X1805535Y111598D01*
X1805243Y111432D01*
X1804910Y111390D01*
G01X1805243Y112057D02*
X1805743Y111390D01*
G01X1807302Y111682D02*
X1807593Y111473D01*
X1807927Y111390D01*
X1808260Y111473D01*
X1808552Y111723D01*
X1808760Y112098D01*
X1808843Y112473D01*
Y112932D01*
X1808760Y113307D01*
X1808552Y113640D01*
X1808302Y113807D01*
X1808010Y113890D01*
X1807677Y113807D01*
X1807427Y113640D01*
X1807260Y113390D01*
X1807177Y113057D01*
X1807260Y112765D01*
X1807468Y112473D01*
X1807718Y112307D01*
X1808010Y112265D01*
X1808343Y112348D01*
X1808593Y112557D01*
X1808843Y112932D01*
G01X1810318Y111390D02*
Y113890D01*
X1811902D01*
G01X1811318Y112682D02*
X1810318D01*
G01X1814210Y111390D02*
Y113890D01*
X1813710Y113390D01*
G01Y111390D02*
X1814710D01*
G01X1824767Y142292D02*
X1824517Y142417D01*
X1824225Y142500D01*
X1823892D01*
X1823517Y142375D01*
X1823225Y142167D01*
X1823017Y141917D01*
X1822850Y141500D01*
X1822808Y141125D01*
X1822892Y140750D01*
X1823017Y140500D01*
X1823267Y140250D01*
X1823558Y140083D01*
X1823850Y140000D01*
X1824142D01*
X1824433Y140083D01*
X1824683Y140208D01*
X1824892Y140375D01*
G01X1826242Y140292D02*
X1826533Y140083D01*
X1826867Y140000D01*
X1827200Y140083D01*
X1827492Y140333D01*
X1827700Y140708D01*
X1827783Y141083D01*
Y141542D01*
X1827700Y141917D01*
X1827492Y142250D01*
X1827242Y142417D01*
X1826950Y142500D01*
X1826617Y142417D01*
X1826367Y142250D01*
X1826200Y142000D01*
X1826117Y141667D01*
X1826200Y141375D01*
X1826408Y141083D01*
X1826658Y140917D01*
X1826950Y140875D01*
X1827283Y140958D01*
X1827533Y141167D01*
X1827783Y141542D01*
G01X1829258Y140000D02*
Y142500D01*
X1830842D01*
G01X1830258Y141292D02*
X1829258D01*
G01X1832442Y140292D02*
X1832733Y140083D01*
X1833067Y140000D01*
X1833400Y140083D01*
X1833692Y140333D01*
X1833900Y140708D01*
X1833983Y141083D01*
Y141542D01*
X1833900Y141917D01*
X1833692Y142250D01*
X1833442Y142417D01*
X1833150Y142500D01*
X1832817Y142417D01*
X1832567Y142250D01*
X1832400Y142000D01*
X1832317Y141667D01*
X1832400Y141375D01*
X1832608Y141083D01*
X1832858Y140917D01*
X1833150Y140875D01*
X1833483Y140958D01*
X1833733Y141167D01*
X1833983Y141542D01*
G01X1815778Y113057D02*
X1815653Y112807D01*
X1815570Y112515D01*
Y112182D01*
X1815695Y111807D01*
X1815903Y111515D01*
X1816153Y111307D01*
X1816570Y111140D01*
X1816945Y111098D01*
X1817320Y111182D01*
X1817570Y111307D01*
X1817820Y111557D01*
X1817987Y111848D01*
X1818070Y112140D01*
Y112432D01*
X1817987Y112723D01*
X1817862Y112973D01*
X1817695Y113182D01*
G01X1817778Y114532D02*
X1817987Y114823D01*
X1818070Y115157D01*
X1817987Y115490D01*
X1817737Y115782D01*
X1817362Y115990D01*
X1816987Y116073D01*
X1816528D01*
X1816153Y115990D01*
X1815820Y115782D01*
X1815653Y115532D01*
X1815570Y115240D01*
X1815653Y114907D01*
X1815820Y114657D01*
X1816070Y114490D01*
X1816403Y114407D01*
X1816695Y114490D01*
X1816987Y114698D01*
X1817153Y114948D01*
X1817195Y115240D01*
X1817112Y115573D01*
X1816903Y115823D01*
X1816528Y116073D01*
G01X1818070Y117548D02*
X1815570D01*
Y119132D01*
G01X1816778Y118548D02*
Y117548D01*
G01X1818070Y121440D02*
X1818028Y121732D01*
X1817903Y122065D01*
X1817695Y122273D01*
X1817403Y122357D01*
X1817112Y122273D01*
X1816862Y122023D01*
X1816737Y121648D01*
Y121232D01*
X1816653Y120982D01*
X1816445Y120773D01*
X1816153Y120690D01*
X1815862Y120815D01*
X1815653Y121107D01*
X1815570Y121440D01*
X1815653Y121773D01*
X1815862Y122065D01*
X1816153Y122190D01*
X1816445Y122107D01*
X1816653Y121898D01*
X1816737Y121648D01*
Y121232D01*
X1816862Y120857D01*
X1817112Y120607D01*
X1817403Y120523D01*
X1817695Y120607D01*
X1817903Y120815D01*
X1818028Y121148D01*
X1818070Y121440D01*
G01X1781075Y133881D02*
Y138304D01*
G01X1779182D02*
X1782968D01*
G01X1781075Y145172D02*
Y141583D01*
X1782968D01*
X1781075Y138304D01*
X1779182Y141583D01*
X1781075D01*
G01X1787123Y115262D02*
X1789016D01*
G01D02*
X1787123Y111983D01*
G01D02*
X1785230Y115262D01*
G01D02*
X1787123D01*
G01Y107560D02*
Y111983D01*
G01X1785230D02*
X1789016D01*
G01X1787123Y118851D02*
Y115262D01*
G01X1789097Y155240D02*
Y157740D01*
X1790138D01*
X1790472Y157615D01*
X1790680Y157448D01*
X1790763Y157115D01*
X1790680Y156782D01*
X1790430Y156573D01*
X1790138Y156448D01*
X1789097D01*
G01X1790138D02*
X1790763Y155240D01*
G01X1792322Y155532D02*
X1792613Y155323D01*
X1792947Y155240D01*
X1793280Y155323D01*
X1793572Y155573D01*
X1793780Y155948D01*
X1793863Y156323D01*
Y156782D01*
X1793780Y157157D01*
X1793572Y157490D01*
X1793322Y157657D01*
X1793030Y157740D01*
X1792697Y157657D01*
X1792447Y157490D01*
X1792280Y157240D01*
X1792197Y156907D01*
X1792280Y156615D01*
X1792488Y156323D01*
X1792738Y156157D01*
X1793030Y156115D01*
X1793363Y156198D01*
X1793613Y156407D01*
X1793863Y156782D01*
G01X1795338Y155240D02*
Y157740D01*
X1796922D01*
G01X1796338Y156532D02*
X1795338D01*
G01X1798438Y156282D02*
X1798730Y156573D01*
X1798980Y156740D01*
X1799313Y156823D01*
X1799605Y156740D01*
X1799813Y156573D01*
X1799980Y156323D01*
X1800022Y156032D01*
X1799980Y155782D01*
X1799813Y155532D01*
X1799563Y155323D01*
X1799272Y155240D01*
X1798938Y155323D01*
X1798647Y155573D01*
X1798480Y155948D01*
X1798438Y156365D01*
X1798522Y156907D01*
X1798647Y157198D01*
X1798855Y157490D01*
X1799147Y157698D01*
X1799438Y157740D01*
X1799730Y157657D01*
X1799938Y157448D01*
G01X1801148Y157437D02*
Y153437D01*
X1808548D01*
G01X1775270Y143250D02*
Y139250D01*
X1782670D01*
G01X1775270Y138750D02*
Y134750D01*
X1782670D01*
G01X1775270Y134250D02*
Y130250D01*
X1782670D01*
G01X1775270Y129750D02*
Y125750D01*
X1782670D01*
G01X1775270Y125250D02*
Y121250D01*
X1782670D01*
G01X1775270Y152750D02*
Y148750D01*
X1782670D01*
G01X1775270Y148250D02*
Y144250D01*
X1782670D01*
G01X1828700Y155033D02*
Y153367D01*
X1826200D01*
Y155033D01*
G01X1827408Y154367D02*
Y153367D01*
G01X1826200Y156383D02*
X1827992D01*
X1828367Y156550D01*
X1828617Y156883D01*
X1828700Y157300D01*
X1828617Y157717D01*
X1828367Y158050D01*
X1827992Y158217D01*
X1826200D01*
G01X1828408Y159692D02*
X1828617Y159983D01*
X1828700Y160317D01*
X1828617Y160650D01*
X1828367Y160942D01*
X1827992Y161150D01*
X1827617Y161233D01*
X1827158D01*
X1826783Y161150D01*
X1826450Y160942D01*
X1826283Y160692D01*
X1826200Y160400D01*
X1826283Y160067D01*
X1826450Y159817D01*
X1826700Y159650D01*
X1827033Y159567D01*
X1827325Y159650D01*
X1827617Y159858D01*
X1827783Y160108D01*
X1827825Y160400D01*
X1827742Y160733D01*
X1827533Y160983D01*
X1827158Y161233D01*
G01X1828700Y162708D02*
X1826200D01*
Y164292D01*
G01X1827408Y163708D02*
Y162708D01*
G01X1828700Y166600D02*
X1826200D01*
X1826700Y166100D01*
G01X1828700D02*
Y167100D01*
G01X1790617Y171292D02*
X1790367Y171417D01*
X1790075Y171500D01*
X1789742D01*
X1789367Y171375D01*
X1789075Y171167D01*
X1788867Y170917D01*
X1788700Y170500D01*
X1788658Y170125D01*
X1788742Y169750D01*
X1788867Y169500D01*
X1789117Y169250D01*
X1789408Y169083D01*
X1789700Y169000D01*
X1789992D01*
X1790283Y169083D01*
X1790533Y169208D01*
X1790742Y169375D01*
G01X1792092Y169292D02*
X1792383Y169083D01*
X1792717Y169000D01*
X1793050Y169083D01*
X1793342Y169333D01*
X1793550Y169708D01*
X1793633Y170083D01*
Y170542D01*
X1793550Y170917D01*
X1793342Y171250D01*
X1793092Y171417D01*
X1792800Y171500D01*
X1792467Y171417D01*
X1792217Y171250D01*
X1792050Y171000D01*
X1791967Y170667D01*
X1792050Y170375D01*
X1792258Y170083D01*
X1792508Y169917D01*
X1792800Y169875D01*
X1793133Y169958D01*
X1793383Y170167D01*
X1793633Y170542D01*
G01X1795108Y169000D02*
Y171500D01*
X1796692D01*
G01X1796108Y170292D02*
X1795108D01*
G01X1799500Y169000D02*
Y171500D01*
X1797958Y169708D01*
X1800042D01*
G01X1783900Y157467D02*
X1781400D01*
Y158508D01*
X1781525Y158842D01*
X1781692Y159050D01*
X1782025Y159133D01*
X1782358Y159050D01*
X1782567Y158800D01*
X1782692Y158508D01*
Y157467D01*
G01Y158508D02*
X1783900Y159133D01*
G01X1783608Y160692D02*
X1783817Y160983D01*
X1783900Y161317D01*
X1783817Y161650D01*
X1783567Y161942D01*
X1783192Y162150D01*
X1782817Y162233D01*
X1782358D01*
X1781983Y162150D01*
X1781650Y161942D01*
X1781483Y161692D01*
X1781400Y161400D01*
X1781483Y161067D01*
X1781650Y160817D01*
X1781900Y160650D01*
X1782233Y160567D01*
X1782525Y160650D01*
X1782817Y160858D01*
X1782983Y161108D01*
X1783025Y161400D01*
X1782942Y161733D01*
X1782733Y161983D01*
X1782358Y162233D01*
G01X1783900Y165333D02*
Y163667D01*
X1781400D01*
Y165333D01*
G01X1782608Y164667D02*
Y163667D01*
G01X1781817Y166808D02*
X1781567Y167058D01*
X1781442Y167350D01*
X1781400Y167683D01*
X1781483Y168100D01*
X1781692Y168392D01*
X1781942Y168475D01*
X1782192Y168433D01*
X1782400Y168267D01*
X1782817Y167433D01*
X1783108Y167058D01*
X1783525Y166808D01*
X1783900Y166725D01*
Y168475D01*
G01Y170700D02*
X1781400D01*
X1781900Y170200D01*
G01X1783900D02*
Y171200D01*
G01X1776900Y158467D02*
X1774400D01*
Y159508D01*
X1774525Y159842D01*
X1774692Y160050D01*
X1775025Y160133D01*
X1775358Y160050D01*
X1775567Y159800D01*
X1775692Y159508D01*
Y158467D01*
G01Y159508D02*
X1776900Y160133D01*
G01X1776608Y161692D02*
X1776817Y161983D01*
X1776900Y162317D01*
X1776817Y162650D01*
X1776567Y162942D01*
X1776192Y163150D01*
X1775817Y163233D01*
X1775358D01*
X1774983Y163150D01*
X1774650Y162942D01*
X1774483Y162692D01*
X1774400Y162400D01*
X1774483Y162067D01*
X1774650Y161817D01*
X1774900Y161650D01*
X1775233Y161567D01*
X1775525Y161650D01*
X1775817Y161858D01*
X1775983Y162108D01*
X1776025Y162400D01*
X1775942Y162733D01*
X1775733Y162983D01*
X1775358Y163233D01*
G01X1776900Y164708D02*
X1774400D01*
Y166292D01*
G01X1775608Y165708D02*
Y164708D01*
G01X1776400Y167683D02*
X1776692Y167933D01*
X1776858Y168267D01*
X1776900Y168642D01*
X1776858Y168975D01*
X1776650Y169308D01*
X1776400Y169517D01*
X1776150Y169558D01*
X1775858Y169475D01*
X1775650Y169183D01*
X1775567Y168892D01*
Y168517D01*
G01Y168892D02*
X1775442Y169142D01*
X1775233Y169350D01*
X1774983Y169433D01*
X1774733Y169350D01*
X1774525Y169142D01*
X1774400Y168767D01*
X1774442Y168392D01*
X1774608Y168017D01*
G01X1776900Y172200D02*
X1774400D01*
X1776192Y170658D01*
Y172742D01*
G01X1780400Y157467D02*
X1777900D01*
Y158508D01*
X1778025Y158842D01*
X1778192Y159050D01*
X1778525Y159133D01*
X1778858Y159050D01*
X1779067Y158800D01*
X1779192Y158508D01*
Y157467D01*
G01Y158508D02*
X1780400Y159133D01*
G01X1780108Y160692D02*
X1780317Y160983D01*
X1780400Y161317D01*
X1780317Y161650D01*
X1780067Y161942D01*
X1779692Y162150D01*
X1779317Y162233D01*
X1778858D01*
X1778483Y162150D01*
X1778150Y161942D01*
X1777983Y161692D01*
X1777900Y161400D01*
X1777983Y161067D01*
X1778150Y160817D01*
X1778400Y160650D01*
X1778733Y160567D01*
X1779025Y160650D01*
X1779317Y160858D01*
X1779483Y161108D01*
X1779525Y161400D01*
X1779442Y161733D01*
X1779233Y161983D01*
X1778858Y162233D01*
G01X1780400Y165333D02*
Y163667D01*
X1777900D01*
Y165333D01*
G01X1779108Y164667D02*
Y163667D01*
G01X1778317Y166808D02*
X1778067Y167058D01*
X1777942Y167350D01*
X1777900Y167683D01*
X1777983Y168100D01*
X1778192Y168392D01*
X1778442Y168475D01*
X1778692Y168433D01*
X1778900Y168267D01*
X1779317Y167433D01*
X1779608Y167058D01*
X1780025Y166808D01*
X1780400Y166725D01*
Y168475D01*
G01Y171200D02*
X1777900D01*
X1779692Y169658D01*
Y171742D01*
G01X1828908Y170267D02*
X1828783Y170017D01*
X1828700Y169725D01*
Y169392D01*
X1828825Y169017D01*
X1829033Y168725D01*
X1829283Y168517D01*
X1829700Y168350D01*
X1830075Y168308D01*
X1830450Y168392D01*
X1830700Y168517D01*
X1830950Y168767D01*
X1831117Y169058D01*
X1831200Y169350D01*
Y169642D01*
X1831117Y169933D01*
X1830992Y170183D01*
X1830825Y170392D01*
G01X1830908Y171742D02*
X1831117Y172033D01*
X1831200Y172367D01*
X1831117Y172700D01*
X1830867Y172992D01*
X1830492Y173200D01*
X1830117Y173283D01*
X1829658D01*
X1829283Y173200D01*
X1828950Y172992D01*
X1828783Y172742D01*
X1828700Y172450D01*
X1828783Y172117D01*
X1828950Y171867D01*
X1829200Y171700D01*
X1829533Y171617D01*
X1829825Y171700D01*
X1830117Y171908D01*
X1830283Y172158D01*
X1830325Y172450D01*
X1830242Y172783D01*
X1830033Y173033D01*
X1829658Y173283D01*
G01X1831200Y174758D02*
X1828700D01*
Y176342D01*
G01X1829908Y175758D02*
Y174758D01*
G01X1830700Y177733D02*
X1830992Y177983D01*
X1831158Y178317D01*
X1831200Y178692D01*
X1831158Y179025D01*
X1830950Y179358D01*
X1830700Y179567D01*
X1830450Y179608D01*
X1830158Y179525D01*
X1829950Y179233D01*
X1829867Y178942D01*
Y178567D01*
G01Y178942D02*
X1829742Y179192D01*
X1829533Y179400D01*
X1829283Y179483D01*
X1829033Y179400D01*
X1828825Y179192D01*
X1828700Y178817D01*
X1828742Y178442D01*
X1828908Y178067D01*
G01X1790617Y174792D02*
X1790367Y174917D01*
X1790075Y175000D01*
X1789742D01*
X1789367Y174875D01*
X1789075Y174667D01*
X1788867Y174417D01*
X1788700Y174000D01*
X1788658Y173625D01*
X1788742Y173250D01*
X1788867Y173000D01*
X1789117Y172750D01*
X1789408Y172583D01*
X1789700Y172500D01*
X1789992D01*
X1790283Y172583D01*
X1790533Y172708D01*
X1790742Y172875D01*
G01X1792092Y172792D02*
X1792383Y172583D01*
X1792717Y172500D01*
X1793050Y172583D01*
X1793342Y172833D01*
X1793550Y173208D01*
X1793633Y173583D01*
Y174042D01*
X1793550Y174417D01*
X1793342Y174750D01*
X1793092Y174917D01*
X1792800Y175000D01*
X1792467Y174917D01*
X1792217Y174750D01*
X1792050Y174500D01*
X1791967Y174167D01*
X1792050Y173875D01*
X1792258Y173583D01*
X1792508Y173417D01*
X1792800Y173375D01*
X1793133Y173458D01*
X1793383Y173667D01*
X1793633Y174042D01*
G01X1796733Y172500D02*
X1795067D01*
Y175000D01*
X1796733D01*
G01X1796067Y173792D02*
X1795067D01*
G01X1799000Y172500D02*
Y175000D01*
X1798500Y174500D01*
G01Y172500D02*
X1799500D01*
G01X1802100Y175000D02*
X1801767Y174917D01*
X1801517Y174708D01*
X1801350Y174458D01*
X1801225Y174125D01*
X1801183Y173750D01*
X1801225Y173375D01*
X1801350Y173042D01*
X1801517Y172792D01*
X1801767Y172583D01*
X1802100Y172500D01*
X1802433Y172583D01*
X1802683Y172792D01*
X1802850Y173042D01*
X1802975Y173375D01*
X1803017Y173750D01*
X1802975Y174125D01*
X1802850Y174458D01*
X1802683Y174708D01*
X1802433Y174917D01*
X1802100Y175000D01*
G01X1832408Y170267D02*
X1832283Y170017D01*
X1832200Y169725D01*
Y169392D01*
X1832325Y169017D01*
X1832533Y168725D01*
X1832783Y168517D01*
X1833200Y168350D01*
X1833575Y168308D01*
X1833950Y168392D01*
X1834200Y168517D01*
X1834450Y168767D01*
X1834617Y169058D01*
X1834700Y169350D01*
Y169642D01*
X1834617Y169933D01*
X1834492Y170183D01*
X1834325Y170392D01*
G01X1834408Y171742D02*
X1834617Y172033D01*
X1834700Y172367D01*
X1834617Y172700D01*
X1834367Y172992D01*
X1833992Y173200D01*
X1833617Y173283D01*
X1833158D01*
X1832783Y173200D01*
X1832450Y172992D01*
X1832283Y172742D01*
X1832200Y172450D01*
X1832283Y172117D01*
X1832450Y171867D01*
X1832700Y171700D01*
X1833033Y171617D01*
X1833325Y171700D01*
X1833617Y171908D01*
X1833783Y172158D01*
X1833825Y172450D01*
X1833742Y172783D01*
X1833533Y173033D01*
X1833158Y173283D01*
G01X1834700Y176383D02*
Y174717D01*
X1832200D01*
Y176383D01*
G01X1833408Y175717D02*
Y174717D01*
G01X1834700Y178650D02*
X1832200D01*
X1832700Y178150D01*
G01X1834700D02*
Y179150D01*
G01Y181750D02*
X1832200D01*
X1832700Y181250D01*
G01X1834700D02*
Y182250D01*
G01X1832595Y218094D02*
X1832825Y217732D01*
X1833131Y217526D01*
X1833476Y217474D01*
X1833783Y217526D01*
X1834090Y217784D01*
X1834281Y218094D01*
X1834320Y218404D01*
X1834243Y218766D01*
X1833975Y219024D01*
X1833706Y219127D01*
X1833361D01*
G01X1833706D02*
X1833936Y219282D01*
X1834128Y219541D01*
X1834205Y219851D01*
X1834128Y220161D01*
X1833936Y220419D01*
X1833591Y220574D01*
X1833246Y220522D01*
X1832901Y220316D01*
G01X1835810Y220057D02*
X1836040Y220367D01*
X1836308Y220522D01*
X1836615Y220574D01*
X1836998Y220471D01*
X1837266Y220212D01*
X1837343Y219902D01*
X1837305Y219592D01*
X1837151Y219334D01*
X1836385Y218817D01*
X1836040Y218456D01*
X1835810Y217939D01*
X1835733Y217474D01*
X1837343D01*
G01X1833710Y251912D02*
X1833978Y252273D01*
X1834208Y252480D01*
X1834515Y252583D01*
X1834783Y252480D01*
X1834975Y252273D01*
X1835128Y251963D01*
X1835166Y251602D01*
X1835128Y251292D01*
X1834975Y250982D01*
X1834745Y250723D01*
X1834476Y250620D01*
X1834170Y250723D01*
X1833901Y251033D01*
X1833748Y251498D01*
X1833710Y252015D01*
X1833786Y252687D01*
X1833901Y253048D01*
X1834093Y253410D01*
X1834361Y253668D01*
X1834630Y253720D01*
X1834898Y253617D01*
X1835090Y253358D01*
G01X1837998Y250620D02*
Y253720D01*
X1836580Y251498D01*
X1838496D01*
G01X1834387Y221749D02*
X1845374D01*
Y231630D01*
G01Y239230D02*
Y249112D01*
X1834387D01*
G01X1834533Y480696D02*
X1832033D01*
Y481737D01*
X1832158Y482071D01*
X1832325Y482279D01*
X1832658Y482362D01*
X1832991Y482279D01*
X1833200Y482029D01*
X1833325Y481737D01*
Y480696D01*
G01Y481737D02*
X1834533Y482362D01*
G01X1834241Y483921D02*
X1834450Y484212D01*
X1834533Y484546D01*
X1834450Y484879D01*
X1834200Y485171D01*
X1833825Y485379D01*
X1833450Y485462D01*
X1832991D01*
X1832616Y485379D01*
X1832283Y485171D01*
X1832116Y484921D01*
X1832033Y484629D01*
X1832116Y484296D01*
X1832283Y484046D01*
X1832533Y483879D01*
X1832866Y483796D01*
X1833158Y483879D01*
X1833450Y484087D01*
X1833616Y484337D01*
X1833658Y484629D01*
X1833575Y484962D01*
X1833366Y485212D01*
X1832991Y485462D01*
G01X1833200Y488062D02*
X1833075Y488229D01*
X1832866Y488354D01*
X1832575Y488437D01*
X1832325Y488354D01*
X1832158Y488187D01*
X1832033Y487896D01*
Y486771D01*
X1834533D01*
Y488146D01*
X1834366Y488437D01*
X1834116Y488604D01*
X1833825Y488687D01*
X1833533Y488604D01*
X1833283Y488354D01*
X1833200Y488062D01*
Y486771D01*
G01X1834533Y490829D02*
X1832033D01*
X1832533Y490329D01*
G01X1834533D02*
Y491329D01*
G01Y494429D02*
X1832033D01*
X1833825Y492887D01*
Y494971D01*
G01X1833293Y515279D02*
X1830793D01*
Y516320D01*
X1830918Y516654D01*
X1831085Y516862D01*
X1831418Y516945D01*
X1831751Y516862D01*
X1831960Y516612D01*
X1832085Y516320D01*
Y515279D01*
G01Y516320D02*
X1833293Y516945D01*
G01X1833001Y518504D02*
X1833210Y518795D01*
X1833293Y519129D01*
X1833210Y519462D01*
X1832960Y519754D01*
X1832585Y519962D01*
X1832210Y520045D01*
X1831751D01*
X1831376Y519962D01*
X1831043Y519754D01*
X1830876Y519504D01*
X1830793Y519212D01*
X1830876Y518879D01*
X1831043Y518629D01*
X1831293Y518462D01*
X1831626Y518379D01*
X1831918Y518462D01*
X1832210Y518670D01*
X1832376Y518920D01*
X1832418Y519212D01*
X1832335Y519545D01*
X1832126Y519795D01*
X1831751Y520045D01*
G01X1831960Y522645D02*
X1831835Y522812D01*
X1831626Y522937D01*
X1831335Y523020D01*
X1831085Y522937D01*
X1830918Y522770D01*
X1830793Y522479D01*
Y521354D01*
X1833293D01*
Y522729D01*
X1833126Y523020D01*
X1832876Y523187D01*
X1832585Y523270D01*
X1832293Y523187D01*
X1832043Y522937D01*
X1831960Y522645D01*
Y521354D01*
G01X1833001Y524704D02*
X1833210Y524995D01*
X1833293Y525329D01*
X1833210Y525662D01*
X1832960Y525954D01*
X1832585Y526162D01*
X1832210Y526245D01*
X1831751D01*
X1831376Y526162D01*
X1831043Y525954D01*
X1830876Y525704D01*
X1830793Y525412D01*
X1830876Y525079D01*
X1831043Y524829D01*
X1831293Y524662D01*
X1831626Y524579D01*
X1831918Y524662D01*
X1832210Y524870D01*
X1832376Y525120D01*
X1832418Y525412D01*
X1832335Y525745D01*
X1832126Y525995D01*
X1831751Y526245D01*
G01X1804622Y519383D02*
X1804852Y519693D01*
X1805120Y519848D01*
X1805427Y519900D01*
X1805810Y519797D01*
X1806078Y519538D01*
X1806155Y519228D01*
X1806117Y518918D01*
X1805963Y518660D01*
X1805197Y518143D01*
X1804852Y517782D01*
X1804622Y517265D01*
X1804545Y516800D01*
X1806155D01*
G01X1829628Y526169D02*
X1829886Y526399D01*
X1830041Y526667D01*
X1830093Y527012D01*
X1829990Y527357D01*
X1829783Y527625D01*
X1829421Y527817D01*
X1829008Y527855D01*
X1828595Y527779D01*
X1828336Y527587D01*
X1828130Y527319D01*
X1828078Y527050D01*
X1828130Y526782D01*
X1828336Y526437D01*
X1826993Y526552D01*
Y527587D01*
G01X1829731Y529460D02*
X1829990Y529729D01*
X1830093Y530035D01*
X1829990Y530342D01*
X1829680Y530610D01*
X1829215Y530802D01*
X1828750Y530879D01*
X1828181D01*
X1827716Y530802D01*
X1827303Y530610D01*
X1827096Y530380D01*
X1826993Y530112D01*
X1827096Y529805D01*
X1827303Y529575D01*
X1827613Y529422D01*
X1828026Y529345D01*
X1828388Y529422D01*
X1828750Y529614D01*
X1828956Y529844D01*
X1829008Y530112D01*
X1828905Y530419D01*
X1828646Y530649D01*
X1828181Y530879D01*
G01X1825833Y520898D02*
X1804683D01*
G01X1797133Y525877D02*
Y532467D01*
G01X1825833Y520898D02*
Y532293D01*
G01X1809840Y495503D02*
X1809590Y495628D01*
X1809298Y495711D01*
X1808965D01*
X1808590Y495586D01*
X1808298Y495378D01*
X1808090Y495128D01*
X1807923Y494711D01*
X1807881Y494336D01*
X1807965Y493961D01*
X1808090Y493711D01*
X1808340Y493461D01*
X1808631Y493294D01*
X1808923Y493211D01*
X1809215D01*
X1809506Y493294D01*
X1809756Y493419D01*
X1809965Y493586D01*
G01X1811315Y493503D02*
X1811606Y493294D01*
X1811940Y493211D01*
X1812273Y493294D01*
X1812565Y493544D01*
X1812773Y493919D01*
X1812856Y494294D01*
Y494753D01*
X1812773Y495128D01*
X1812565Y495461D01*
X1812315Y495628D01*
X1812023Y495711D01*
X1811690Y495628D01*
X1811440Y495461D01*
X1811273Y495211D01*
X1811190Y494878D01*
X1811273Y494586D01*
X1811481Y494294D01*
X1811731Y494128D01*
X1812023Y494086D01*
X1812356Y494169D01*
X1812606Y494378D01*
X1812856Y494753D01*
G01X1815456Y494544D02*
X1815623Y494669D01*
X1815748Y494878D01*
X1815831Y495169D01*
X1815748Y495419D01*
X1815581Y495586D01*
X1815290Y495711D01*
X1814165D01*
Y493211D01*
X1815540D01*
X1815831Y493378D01*
X1815998Y493628D01*
X1816081Y493919D01*
X1815998Y494211D01*
X1815748Y494461D01*
X1815456Y494544D01*
X1814165D01*
G01X1818223Y493211D02*
X1818515Y493253D01*
X1818848Y493378D01*
X1819056Y493586D01*
X1819140Y493878D01*
X1819056Y494169D01*
X1818806Y494419D01*
X1818431Y494544D01*
X1818015D01*
X1817765Y494628D01*
X1817556Y494836D01*
X1817473Y495128D01*
X1817598Y495419D01*
X1817890Y495628D01*
X1818223Y495711D01*
X1818556Y495628D01*
X1818848Y495419D01*
X1818973Y495128D01*
X1818890Y494836D01*
X1818681Y494628D01*
X1818431Y494544D01*
X1818015D01*
X1817640Y494419D01*
X1817390Y494169D01*
X1817306Y493878D01*
X1817390Y493586D01*
X1817598Y493378D01*
X1817931Y493253D01*
X1818223Y493211D01*
G01X1799050Y499100D02*
Y496850D01*
X1828950D01*
Y497900D01*
G01Y513900D02*
Y514950D01*
X1799050D01*
Y512700D01*
G01X1834000D02*
Y513900D01*
X1822000D01*
Y512700D01*
G01X1834000Y499100D02*
Y497900D01*
X1822000D01*
Y499100D01*
G01X1788558Y552893D02*
X1788403Y552663D01*
X1788300Y552395D01*
Y552088D01*
X1788455Y551743D01*
X1788713Y551475D01*
X1789023Y551283D01*
X1789540Y551130D01*
X1790005Y551092D01*
X1790470Y551168D01*
X1790780Y551283D01*
X1791090Y551513D01*
X1791297Y551782D01*
X1791400Y552050D01*
Y552318D01*
X1791297Y552587D01*
X1791142Y552817D01*
X1790935Y553008D01*
G01X1791400Y554383D02*
X1788300D01*
Y555303D01*
X1788455Y555610D01*
X1788817Y555840D01*
X1789230Y555917D01*
X1789643Y555840D01*
X1789953Y555648D01*
X1790108Y555303D01*
Y554383D01*
G01X1788300Y557407D02*
X1790522D01*
X1790987Y557560D01*
X1791297Y557867D01*
X1791400Y558250D01*
X1791297Y558633D01*
X1790987Y558940D01*
X1790522Y559093D01*
X1788300D01*
G01X1792433Y562500D02*
X1789333Y560583D01*
X1788817D01*
X1788300Y560967D01*
Y561350D01*
X1788817Y561733D01*
X1789333D01*
X1789850Y561350D01*
X1790367Y560583D01*
X1790883Y560200D01*
X1791917D01*
X1792433Y560583D01*
Y561733D01*
X1791400Y562500D01*
G01Y563683D02*
X1788300D01*
Y564603D01*
X1788455Y564910D01*
X1788817Y565140D01*
X1789230Y565217D01*
X1789643Y565140D01*
X1789953Y564948D01*
X1790108Y564603D01*
Y563683D01*
G01X1788558Y568393D02*
X1788403Y568163D01*
X1788300Y567895D01*
Y567588D01*
X1788455Y567243D01*
X1788713Y566975D01*
X1789023Y566783D01*
X1789540Y566630D01*
X1790005Y566592D01*
X1790470Y566668D01*
X1790780Y566783D01*
X1791090Y567013D01*
X1791297Y567282D01*
X1791400Y567550D01*
Y567818D01*
X1791297Y568087D01*
X1791142Y568317D01*
X1790935Y568508D01*
G01X1791400Y569845D02*
X1788300D01*
G01Y571455D02*
X1791400D01*
G01X1789850D02*
Y569845D01*
G01X1791400Y576045D02*
X1788300Y577655D01*
G01Y576045D02*
X1791400Y577655D01*
G01Y579107D02*
X1788300D01*
Y579873D01*
X1788455Y580180D01*
X1788662Y580410D01*
X1788972Y580602D01*
X1789333Y580755D01*
X1789850Y580793D01*
X1790367Y580755D01*
X1790728Y580602D01*
X1791038Y580410D01*
X1791245Y580180D01*
X1791400Y579873D01*
Y579107D01*
G01Y582283D02*
X1788300D01*
Y583203D01*
X1788455Y583510D01*
X1788817Y583740D01*
X1789230Y583817D01*
X1789643Y583740D01*
X1789953Y583548D01*
X1790108Y583203D01*
Y582283D01*
G01X1785860Y553923D02*
X1783360D01*
Y554964D01*
X1783485Y555298D01*
X1783652Y555506D01*
X1783985Y555589D01*
X1784318Y555506D01*
X1784527Y555256D01*
X1784652Y554964D01*
Y553923D01*
G01Y554964D02*
X1785860Y555589D01*
G01X1783777Y557064D02*
X1783527Y557314D01*
X1783402Y557606D01*
X1783360Y557939D01*
X1783443Y558356D01*
X1783652Y558648D01*
X1783902Y558731D01*
X1784152Y558689D01*
X1784360Y558523D01*
X1784777Y557689D01*
X1785068Y557314D01*
X1785485Y557064D01*
X1785860Y556981D01*
Y558731D01*
G01X1785485Y560039D02*
X1785693Y560289D01*
X1785818Y560581D01*
X1785860Y560956D01*
X1785777Y561331D01*
X1785610Y561623D01*
X1785318Y561831D01*
X1784985Y561873D01*
X1784652Y561789D01*
X1784443Y561581D01*
X1784277Y561289D01*
X1784235Y560998D01*
X1784277Y560706D01*
X1784443Y560331D01*
X1783360Y560456D01*
Y561581D01*
G01Y562806D02*
X1785860Y563389D01*
X1783360Y564056D01*
X1785860Y564723D01*
X1783360Y565306D01*
G01X1785860Y567156D02*
X1783360D01*
X1783860Y566656D01*
G01X1785860D02*
Y567656D01*
G01Y570256D02*
X1785818Y570548D01*
X1785693Y570881D01*
X1785485Y571089D01*
X1785193Y571173D01*
X1784902Y571089D01*
X1784652Y570839D01*
X1784527Y570464D01*
Y570048D01*
X1784443Y569798D01*
X1784235Y569589D01*
X1783943Y569506D01*
X1783652Y569631D01*
X1783443Y569923D01*
X1783360Y570256D01*
X1783443Y570589D01*
X1783652Y570881D01*
X1783943Y571006D01*
X1784235Y570923D01*
X1784443Y570714D01*
X1784527Y570464D01*
Y570048D01*
X1784652Y569673D01*
X1784902Y569423D01*
X1785193Y569339D01*
X1785485Y569423D01*
X1785693Y569631D01*
X1785818Y569964D01*
X1785860Y570256D01*
G01X1785485Y572439D02*
X1785693Y572689D01*
X1785818Y572981D01*
X1785860Y573356D01*
X1785777Y573731D01*
X1785610Y574023D01*
X1785318Y574231D01*
X1784985Y574273D01*
X1784652Y574189D01*
X1784443Y573981D01*
X1784277Y573689D01*
X1784235Y573398D01*
X1784277Y573106D01*
X1784443Y572731D01*
X1783360Y572856D01*
Y573981D01*
G01X1829333Y555800D02*
Y554008D01*
X1829500Y553633D01*
X1829833Y553383D01*
X1830250Y553300D01*
X1830667Y553383D01*
X1831000Y553633D01*
X1831167Y554008D01*
Y555800D01*
G01X1832642Y553592D02*
X1832933Y553383D01*
X1833267Y553300D01*
X1833600Y553383D01*
X1833892Y553633D01*
X1834100Y554008D01*
X1834183Y554383D01*
Y554842D01*
X1834100Y555217D01*
X1833892Y555550D01*
X1833642Y555717D01*
X1833350Y555800D01*
X1833017Y555717D01*
X1832767Y555550D01*
X1832600Y555300D01*
X1832517Y554967D01*
X1832600Y554675D01*
X1832808Y554383D01*
X1833058Y554217D01*
X1833350Y554175D01*
X1833683Y554258D01*
X1833933Y554467D01*
X1834183Y554842D01*
G01X1835408Y553300D02*
X1836450Y555800D01*
X1837492Y553300D01*
G01X1837117Y554175D02*
X1835783D01*
G01X1838633Y553675D02*
X1838883Y553467D01*
X1839175Y553342D01*
X1839550Y553300D01*
X1839925Y553383D01*
X1840217Y553550D01*
X1840425Y553842D01*
X1840467Y554175D01*
X1840383Y554508D01*
X1840175Y554717D01*
X1839883Y554883D01*
X1839592Y554925D01*
X1839300Y554883D01*
X1838925Y554717D01*
X1839050Y555800D01*
X1840175D01*
G01X1835471Y556913D02*
X1835721Y557121D01*
X1835888Y557371D01*
X1835971Y557663D01*
X1835888Y557996D01*
X1835721Y558246D01*
X1835471Y558496D01*
X1835138Y558579D01*
X1833471D01*
G01X1835679Y560138D02*
X1835888Y560429D01*
X1835971Y560763D01*
X1835888Y561096D01*
X1835638Y561388D01*
X1835263Y561596D01*
X1834888Y561679D01*
X1834429D01*
X1834054Y561596D01*
X1833721Y561388D01*
X1833554Y561138D01*
X1833471Y560846D01*
X1833554Y560513D01*
X1833721Y560263D01*
X1833971Y560096D01*
X1834304Y560013D01*
X1834596Y560096D01*
X1834888Y560304D01*
X1835054Y560554D01*
X1835096Y560846D01*
X1835013Y561179D01*
X1834804Y561429D01*
X1834429Y561679D01*
G01X1835971Y562904D02*
X1833471Y563946D01*
X1835971Y564988D01*
G01X1835096Y564613D02*
Y563279D01*
G01X1835471Y566129D02*
X1835763Y566379D01*
X1835929Y566713D01*
X1835971Y567088D01*
X1835929Y567421D01*
X1835721Y567754D01*
X1835471Y567963D01*
X1835221Y568004D01*
X1834929Y567921D01*
X1834721Y567629D01*
X1834638Y567338D01*
Y566963D01*
G01Y567338D02*
X1834513Y567588D01*
X1834304Y567796D01*
X1834054Y567879D01*
X1833804Y567796D01*
X1833596Y567588D01*
X1833471Y567213D01*
X1833513Y566838D01*
X1833679Y566463D01*
G01X1808092Y611200D02*
X1809050Y608100D01*
X1810008Y611200D01*
G01X1811383Y608100D02*
Y611200D01*
X1812342D01*
X1812648Y611045D01*
X1812840Y610838D01*
X1812917Y610425D01*
X1812840Y610012D01*
X1812610Y609753D01*
X1812342Y609598D01*
X1811383D01*
G01X1812342D02*
X1812917Y608100D01*
G01X1814100Y607067D02*
X1816400D01*
G01X1817507Y608100D02*
Y611200D01*
X1818273D01*
X1818580Y611045D01*
X1818810Y610838D01*
X1819002Y610528D01*
X1819155Y610167D01*
X1819193Y609650D01*
X1819155Y609133D01*
X1819002Y608772D01*
X1818810Y608462D01*
X1818580Y608255D01*
X1818273Y608100D01*
X1817507D01*
G01X1821757Y609753D02*
X1821910Y609908D01*
X1822025Y610167D01*
X1822102Y610528D01*
X1822025Y610838D01*
X1821872Y611045D01*
X1821603Y611200D01*
X1820568D01*
Y608100D01*
X1821833D01*
X1822102Y608307D01*
X1822255Y608617D01*
X1822332Y608978D01*
X1822255Y609340D01*
X1822025Y609650D01*
X1821757Y609753D01*
X1820568D01*
G01X1824780Y609650D02*
X1825547D01*
Y608720D01*
X1825317Y608410D01*
X1825048Y608203D01*
X1824665Y608100D01*
X1824282Y608203D01*
X1824013Y608410D01*
X1823783Y608720D01*
X1823630Y609082D01*
X1823553Y609495D01*
Y609857D01*
X1823630Y610167D01*
X1823783Y610528D01*
X1824013Y610838D01*
X1824243Y611045D01*
X1824550Y611200D01*
X1824818D01*
X1825125Y611097D01*
X1825355Y610890D01*
G01X1832280Y595802D02*
Y598302D01*
X1833321D01*
X1833655Y598177D01*
X1833863Y598010D01*
X1833946Y597677D01*
X1833863Y597344D01*
X1833613Y597135D01*
X1833321Y597010D01*
X1832280D01*
G01X1833321D02*
X1833946Y595802D01*
G01X1835505Y596094D02*
X1835796Y595885D01*
X1836130Y595802D01*
X1836463Y595885D01*
X1836755Y596135D01*
X1836963Y596510D01*
X1837046Y596885D01*
Y597344D01*
X1836963Y597719D01*
X1836755Y598052D01*
X1836505Y598219D01*
X1836213Y598302D01*
X1835880Y598219D01*
X1835630Y598052D01*
X1835463Y597802D01*
X1835380Y597469D01*
X1835463Y597177D01*
X1835671Y596885D01*
X1835921Y596719D01*
X1836213Y596677D01*
X1836546Y596760D01*
X1836796Y596969D01*
X1837046Y597344D01*
G01X1838271Y595802D02*
X1839313Y598302D01*
X1840355Y595802D01*
G01X1839980Y596677D02*
X1838646D01*
G01X1842413Y595802D02*
Y598302D01*
X1841913Y597802D01*
G01Y595802D02*
X1842913D01*
G01X1844596Y596177D02*
X1844846Y595969D01*
X1845138Y595844D01*
X1845513Y595802D01*
X1845888Y595885D01*
X1846180Y596052D01*
X1846388Y596344D01*
X1846430Y596677D01*
X1846346Y597010D01*
X1846138Y597219D01*
X1845846Y597385D01*
X1845555Y597427D01*
X1845263Y597385D01*
X1844888Y597219D01*
X1845013Y598302D01*
X1846138D01*
G01X1778670Y607297D02*
X1776170D01*
Y608338D01*
X1776295Y608672D01*
X1776462Y608880D01*
X1776795Y608963D01*
X1777128Y608880D01*
X1777337Y608630D01*
X1777462Y608338D01*
Y607297D01*
G01Y608338D02*
X1778670Y608963D01*
G01X1778378Y610522D02*
X1778587Y610813D01*
X1778670Y611147D01*
X1778587Y611480D01*
X1778337Y611772D01*
X1777962Y611980D01*
X1777587Y612063D01*
X1777128D01*
X1776753Y611980D01*
X1776420Y611772D01*
X1776253Y611522D01*
X1776170Y611230D01*
X1776253Y610897D01*
X1776420Y610647D01*
X1776670Y610480D01*
X1777003Y610397D01*
X1777295Y610480D01*
X1777587Y610688D01*
X1777753Y610938D01*
X1777795Y611230D01*
X1777712Y611563D01*
X1777503Y611813D01*
X1777128Y612063D01*
G01X1778670Y613288D02*
X1776170Y614330D01*
X1778670Y615372D01*
G01X1777795Y614997D02*
Y613663D01*
G01X1778670Y617430D02*
X1776170D01*
X1776670Y616930D01*
G01X1778670D02*
Y617930D01*
G01X1792200Y591517D02*
X1789700D01*
Y592558D01*
X1789825Y592892D01*
X1789992Y593100D01*
X1790325Y593183D01*
X1790658Y593100D01*
X1790867Y592850D01*
X1790992Y592558D01*
Y591517D01*
G01Y592558D02*
X1792200Y593183D01*
G01X1791908Y594742D02*
X1792117Y595033D01*
X1792200Y595367D01*
X1792117Y595700D01*
X1791867Y595992D01*
X1791492Y596200D01*
X1791117Y596283D01*
X1790658D01*
X1790283Y596200D01*
X1789950Y595992D01*
X1789783Y595742D01*
X1789700Y595450D01*
X1789783Y595117D01*
X1789950Y594867D01*
X1790200Y594700D01*
X1790533Y594617D01*
X1790825Y594700D01*
X1791117Y594908D01*
X1791283Y595158D01*
X1791325Y595450D01*
X1791242Y595783D01*
X1791033Y596033D01*
X1790658Y596283D01*
G01X1792200Y597508D02*
X1789700Y598550D01*
X1792200Y599592D01*
G01X1791325Y599217D02*
Y597883D01*
G01X1792200Y602150D02*
X1789700D01*
X1791492Y600608D01*
Y602692D01*
G01X1785430Y590617D02*
X1782930D01*
Y591658D01*
X1783055Y591992D01*
X1783222Y592200D01*
X1783555Y592283D01*
X1783888Y592200D01*
X1784097Y591950D01*
X1784222Y591658D01*
Y590617D01*
G01Y591658D02*
X1785430Y592283D01*
G01X1783347Y593758D02*
X1783097Y594008D01*
X1782972Y594300D01*
X1782930Y594633D01*
X1783013Y595050D01*
X1783222Y595342D01*
X1783472Y595425D01*
X1783722Y595383D01*
X1783930Y595217D01*
X1784347Y594383D01*
X1784638Y594008D01*
X1785055Y593758D01*
X1785430Y593675D01*
Y595425D01*
G01X1785055Y596733D02*
X1785263Y596983D01*
X1785388Y597275D01*
X1785430Y597650D01*
X1785347Y598025D01*
X1785180Y598317D01*
X1784888Y598525D01*
X1784555Y598567D01*
X1784222Y598483D01*
X1784013Y598275D01*
X1783847Y597983D01*
X1783805Y597692D01*
X1783847Y597400D01*
X1784013Y597025D01*
X1782930Y597150D01*
Y598275D01*
G01Y599500D02*
X1785430Y600083D01*
X1782930Y600750D01*
X1785430Y601417D01*
X1782930Y602000D01*
G01X1785430Y603850D02*
X1782930D01*
X1783430Y603350D01*
G01X1785430D02*
Y604350D01*
G01X1784388Y606158D02*
X1784097Y606450D01*
X1783930Y606700D01*
X1783847Y607033D01*
X1783930Y607325D01*
X1784097Y607533D01*
X1784347Y607700D01*
X1784638Y607742D01*
X1784888Y607700D01*
X1785138Y607533D01*
X1785347Y607283D01*
X1785430Y606992D01*
X1785347Y606658D01*
X1785097Y606367D01*
X1784722Y606200D01*
X1784305Y606158D01*
X1783763Y606242D01*
X1783472Y606367D01*
X1783180Y606575D01*
X1782972Y606867D01*
X1782930Y607158D01*
X1783013Y607450D01*
X1783222Y607658D01*
G01X1785430Y610550D02*
X1782930D01*
X1784722Y609008D01*
Y611092D01*
G01X1826737Y598484D02*
X1826612Y598234D01*
X1826529Y597942D01*
Y597609D01*
X1826654Y597234D01*
X1826862Y596942D01*
X1827112Y596734D01*
X1827529Y596567D01*
X1827904Y596525D01*
X1828279Y596609D01*
X1828529Y596734D01*
X1828779Y596984D01*
X1828946Y597275D01*
X1829029Y597567D01*
Y597859D01*
X1828946Y598150D01*
X1828821Y598400D01*
X1828654Y598609D01*
G01X1828737Y599959D02*
X1828946Y600250D01*
X1829029Y600584D01*
X1828946Y600917D01*
X1828696Y601209D01*
X1828321Y601417D01*
X1827946Y601500D01*
X1827487D01*
X1827112Y601417D01*
X1826779Y601209D01*
X1826612Y600959D01*
X1826529Y600667D01*
X1826612Y600334D01*
X1826779Y600084D01*
X1827029Y599917D01*
X1827362Y599834D01*
X1827654Y599917D01*
X1827946Y600125D01*
X1828112Y600375D01*
X1828154Y600667D01*
X1828071Y601000D01*
X1827862Y601250D01*
X1827487Y601500D01*
G01X1829029Y602725D02*
X1826529Y603767D01*
X1829029Y604809D01*
G01X1828154Y604434D02*
Y603100D01*
G01X1826946Y606075D02*
X1826696Y606325D01*
X1826571Y606617D01*
X1826529Y606950D01*
X1826612Y607367D01*
X1826821Y607659D01*
X1827071Y607742D01*
X1827321Y607700D01*
X1827529Y607534D01*
X1827946Y606700D01*
X1828237Y606325D01*
X1828654Y606075D01*
X1829029Y605992D01*
Y607742D01*
G01X1832165Y601389D02*
X1832040Y601139D01*
X1831957Y600847D01*
Y600514D01*
X1832082Y600139D01*
X1832290Y599847D01*
X1832540Y599639D01*
X1832957Y599472D01*
X1833332Y599430D01*
X1833707Y599514D01*
X1833957Y599639D01*
X1834207Y599889D01*
X1834374Y600180D01*
X1834457Y600472D01*
Y600764D01*
X1834374Y601055D01*
X1834249Y601305D01*
X1834082Y601514D01*
G01X1834165Y602864D02*
X1834374Y603155D01*
X1834457Y603489D01*
X1834374Y603822D01*
X1834124Y604114D01*
X1833749Y604322D01*
X1833374Y604405D01*
X1832915D01*
X1832540Y604322D01*
X1832207Y604114D01*
X1832040Y603864D01*
X1831957Y603572D01*
X1832040Y603239D01*
X1832207Y602989D01*
X1832457Y602822D01*
X1832790Y602739D01*
X1833082Y602822D01*
X1833374Y603030D01*
X1833540Y603280D01*
X1833582Y603572D01*
X1833499Y603905D01*
X1833290Y604155D01*
X1832915Y604405D01*
G01X1834457Y605630D02*
X1831957Y606672D01*
X1834457Y607714D01*
G01X1833582Y607339D02*
Y606005D01*
G01X1834457Y610272D02*
X1831957D01*
X1833749Y608730D01*
Y610814D01*
G01X1801422Y609592D02*
X1801690Y609953D01*
X1801920Y610160D01*
X1802227Y610263D01*
X1802495Y610160D01*
X1802687Y609953D01*
X1802840Y609643D01*
X1802878Y609282D01*
X1802840Y608972D01*
X1802687Y608662D01*
X1802457Y608403D01*
X1802188Y608300D01*
X1801882Y608403D01*
X1801613Y608713D01*
X1801460Y609178D01*
X1801422Y609695D01*
X1801498Y610367D01*
X1801613Y610728D01*
X1801805Y611090D01*
X1802073Y611348D01*
X1802342Y611400D01*
X1802610Y611297D01*
X1802802Y611038D01*
G01X1805250Y611400D02*
X1804943Y611297D01*
X1804713Y611038D01*
X1804560Y610728D01*
X1804445Y610315D01*
X1804407Y609850D01*
X1804445Y609385D01*
X1804560Y608972D01*
X1804713Y608662D01*
X1804943Y608403D01*
X1805250Y608300D01*
X1805557Y608403D01*
X1805787Y608662D01*
X1805940Y608972D01*
X1806055Y609385D01*
X1806093Y609850D01*
X1806055Y610315D01*
X1805940Y610728D01*
X1805787Y611038D01*
X1805557Y611297D01*
X1805250Y611400D01*
G01X1825832Y604849D02*
Y593282D01*
G01X1797132Y593312D02*
Y601021D01*
G01X1825832Y604849D02*
X1804751D01*
G01X1800730Y614180D02*
X1800688Y613847D01*
X1800522Y613555D01*
X1800272Y613305D01*
X1799980Y613138D01*
X1799647Y613055D01*
X1799313D01*
X1798980Y613138D01*
X1798688Y613305D01*
X1798438Y613555D01*
X1798272Y613847D01*
X1798230Y614180D01*
X1798272Y614513D01*
X1798438Y614805D01*
X1798688Y615055D01*
X1798980Y615222D01*
X1799313Y615305D01*
X1799647D01*
X1799980Y615222D01*
X1800272Y615055D01*
X1800522Y614805D01*
X1800688Y614513D01*
X1800730Y614180D01*
G01X1800063Y614513D02*
X1800730Y615013D01*
G01X1800438Y616572D02*
X1800647Y616863D01*
X1800730Y617197D01*
X1800647Y617530D01*
X1800397Y617822D01*
X1800022Y618030D01*
X1799647Y618113D01*
X1799188D01*
X1798813Y618030D01*
X1798480Y617822D01*
X1798313Y617572D01*
X1798230Y617280D01*
X1798313Y616947D01*
X1798480Y616697D01*
X1798730Y616530D01*
X1799063Y616447D01*
X1799355Y616530D01*
X1799647Y616738D01*
X1799813Y616988D01*
X1799855Y617280D01*
X1799772Y617613D01*
X1799563Y617863D01*
X1799188Y618113D01*
G01X1800730Y619338D02*
X1798230Y620380D01*
X1800730Y621422D01*
G01X1799855Y621047D02*
Y619713D01*
G01X1800730Y623480D02*
X1798230D01*
X1798730Y622980D01*
G01X1800730D02*
Y623980D01*
G01X1835165Y624563D02*
Y612763D01*
X1804165D01*
Y624563D01*
X1835165D01*
G01X1836927Y6610D02*
Y9110D01*
X1837968D01*
X1838302Y8985D01*
X1838510Y8818D01*
X1838593Y8485D01*
X1838510Y8152D01*
X1838260Y7943D01*
X1837968Y7818D01*
X1836927D01*
G01X1837968D02*
X1838593Y6610D01*
G01X1840068Y8693D02*
X1840318Y8943D01*
X1840610Y9068D01*
X1840943Y9110D01*
X1841360Y9027D01*
X1841652Y8818D01*
X1841735Y8568D01*
X1841693Y8318D01*
X1841527Y8110D01*
X1840693Y7693D01*
X1840318Y7402D01*
X1840068Y6985D01*
X1839985Y6610D01*
X1841735D01*
G01X1843043Y6985D02*
X1843293Y6777D01*
X1843585Y6652D01*
X1843960Y6610D01*
X1844335Y6693D01*
X1844627Y6860D01*
X1844835Y7152D01*
X1844877Y7485D01*
X1844793Y7818D01*
X1844585Y8027D01*
X1844293Y8193D01*
X1844002Y8235D01*
X1843710Y8193D01*
X1843335Y8027D01*
X1843460Y9110D01*
X1844585D01*
G01X1845810D02*
X1846393Y6610D01*
X1847060Y9110D01*
X1847727Y6610D01*
X1848310Y9110D01*
G01X1850160Y6610D02*
Y9110D01*
X1849660Y8610D01*
G01Y6610D02*
X1850660D01*
G01X1852343Y6985D02*
X1852593Y6777D01*
X1852885Y6652D01*
X1853260Y6610D01*
X1853635Y6693D01*
X1853927Y6860D01*
X1854135Y7152D01*
X1854177Y7485D01*
X1854093Y7818D01*
X1853885Y8027D01*
X1853593Y8193D01*
X1853302Y8235D01*
X1853010Y8193D01*
X1852635Y8027D01*
X1852760Y9110D01*
X1853885D01*
G01X1856860Y6610D02*
Y9110D01*
X1855318Y7318D01*
X1857402D01*
G01X1841810Y-15250D02*
X1841768Y-15583D01*
X1841602Y-15875D01*
X1841352Y-16125D01*
X1841060Y-16292D01*
X1840727Y-16375D01*
X1840393D01*
X1840060Y-16292D01*
X1839768Y-16125D01*
X1839518Y-15875D01*
X1839352Y-15583D01*
X1839310Y-15250D01*
X1839352Y-14917D01*
X1839518Y-14625D01*
X1839768Y-14375D01*
X1840060Y-14208D01*
X1840393Y-14125D01*
X1840727D01*
X1841060Y-14208D01*
X1841352Y-14375D01*
X1841602Y-14625D01*
X1841768Y-14917D01*
X1841810Y-15250D01*
G01X1841143Y-14917D02*
X1841810Y-14417D01*
G01X1841518Y-12858D02*
X1841727Y-12567D01*
X1841810Y-12233D01*
X1841727Y-11900D01*
X1841477Y-11608D01*
X1841102Y-11400D01*
X1840727Y-11317D01*
X1840268D01*
X1839893Y-11400D01*
X1839560Y-11608D01*
X1839393Y-11858D01*
X1839310Y-12150D01*
X1839393Y-12483D01*
X1839560Y-12733D01*
X1839810Y-12900D01*
X1840143Y-12983D01*
X1840435Y-12900D01*
X1840727Y-12692D01*
X1840893Y-12442D01*
X1840935Y-12150D01*
X1840852Y-11817D01*
X1840643Y-11567D01*
X1840268Y-11317D01*
G01X1840560Y-8800D02*
Y-7967D01*
X1841310D01*
X1841560Y-8217D01*
X1841727Y-8508D01*
X1841810Y-8925D01*
X1841727Y-9342D01*
X1841560Y-9633D01*
X1841310Y-9883D01*
X1841018Y-10050D01*
X1840685Y-10133D01*
X1840393D01*
X1840143Y-10050D01*
X1839852Y-9883D01*
X1839602Y-9633D01*
X1839435Y-9383D01*
X1839310Y-9050D01*
Y-8758D01*
X1839393Y-8425D01*
X1839560Y-8175D01*
G01X1841810Y-5950D02*
X1839310D01*
X1839810Y-6450D01*
G01X1841810D02*
Y-5450D01*
G01X1886334Y-10700D02*
X1888834D01*
G01X1886334Y-11658D02*
Y-9742D01*
G01X1888834Y-8475D02*
X1886334D01*
G01Y-6725D02*
X1888834D01*
G01X1887584D02*
Y-8475D01*
G01X1888542Y-5208D02*
X1888751Y-4917D01*
X1888834Y-4583D01*
X1888751Y-4250D01*
X1888501Y-3958D01*
X1888126Y-3750D01*
X1887751Y-3667D01*
X1887292D01*
X1886917Y-3750D01*
X1886584Y-3958D01*
X1886417Y-4208D01*
X1886334Y-4500D01*
X1886417Y-4833D01*
X1886584Y-5083D01*
X1886834Y-5250D01*
X1887167Y-5333D01*
X1887459Y-5250D01*
X1887751Y-5042D01*
X1887917Y-4792D01*
X1887959Y-4500D01*
X1887876Y-4167D01*
X1887667Y-3917D01*
X1887292Y-3667D01*
G01X1887584Y-1150D02*
Y-317D01*
X1888334D01*
X1888584Y-567D01*
X1888751Y-858D01*
X1888834Y-1275D01*
X1888751Y-1692D01*
X1888584Y-1983D01*
X1888334Y-2233D01*
X1888042Y-2400D01*
X1887709Y-2483D01*
X1887417D01*
X1887167Y-2400D01*
X1886876Y-2233D01*
X1886626Y-1983D01*
X1886459Y-1733D01*
X1886334Y-1400D01*
Y-1108D01*
X1886417Y-775D01*
X1886584Y-525D01*
G01X1888834Y1700D02*
X1886334D01*
X1886834Y1200D01*
G01X1888834D02*
Y2200D01*
G01X1878594Y8115D02*
X1878824Y8425D01*
X1879092Y8580D01*
X1879399Y8632D01*
X1879782Y8529D01*
X1880050Y8270D01*
X1880127Y7960D01*
X1880089Y7650D01*
X1879935Y7392D01*
X1879169Y6875D01*
X1878824Y6514D01*
X1878594Y5997D01*
X1878517Y5532D01*
X1880127D01*
G01X1889956Y27745D02*
X1890206Y27953D01*
X1890373Y28203D01*
X1890456Y28495D01*
X1890373Y28828D01*
X1890206Y29078D01*
X1889956Y29328D01*
X1889623Y29411D01*
X1887956D01*
G01X1890456Y30636D02*
X1887956Y31678D01*
X1890456Y32720D01*
G01X1889581Y32345D02*
Y31011D01*
G01X1890164Y34070D02*
X1890373Y34361D01*
X1890456Y34695D01*
X1890373Y35028D01*
X1890123Y35320D01*
X1889748Y35528D01*
X1889373Y35611D01*
X1888914D01*
X1888539Y35528D01*
X1888206Y35320D01*
X1888039Y35070D01*
X1887956Y34778D01*
X1888039Y34445D01*
X1888206Y34195D01*
X1888456Y34028D01*
X1888789Y33945D01*
X1889081Y34028D01*
X1889373Y34236D01*
X1889539Y34486D01*
X1889581Y34778D01*
X1889498Y35111D01*
X1889289Y35361D01*
X1888914Y35611D01*
G01X1889206Y38128D02*
Y38961D01*
X1889956D01*
X1890206Y38711D01*
X1890373Y38420D01*
X1890456Y38003D01*
X1890373Y37586D01*
X1890206Y37295D01*
X1889956Y37045D01*
X1889664Y36878D01*
X1889331Y36795D01*
X1889039D01*
X1888789Y36878D01*
X1888498Y37045D01*
X1888248Y37295D01*
X1888081Y37545D01*
X1887956Y37878D01*
Y38170D01*
X1888039Y38503D01*
X1888206Y38753D01*
G01X1890456Y40978D02*
X1887956D01*
X1888456Y40478D01*
G01X1890456D02*
Y41478D01*
G01X1976339Y-12796D02*
X1962406D01*
Y-18696D01*
X1943106D01*
Y-11846D01*
X1918756D01*
Y-14796D01*
X1904656D01*
Y-12796D01*
X1892356D01*
Y56104D01*
X1904656D01*
Y58104D01*
X1918756D01*
Y55154D01*
X1943106D01*
Y62004D01*
X1962406D01*
Y56104D01*
X1976339D01*
Y55119D01*
X1906851D01*
G03X1904882Y53150I0J-1969D01*
G01Y-9842D01*
G03X1906851Y-11811I1969J0D01*
G01X1976339D01*
Y-12796D01*
G01X1866781Y64685D02*
Y67185D01*
X1867822D01*
X1868156Y67060D01*
X1868364Y66893D01*
X1868447Y66560D01*
X1868364Y66227D01*
X1868114Y66018D01*
X1867822Y65893D01*
X1866781D01*
G01X1867822D02*
X1868447Y64685D01*
G01X1870006Y64977D02*
X1870297Y64768D01*
X1870631Y64685D01*
X1870964Y64768D01*
X1871256Y65018D01*
X1871464Y65393D01*
X1871547Y65768D01*
Y66227D01*
X1871464Y66602D01*
X1871256Y66935D01*
X1871006Y67102D01*
X1870714Y67185D01*
X1870381Y67102D01*
X1870131Y66935D01*
X1869964Y66685D01*
X1869881Y66352D01*
X1869964Y66060D01*
X1870172Y65768D01*
X1870422Y65602D01*
X1870714Y65560D01*
X1871047Y65643D01*
X1871297Y65852D01*
X1871547Y66227D01*
G01X1874064Y65935D02*
X1874897D01*
Y65185D01*
X1874647Y64935D01*
X1874356Y64768D01*
X1873939Y64685D01*
X1873522Y64768D01*
X1873231Y64935D01*
X1872981Y65185D01*
X1872814Y65477D01*
X1872731Y65810D01*
Y66102D01*
X1872814Y66352D01*
X1872981Y66643D01*
X1873231Y66893D01*
X1873481Y67060D01*
X1873814Y67185D01*
X1874106D01*
X1874439Y67102D01*
X1874689Y66935D01*
G01X1876914Y64685D02*
Y67185D01*
X1876414Y66685D01*
G01Y64685D02*
X1877414D01*
G01X1879306Y64977D02*
X1879597Y64768D01*
X1879931Y64685D01*
X1880264Y64768D01*
X1880556Y65018D01*
X1880764Y65393D01*
X1880847Y65768D01*
Y66227D01*
X1880764Y66602D01*
X1880556Y66935D01*
X1880306Y67102D01*
X1880014Y67185D01*
X1879681Y67102D01*
X1879431Y66935D01*
X1879264Y66685D01*
X1879181Y66352D01*
X1879264Y66060D01*
X1879472Y65768D01*
X1879722Y65602D01*
X1880014Y65560D01*
X1880347Y65643D01*
X1880597Y65852D01*
X1880847Y66227D01*
G01X1866981Y68185D02*
Y70685D01*
X1868022D01*
X1868356Y70560D01*
X1868564Y70393D01*
X1868647Y70060D01*
X1868564Y69727D01*
X1868314Y69518D01*
X1868022Y69393D01*
X1866981D01*
G01X1868022D02*
X1868647Y68185D01*
G01X1870206Y68477D02*
X1870497Y68268D01*
X1870831Y68185D01*
X1871164Y68268D01*
X1871456Y68518D01*
X1871664Y68893D01*
X1871747Y69268D01*
Y69727D01*
X1871664Y70102D01*
X1871456Y70435D01*
X1871206Y70602D01*
X1870914Y70685D01*
X1870581Y70602D01*
X1870331Y70435D01*
X1870164Y70185D01*
X1870081Y69852D01*
X1870164Y69560D01*
X1870372Y69268D01*
X1870622Y69102D01*
X1870914Y69060D01*
X1871247Y69143D01*
X1871497Y69352D01*
X1871747Y69727D01*
G01X1874264Y69435D02*
X1875097D01*
Y68685D01*
X1874847Y68435D01*
X1874556Y68268D01*
X1874139Y68185D01*
X1873722Y68268D01*
X1873431Y68435D01*
X1873181Y68685D01*
X1873014Y68977D01*
X1872931Y69310D01*
Y69602D01*
X1873014Y69852D01*
X1873181Y70143D01*
X1873431Y70393D01*
X1873681Y70560D01*
X1874014Y70685D01*
X1874306D01*
X1874639Y70602D01*
X1874889Y70435D01*
G01X1876322Y70268D02*
X1876572Y70518D01*
X1876864Y70643D01*
X1877197Y70685D01*
X1877614Y70602D01*
X1877906Y70393D01*
X1877989Y70143D01*
X1877947Y69893D01*
X1877781Y69685D01*
X1876947Y69268D01*
X1876572Y68977D01*
X1876322Y68560D01*
X1876239Y68185D01*
X1877989D01*
G01X1880214Y70685D02*
X1879881Y70602D01*
X1879631Y70393D01*
X1879464Y70143D01*
X1879339Y69810D01*
X1879297Y69435D01*
X1879339Y69060D01*
X1879464Y68727D01*
X1879631Y68477D01*
X1879881Y68268D01*
X1880214Y68185D01*
X1880547Y68268D01*
X1880797Y68477D01*
X1880964Y68727D01*
X1881089Y69060D01*
X1881131Y69435D01*
X1881089Y69810D01*
X1880964Y70143D01*
X1880797Y70393D01*
X1880547Y70602D01*
X1880214Y70685D01*
G01X1873531Y41952D02*
X1871031D01*
Y42993D01*
X1871156Y43327D01*
X1871323Y43535D01*
X1871656Y43618D01*
X1871989Y43535D01*
X1872198Y43285D01*
X1872323Y42993D01*
Y41952D01*
G01Y42993D02*
X1873531Y43618D01*
G01X1873239Y45177D02*
X1873448Y45468D01*
X1873531Y45802D01*
X1873448Y46135D01*
X1873198Y46427D01*
X1872823Y46635D01*
X1872448Y46718D01*
X1871989D01*
X1871614Y46635D01*
X1871281Y46427D01*
X1871114Y46177D01*
X1871031Y45885D01*
X1871114Y45552D01*
X1871281Y45302D01*
X1871531Y45135D01*
X1871864Y45052D01*
X1872156Y45135D01*
X1872448Y45343D01*
X1872614Y45593D01*
X1872656Y45885D01*
X1872573Y46218D01*
X1872364Y46468D01*
X1871989Y46718D01*
G01X1872281Y49235D02*
Y50068D01*
X1873031D01*
X1873281Y49818D01*
X1873448Y49527D01*
X1873531Y49110D01*
X1873448Y48693D01*
X1873281Y48402D01*
X1873031Y48152D01*
X1872739Y47985D01*
X1872406Y47902D01*
X1872114D01*
X1871864Y47985D01*
X1871573Y48152D01*
X1871323Y48402D01*
X1871156Y48652D01*
X1871031Y48985D01*
Y49277D01*
X1871114Y49610D01*
X1871281Y49860D01*
G01X1871448Y51293D02*
X1871198Y51543D01*
X1871073Y51835D01*
X1871031Y52168D01*
X1871114Y52585D01*
X1871323Y52877D01*
X1871573Y52960D01*
X1871823Y52918D01*
X1872031Y52752D01*
X1872448Y51918D01*
X1872739Y51543D01*
X1873156Y51293D01*
X1873531Y51210D01*
Y52960D01*
G01Y55685D02*
X1871031D01*
X1872823Y54143D01*
Y56227D01*
G01X1870049Y46430D02*
X1867549D01*
Y47471D01*
X1867674Y47805D01*
X1867841Y48013D01*
X1868174Y48096D01*
X1868507Y48013D01*
X1868716Y47763D01*
X1868841Y47471D01*
Y46430D01*
G01Y47471D02*
X1870049Y48096D01*
G01X1869757Y49655D02*
X1869966Y49946D01*
X1870049Y50280D01*
X1869966Y50613D01*
X1869716Y50905D01*
X1869341Y51113D01*
X1868966Y51196D01*
X1868507D01*
X1868132Y51113D01*
X1867799Y50905D01*
X1867632Y50655D01*
X1867549Y50363D01*
X1867632Y50030D01*
X1867799Y49780D01*
X1868049Y49613D01*
X1868382Y49530D01*
X1868674Y49613D01*
X1868966Y49821D01*
X1869132Y50071D01*
X1869174Y50363D01*
X1869091Y50696D01*
X1868882Y50946D01*
X1868507Y51196D01*
G01X1868799Y53713D02*
Y54546D01*
X1869549D01*
X1869799Y54296D01*
X1869966Y54005D01*
X1870049Y53588D01*
X1869966Y53171D01*
X1869799Y52880D01*
X1869549Y52630D01*
X1869257Y52463D01*
X1868924Y52380D01*
X1868632D01*
X1868382Y52463D01*
X1868091Y52630D01*
X1867841Y52880D01*
X1867674Y53130D01*
X1867549Y53463D01*
Y53755D01*
X1867632Y54088D01*
X1867799Y54338D01*
G01X1867966Y55771D02*
X1867716Y56021D01*
X1867591Y56313D01*
X1867549Y56646D01*
X1867632Y57063D01*
X1867841Y57355D01*
X1868091Y57438D01*
X1868341Y57396D01*
X1868549Y57230D01*
X1868966Y56396D01*
X1869257Y56021D01*
X1869674Y55771D01*
X1870049Y55688D01*
Y57438D01*
G01X1867966Y58871D02*
X1867716Y59121D01*
X1867591Y59413D01*
X1867549Y59746D01*
X1867632Y60163D01*
X1867841Y60455D01*
X1868091Y60538D01*
X1868341Y60496D01*
X1868549Y60330D01*
X1868966Y59496D01*
X1869257Y59121D01*
X1869674Y58871D01*
X1870049Y58788D01*
Y60538D01*
G01X1894664Y62296D02*
X1894539Y62046D01*
X1894456Y61754D01*
Y61421D01*
X1894581Y61046D01*
X1894789Y60754D01*
X1895039Y60546D01*
X1895456Y60379D01*
X1895831Y60337D01*
X1896206Y60421D01*
X1896456Y60546D01*
X1896706Y60796D01*
X1896873Y61087D01*
X1896956Y61379D01*
Y61671D01*
X1896873Y61962D01*
X1896748Y62212D01*
X1896581Y62421D01*
G01X1896664Y63771D02*
X1896873Y64062D01*
X1896956Y64396D01*
X1896873Y64729D01*
X1896623Y65021D01*
X1896248Y65229D01*
X1895873Y65312D01*
X1895414D01*
X1895039Y65229D01*
X1894706Y65021D01*
X1894539Y64771D01*
X1894456Y64479D01*
X1894539Y64146D01*
X1894706Y63896D01*
X1894956Y63729D01*
X1895289Y63646D01*
X1895581Y63729D01*
X1895873Y63937D01*
X1896039Y64187D01*
X1896081Y64479D01*
X1895998Y64812D01*
X1895789Y65062D01*
X1895414Y65312D01*
G01X1895706Y67829D02*
Y68662D01*
X1896456D01*
X1896706Y68412D01*
X1896873Y68121D01*
X1896956Y67704D01*
X1896873Y67287D01*
X1896706Y66996D01*
X1896456Y66746D01*
X1896164Y66579D01*
X1895831Y66496D01*
X1895539D01*
X1895289Y66579D01*
X1894998Y66746D01*
X1894748Y66996D01*
X1894581Y67246D01*
X1894456Y67579D01*
Y67871D01*
X1894539Y68204D01*
X1894706Y68454D01*
G01X1896956Y71179D02*
X1894456D01*
X1896248Y69637D01*
Y71721D01*
G01X1845537Y86616D02*
X1846384D01*
G01Y87463D02*
Y86616D01*
G01Y94037D02*
Y94884D01*
G01X1838116Y94037D02*
Y94884D01*
G01X1838963Y86616D02*
X1838116D01*
G01Y87463D02*
Y86616D01*
G01X1853413Y83432D02*
Y99540D01*
X1867587D01*
Y83432D01*
G01X1892950Y80608D02*
Y85054D01*
G01X1885850Y80611D02*
Y85056D01*
G01X1850477Y76847D02*
Y74347D01*
X1852143D01*
G01X1854410D02*
X1854702Y74389D01*
X1855035Y74514D01*
X1855243Y74722D01*
X1855327Y75014D01*
X1855243Y75305D01*
X1854993Y75555D01*
X1854618Y75680D01*
X1854202D01*
X1853952Y75764D01*
X1853743Y75972D01*
X1853660Y76264D01*
X1853785Y76555D01*
X1854077Y76764D01*
X1854410Y76847D01*
X1854743Y76764D01*
X1855035Y76555D01*
X1855160Y76264D01*
X1855077Y75972D01*
X1854868Y75764D01*
X1854618Y75680D01*
X1854202D01*
X1853827Y75555D01*
X1853577Y75305D01*
X1853493Y75014D01*
X1853577Y74722D01*
X1853785Y74514D01*
X1854118Y74389D01*
X1854410Y74347D01*
G01X1856718D02*
Y76847D01*
X1858302D01*
G01X1857718Y75639D02*
X1856718D01*
G01X1860610Y74347D02*
Y76847D01*
X1860110Y76347D01*
G01Y74347D02*
X1861110D01*
G01X1886356Y91662D02*
Y101662D01*
X1903956D01*
Y91662D01*
X1886356D01*
G01X1893500Y145699D02*
X1898700D01*
G01X1870218Y150330D02*
X1885870D01*
Y145699D01*
X1889000D01*
G01X1864230Y142426D02*
Y150330D01*
X1865950D01*
G01X1853300Y125267D02*
X1850800D01*
Y126308D01*
X1850925Y126642D01*
X1851092Y126850D01*
X1851425Y126933D01*
X1851758Y126850D01*
X1851967Y126600D01*
X1852092Y126308D01*
Y125267D01*
G01Y126308D02*
X1853300Y126933D01*
G01X1853008Y128492D02*
X1853217Y128783D01*
X1853300Y129117D01*
X1853217Y129450D01*
X1852967Y129742D01*
X1852592Y129950D01*
X1852217Y130033D01*
X1851758D01*
X1851383Y129950D01*
X1851050Y129742D01*
X1850883Y129492D01*
X1850800Y129200D01*
X1850883Y128867D01*
X1851050Y128617D01*
X1851300Y128450D01*
X1851633Y128367D01*
X1851925Y128450D01*
X1852217Y128658D01*
X1852383Y128908D01*
X1852425Y129200D01*
X1852342Y129533D01*
X1852133Y129783D01*
X1851758Y130033D01*
G01X1853300Y131508D02*
X1850800D01*
Y133092D01*
G01X1852008Y132508D02*
Y131508D01*
G01X1852800Y134483D02*
X1853092Y134733D01*
X1853258Y135067D01*
X1853300Y135442D01*
X1853258Y135775D01*
X1853050Y136108D01*
X1852800Y136317D01*
X1852550Y136358D01*
X1852258Y136275D01*
X1852050Y135983D01*
X1851967Y135692D01*
Y135317D01*
G01Y135692D02*
X1851842Y135942D01*
X1851633Y136150D01*
X1851383Y136233D01*
X1851133Y136150D01*
X1850925Y135942D01*
X1850800Y135567D01*
X1850842Y135192D01*
X1851008Y134817D01*
G01X1851217Y137708D02*
X1850967Y137958D01*
X1850842Y138250D01*
X1850800Y138583D01*
X1850883Y139000D01*
X1851092Y139292D01*
X1851342Y139375D01*
X1851592Y139333D01*
X1851800Y139167D01*
X1852217Y138333D01*
X1852508Y137958D01*
X1852925Y137708D01*
X1853300Y137625D01*
Y139375D01*
G01X1858108Y151717D02*
X1857983Y151467D01*
X1857900Y151175D01*
Y150842D01*
X1858025Y150467D01*
X1858233Y150175D01*
X1858483Y149967D01*
X1858900Y149800D01*
X1859275Y149758D01*
X1859650Y149842D01*
X1859900Y149967D01*
X1860150Y150217D01*
X1860317Y150508D01*
X1860400Y150800D01*
Y151092D01*
X1860317Y151383D01*
X1860192Y151633D01*
X1860025Y151842D01*
G01X1860108Y153192D02*
X1860317Y153483D01*
X1860400Y153817D01*
X1860317Y154150D01*
X1860067Y154442D01*
X1859692Y154650D01*
X1859317Y154733D01*
X1858858D01*
X1858483Y154650D01*
X1858150Y154442D01*
X1857983Y154192D01*
X1857900Y153900D01*
X1857983Y153567D01*
X1858150Y153317D01*
X1858400Y153150D01*
X1858733Y153067D01*
X1859025Y153150D01*
X1859317Y153358D01*
X1859483Y153608D01*
X1859525Y153900D01*
X1859442Y154233D01*
X1859233Y154483D01*
X1858858Y154733D01*
G01X1860400Y156208D02*
X1857900D01*
Y157792D01*
G01X1859108Y157208D02*
Y156208D01*
G01X1860400Y160100D02*
X1857900D01*
X1858400Y159600D01*
G01X1860400D02*
Y160600D01*
G01X1857900Y163200D02*
X1857983Y162867D01*
X1858192Y162617D01*
X1858442Y162450D01*
X1858775Y162325D01*
X1859150Y162283D01*
X1859525Y162325D01*
X1859858Y162450D01*
X1860108Y162617D01*
X1860317Y162867D01*
X1860400Y163200D01*
X1860317Y163533D01*
X1860108Y163783D01*
X1859858Y163950D01*
X1859525Y164075D01*
X1859150Y164117D01*
X1858775Y164075D01*
X1858442Y163950D01*
X1858192Y163783D01*
X1857983Y163533D01*
X1857900Y163200D01*
G01X1845537Y94884D02*
X1846384D01*
G01X1838963D02*
X1838116D01*
G01X1849800Y124767D02*
X1847300D01*
Y125808D01*
X1847425Y126142D01*
X1847592Y126350D01*
X1847925Y126433D01*
X1848258Y126350D01*
X1848467Y126100D01*
X1848592Y125808D01*
Y124767D01*
G01Y125808D02*
X1849800Y126433D01*
G01X1849508Y127992D02*
X1849717Y128283D01*
X1849800Y128617D01*
X1849717Y128950D01*
X1849467Y129242D01*
X1849092Y129450D01*
X1848717Y129533D01*
X1848258D01*
X1847883Y129450D01*
X1847550Y129242D01*
X1847383Y128992D01*
X1847300Y128700D01*
X1847383Y128367D01*
X1847550Y128117D01*
X1847800Y127950D01*
X1848133Y127867D01*
X1848425Y127950D01*
X1848717Y128158D01*
X1848883Y128408D01*
X1848925Y128700D01*
X1848842Y129033D01*
X1848633Y129283D01*
X1848258Y129533D01*
G01X1849800Y131008D02*
X1847300D01*
Y132592D01*
G01X1848508Y132008D02*
Y131008D01*
G01X1849300Y133983D02*
X1849592Y134233D01*
X1849758Y134567D01*
X1849800Y134942D01*
X1849758Y135275D01*
X1849550Y135608D01*
X1849300Y135817D01*
X1849050Y135858D01*
X1848758Y135775D01*
X1848550Y135483D01*
X1848467Y135192D01*
Y134817D01*
G01Y135192D02*
X1848342Y135442D01*
X1848133Y135650D01*
X1847883Y135733D01*
X1847633Y135650D01*
X1847425Y135442D01*
X1847300Y135067D01*
X1847342Y134692D01*
X1847508Y134317D01*
G01X1849800Y138000D02*
X1847300D01*
X1847800Y137500D01*
G01X1849800D02*
Y138500D01*
G01X1853663Y140248D02*
X1857663D01*
Y147648D01*
G01X1886800Y153400D02*
Y192800D01*
X1926200D01*
Y153400D01*
X1886800D01*
G01X1889834Y155385D02*
X1888785D01*
Y156436D01*
G01X1865980Y137000D02*
Y106000D01*
X1897030D01*
Y137000D01*
X1865980D01*
G01X1840727Y154348D02*
Y152682D01*
X1838227D01*
Y154348D01*
G01X1839435Y153682D02*
Y152682D01*
G01X1838227Y155698D02*
X1840019D01*
X1840394Y155865D01*
X1840644Y156198D01*
X1840727Y156615D01*
X1840644Y157032D01*
X1840394Y157365D01*
X1840019Y157532D01*
X1838227D01*
G01X1840435Y159007D02*
X1840644Y159298D01*
X1840727Y159632D01*
X1840644Y159965D01*
X1840394Y160257D01*
X1840019Y160465D01*
X1839644Y160548D01*
X1839185D01*
X1838810Y160465D01*
X1838477Y160257D01*
X1838310Y160007D01*
X1838227Y159715D01*
X1838310Y159382D01*
X1838477Y159132D01*
X1838727Y158965D01*
X1839060Y158882D01*
X1839352Y158965D01*
X1839644Y159173D01*
X1839810Y159423D01*
X1839852Y159715D01*
X1839769Y160048D01*
X1839560Y160298D01*
X1839185Y160548D01*
G01X1840727Y162023D02*
X1838227D01*
Y163607D01*
G01X1839435Y163023D02*
Y162023D01*
G01X1838644Y165123D02*
X1838394Y165373D01*
X1838269Y165665D01*
X1838227Y165998D01*
X1838310Y166415D01*
X1838519Y166707D01*
X1838769Y166790D01*
X1839019Y166748D01*
X1839227Y166582D01*
X1839644Y165748D01*
X1839935Y165373D01*
X1840352Y165123D01*
X1840727Y165040D01*
Y166790D01*
G01X1912783Y224082D02*
Y224608D01*
X1900020D01*
Y227503D01*
X1894033D01*
Y229608D01*
X1875349D01*
Y223950D01*
X1862816D01*
Y209740D01*
X1879658D01*
Y206566D01*
X1899049D01*
G01X1884178Y212417D02*
X1881678D01*
Y213458D01*
X1881803Y213792D01*
X1881970Y214000D01*
X1882303Y214083D01*
X1882636Y214000D01*
X1882845Y213750D01*
X1882970Y213458D01*
Y212417D01*
G01Y213458D02*
X1884178Y214083D01*
G01X1883886Y215642D02*
X1884095Y215933D01*
X1884178Y216267D01*
X1884095Y216600D01*
X1883845Y216892D01*
X1883470Y217100D01*
X1883095Y217183D01*
X1882636D01*
X1882261Y217100D01*
X1881928Y216892D01*
X1881761Y216642D01*
X1881678Y216350D01*
X1881761Y216017D01*
X1881928Y215767D01*
X1882178Y215600D01*
X1882511Y215517D01*
X1882803Y215600D01*
X1883095Y215808D01*
X1883261Y216058D01*
X1883303Y216350D01*
X1883220Y216683D01*
X1883011Y216933D01*
X1882636Y217183D01*
G01X1884178Y220283D02*
Y218617D01*
X1881678D01*
Y220283D01*
G01X1882886Y219617D02*
Y218617D01*
G01X1884178Y223050D02*
X1881678D01*
X1883470Y221508D01*
Y223592D01*
G01X1880050Y212264D02*
X1877550D01*
Y213305D01*
X1877675Y213639D01*
X1877842Y213847D01*
X1878175Y213930D01*
X1878508Y213847D01*
X1878717Y213597D01*
X1878842Y213305D01*
Y212264D01*
G01Y213305D02*
X1880050Y213930D01*
G01X1879758Y215489D02*
X1879967Y215780D01*
X1880050Y216114D01*
X1879967Y216447D01*
X1879717Y216739D01*
X1879342Y216947D01*
X1878967Y217030D01*
X1878508D01*
X1878133Y216947D01*
X1877800Y216739D01*
X1877633Y216489D01*
X1877550Y216197D01*
X1877633Y215864D01*
X1877800Y215614D01*
X1878050Y215447D01*
X1878383Y215364D01*
X1878675Y215447D01*
X1878967Y215655D01*
X1879133Y215905D01*
X1879175Y216197D01*
X1879092Y216530D01*
X1878883Y216780D01*
X1878508Y217030D01*
G01X1880050Y220130D02*
Y218464D01*
X1877550D01*
Y220130D01*
G01X1878758Y219464D02*
Y218464D01*
G01X1879550Y221480D02*
X1879842Y221730D01*
X1880008Y222064D01*
X1880050Y222439D01*
X1880008Y222772D01*
X1879800Y223105D01*
X1879550Y223314D01*
X1879300Y223355D01*
X1879008Y223272D01*
X1878800Y222980D01*
X1878717Y222689D01*
Y222314D01*
G01Y222689D02*
X1878592Y222939D01*
X1878383Y223147D01*
X1878133Y223230D01*
X1877883Y223147D01*
X1877675Y222939D01*
X1877550Y222564D01*
X1877592Y222189D01*
X1877758Y221814D01*
G01X1875587Y211397D02*
X1873087D01*
Y212438D01*
X1873212Y212772D01*
X1873379Y212980D01*
X1873712Y213063D01*
X1874045Y212980D01*
X1874254Y212730D01*
X1874379Y212438D01*
Y211397D01*
G01Y212438D02*
X1875587Y213063D01*
G01X1875295Y214622D02*
X1875504Y214913D01*
X1875587Y215247D01*
X1875504Y215580D01*
X1875254Y215872D01*
X1874879Y216080D01*
X1874504Y216163D01*
X1874045D01*
X1873670Y216080D01*
X1873337Y215872D01*
X1873170Y215622D01*
X1873087Y215330D01*
X1873170Y214997D01*
X1873337Y214747D01*
X1873587Y214580D01*
X1873920Y214497D01*
X1874212Y214580D01*
X1874504Y214788D01*
X1874670Y215038D01*
X1874712Y215330D01*
X1874629Y215663D01*
X1874420Y215913D01*
X1874045Y216163D01*
G01X1875587Y219263D02*
Y217597D01*
X1873087D01*
Y219263D01*
G01X1874295Y218597D02*
Y217597D01*
G01X1873504Y220738D02*
X1873254Y220988D01*
X1873129Y221280D01*
X1873087Y221613D01*
X1873170Y222030D01*
X1873379Y222322D01*
X1873629Y222405D01*
X1873879Y222363D01*
X1874087Y222197D01*
X1874504Y221363D01*
X1874795Y220988D01*
X1875212Y220738D01*
X1875587Y220655D01*
Y222405D01*
G01X1886079Y212238D02*
Y214738D01*
X1887120D01*
X1887454Y214613D01*
X1887662Y214446D01*
X1887745Y214113D01*
X1887662Y213780D01*
X1887412Y213571D01*
X1887120Y213446D01*
X1886079D01*
G01X1887120D02*
X1887745Y212238D01*
G01X1889304Y212530D02*
X1889595Y212321D01*
X1889929Y212238D01*
X1890262Y212321D01*
X1890554Y212571D01*
X1890762Y212946D01*
X1890845Y213321D01*
Y213780D01*
X1890762Y214155D01*
X1890554Y214488D01*
X1890304Y214655D01*
X1890012Y214738D01*
X1889679Y214655D01*
X1889429Y214488D01*
X1889262Y214238D01*
X1889179Y213905D01*
X1889262Y213613D01*
X1889470Y213321D01*
X1889720Y213155D01*
X1890012Y213113D01*
X1890345Y213196D01*
X1890595Y213405D01*
X1890845Y213780D01*
G01X1893945Y212238D02*
X1892279D01*
Y214738D01*
X1893945D01*
G01X1893279Y213530D02*
X1892279D01*
G01X1895504Y212530D02*
X1895795Y212321D01*
X1896129Y212238D01*
X1896462Y212321D01*
X1896754Y212571D01*
X1896962Y212946D01*
X1897045Y213321D01*
Y213780D01*
X1896962Y214155D01*
X1896754Y214488D01*
X1896504Y214655D01*
X1896212Y214738D01*
X1895879Y214655D01*
X1895629Y214488D01*
X1895462Y214238D01*
X1895379Y213905D01*
X1895462Y213613D01*
X1895670Y213321D01*
X1895920Y213155D01*
X1896212Y213113D01*
X1896545Y213196D01*
X1896795Y213405D01*
X1897045Y213780D01*
G01X1886142Y215565D02*
Y218065D01*
X1887183D01*
X1887517Y217940D01*
X1887725Y217773D01*
X1887808Y217440D01*
X1887725Y217107D01*
X1887475Y216898D01*
X1887183Y216773D01*
X1886142D01*
G01X1887183D02*
X1887808Y215565D01*
G01X1889367Y215857D02*
X1889658Y215648D01*
X1889992Y215565D01*
X1890325Y215648D01*
X1890617Y215898D01*
X1890825Y216273D01*
X1890908Y216648D01*
Y217107D01*
X1890825Y217482D01*
X1890617Y217815D01*
X1890367Y217982D01*
X1890075Y218065D01*
X1889742Y217982D01*
X1889492Y217815D01*
X1889325Y217565D01*
X1889242Y217232D01*
X1889325Y216940D01*
X1889533Y216648D01*
X1889783Y216482D01*
X1890075Y216440D01*
X1890408Y216523D01*
X1890658Y216732D01*
X1890908Y217107D01*
G01X1894008Y215565D02*
X1892342D01*
Y218065D01*
X1894008D01*
G01X1893342Y216857D02*
X1892342D01*
G01X1896275Y215565D02*
X1896567Y215607D01*
X1896900Y215732D01*
X1897108Y215940D01*
X1897192Y216232D01*
X1897108Y216523D01*
X1896858Y216773D01*
X1896483Y216898D01*
X1896067D01*
X1895817Y216982D01*
X1895608Y217190D01*
X1895525Y217482D01*
X1895650Y217773D01*
X1895942Y217982D01*
X1896275Y218065D01*
X1896608Y217982D01*
X1896900Y217773D01*
X1897025Y217482D01*
X1896942Y217190D01*
X1896733Y216982D01*
X1896483Y216898D01*
X1896067D01*
X1895692Y216773D01*
X1895442Y216523D01*
X1895358Y216232D01*
X1895442Y215940D01*
X1895650Y215732D01*
X1895983Y215607D01*
X1896275Y215565D01*
G01X1870357Y199703D02*
Y202203D01*
X1871398D01*
X1871732Y202078D01*
X1871940Y201911D01*
X1872023Y201578D01*
X1871940Y201245D01*
X1871690Y201036D01*
X1871398Y200911D01*
X1870357D01*
G01X1871398D02*
X1872023Y199703D01*
G01X1873582Y199995D02*
X1873873Y199786D01*
X1874207Y199703D01*
X1874540Y199786D01*
X1874832Y200036D01*
X1875040Y200411D01*
X1875123Y200786D01*
Y201245D01*
X1875040Y201620D01*
X1874832Y201953D01*
X1874582Y202120D01*
X1874290Y202203D01*
X1873957Y202120D01*
X1873707Y201953D01*
X1873540Y201703D01*
X1873457Y201370D01*
X1873540Y201078D01*
X1873748Y200786D01*
X1873998Y200620D01*
X1874290Y200578D01*
X1874623Y200661D01*
X1874873Y200870D01*
X1875123Y201245D01*
G01X1878223Y199703D02*
X1876557D01*
Y202203D01*
X1878223D01*
G01X1877557Y200995D02*
X1876557D01*
G01X1880407Y199703D02*
X1880490Y200245D01*
X1880615Y200703D01*
X1880782Y201120D01*
X1880990Y201578D01*
X1881323Y202203D01*
X1879657D01*
G01X1893748Y208988D02*
Y211488D01*
X1894789D01*
X1895123Y211363D01*
X1895331Y211196D01*
X1895414Y210863D01*
X1895331Y210530D01*
X1895081Y210321D01*
X1894789Y210196D01*
X1893748D01*
G01X1894789D02*
X1895414Y208988D01*
G01X1896973Y209280D02*
X1897264Y209071D01*
X1897598Y208988D01*
X1897931Y209071D01*
X1898223Y209321D01*
X1898431Y209696D01*
X1898514Y210071D01*
Y210530D01*
X1898431Y210905D01*
X1898223Y211238D01*
X1897973Y211405D01*
X1897681Y211488D01*
X1897348Y211405D01*
X1897098Y211238D01*
X1896931Y210988D01*
X1896848Y210655D01*
X1896931Y210363D01*
X1897139Y210071D01*
X1897389Y209905D01*
X1897681Y209863D01*
X1898014Y209946D01*
X1898264Y210155D01*
X1898514Y210530D01*
G01X1901614Y208988D02*
X1899948D01*
Y211488D01*
X1901614D01*
G01X1900948Y210280D02*
X1899948D01*
G01X1903089Y211071D02*
X1903339Y211321D01*
X1903631Y211446D01*
X1903964Y211488D01*
X1904381Y211405D01*
X1904673Y211196D01*
X1904756Y210946D01*
X1904714Y210696D01*
X1904548Y210488D01*
X1903714Y210071D01*
X1903339Y209780D01*
X1903089Y209363D01*
X1903006Y208988D01*
X1904756D01*
G01X1906189Y211071D02*
X1906439Y211321D01*
X1906731Y211446D01*
X1907064Y211488D01*
X1907481Y211405D01*
X1907773Y211196D01*
X1907856Y210946D01*
X1907814Y210696D01*
X1907648Y210488D01*
X1906814Y210071D01*
X1906439Y209780D01*
X1906189Y209363D01*
X1906106Y208988D01*
X1907856D01*
G01X1863467Y190667D02*
Y193167D01*
X1864508D01*
X1864842Y193042D01*
X1865050Y192875D01*
X1865133Y192542D01*
X1865050Y192209D01*
X1864800Y192000D01*
X1864508Y191875D01*
X1863467D01*
G01X1864508D02*
X1865133Y190667D01*
G01X1866692Y190959D02*
X1866983Y190750D01*
X1867317Y190667D01*
X1867650Y190750D01*
X1867942Y191000D01*
X1868150Y191375D01*
X1868233Y191750D01*
Y192209D01*
X1868150Y192584D01*
X1867942Y192917D01*
X1867692Y193084D01*
X1867400Y193167D01*
X1867067Y193084D01*
X1866817Y192917D01*
X1866650Y192667D01*
X1866567Y192334D01*
X1866650Y192042D01*
X1866858Y191750D01*
X1867108Y191584D01*
X1867400Y191542D01*
X1867733Y191625D01*
X1867983Y191834D01*
X1868233Y192209D01*
G01X1871333Y190667D02*
X1869667D01*
Y193167D01*
X1871333D01*
G01X1870667Y191959D02*
X1869667D01*
G01X1873600Y190667D02*
Y193167D01*
X1873100Y192667D01*
G01Y190667D02*
X1874100D01*
G01X1875908Y191709D02*
X1876200Y192000D01*
X1876450Y192167D01*
X1876783Y192250D01*
X1877075Y192167D01*
X1877283Y192000D01*
X1877450Y191750D01*
X1877492Y191459D01*
X1877450Y191209D01*
X1877283Y190959D01*
X1877033Y190750D01*
X1876742Y190667D01*
X1876408Y190750D01*
X1876117Y191000D01*
X1875950Y191375D01*
X1875908Y191792D01*
X1875992Y192334D01*
X1876117Y192625D01*
X1876325Y192917D01*
X1876617Y193125D01*
X1876908Y193167D01*
X1877200Y193084D01*
X1877408Y192875D01*
G01X1863467Y186767D02*
Y189267D01*
X1864508D01*
X1864842Y189142D01*
X1865050Y188975D01*
X1865133Y188642D01*
X1865050Y188309D01*
X1864800Y188100D01*
X1864508Y187975D01*
X1863467D01*
G01X1864508D02*
X1865133Y186767D01*
G01X1866692Y187059D02*
X1866983Y186850D01*
X1867317Y186767D01*
X1867650Y186850D01*
X1867942Y187100D01*
X1868150Y187475D01*
X1868233Y187850D01*
Y188309D01*
X1868150Y188684D01*
X1867942Y189017D01*
X1867692Y189184D01*
X1867400Y189267D01*
X1867067Y189184D01*
X1866817Y189017D01*
X1866650Y188767D01*
X1866567Y188434D01*
X1866650Y188142D01*
X1866858Y187850D01*
X1867108Y187684D01*
X1867400Y187642D01*
X1867733Y187725D01*
X1867983Y187934D01*
X1868233Y188309D01*
G01X1871333Y186767D02*
X1869667D01*
Y189267D01*
X1871333D01*
G01X1870667Y188059D02*
X1869667D01*
G01X1873600Y186767D02*
Y189267D01*
X1873100Y188767D01*
G01Y186767D02*
X1874100D01*
G01X1876700D02*
X1876992Y186809D01*
X1877325Y186934D01*
X1877533Y187142D01*
X1877617Y187434D01*
X1877533Y187725D01*
X1877283Y187975D01*
X1876908Y188100D01*
X1876492D01*
X1876242Y188184D01*
X1876033Y188392D01*
X1875950Y188684D01*
X1876075Y188975D01*
X1876367Y189184D01*
X1876700Y189267D01*
X1877033Y189184D01*
X1877325Y188975D01*
X1877450Y188684D01*
X1877367Y188392D01*
X1877158Y188184D01*
X1876908Y188100D01*
X1876492D01*
X1876117Y187975D01*
X1875867Y187725D01*
X1875783Y187434D01*
X1875867Y187142D01*
X1876075Y186934D01*
X1876408Y186809D01*
X1876700Y186767D01*
G01X1863512Y183016D02*
Y185516D01*
X1864553D01*
X1864887Y185391D01*
X1865095Y185224D01*
X1865178Y184891D01*
X1865095Y184558D01*
X1864845Y184349D01*
X1864553Y184224D01*
X1863512D01*
G01X1864553D02*
X1865178Y183016D01*
G01X1866737Y183308D02*
X1867028Y183099D01*
X1867362Y183016D01*
X1867695Y183099D01*
X1867987Y183349D01*
X1868195Y183724D01*
X1868278Y184099D01*
Y184558D01*
X1868195Y184933D01*
X1867987Y185266D01*
X1867737Y185433D01*
X1867445Y185516D01*
X1867112Y185433D01*
X1866862Y185266D01*
X1866695Y185016D01*
X1866612Y184683D01*
X1866695Y184391D01*
X1866903Y184099D01*
X1867153Y183933D01*
X1867445Y183891D01*
X1867778Y183974D01*
X1868028Y184183D01*
X1868278Y184558D01*
G01X1871378Y183016D02*
X1869712D01*
Y185516D01*
X1871378D01*
G01X1870712Y184308D02*
X1869712D01*
G01X1872853Y185099D02*
X1873103Y185349D01*
X1873395Y185474D01*
X1873728Y185516D01*
X1874145Y185433D01*
X1874437Y185224D01*
X1874520Y184974D01*
X1874478Y184724D01*
X1874312Y184516D01*
X1873478Y184099D01*
X1873103Y183808D01*
X1872853Y183391D01*
X1872770Y183016D01*
X1874520D01*
G01X1876745Y185516D02*
X1876412Y185433D01*
X1876162Y185224D01*
X1875995Y184974D01*
X1875870Y184641D01*
X1875828Y184266D01*
X1875870Y183891D01*
X1875995Y183558D01*
X1876162Y183308D01*
X1876412Y183099D01*
X1876745Y183016D01*
X1877078Y183099D01*
X1877328Y183308D01*
X1877495Y183558D01*
X1877620Y183891D01*
X1877662Y184266D01*
X1877620Y184641D01*
X1877495Y184974D01*
X1877328Y185224D01*
X1877078Y185433D01*
X1876745Y185516D01*
G01X1863362Y179136D02*
Y181636D01*
X1864403D01*
X1864737Y181511D01*
X1864945Y181344D01*
X1865028Y181011D01*
X1864945Y180678D01*
X1864695Y180469D01*
X1864403Y180344D01*
X1863362D01*
G01X1864403D02*
X1865028Y179136D01*
G01X1866587Y179428D02*
X1866878Y179219D01*
X1867212Y179136D01*
X1867545Y179219D01*
X1867837Y179469D01*
X1868045Y179844D01*
X1868128Y180219D01*
Y180678D01*
X1868045Y181053D01*
X1867837Y181386D01*
X1867587Y181553D01*
X1867295Y181636D01*
X1866962Y181553D01*
X1866712Y181386D01*
X1866545Y181136D01*
X1866462Y180803D01*
X1866545Y180511D01*
X1866753Y180219D01*
X1867003Y180053D01*
X1867295Y180011D01*
X1867628Y180094D01*
X1867878Y180303D01*
X1868128Y180678D01*
G01X1871228Y179136D02*
X1869562D01*
Y181636D01*
X1871228D01*
G01X1870562Y180428D02*
X1869562D01*
G01X1872703Y181219D02*
X1872953Y181469D01*
X1873245Y181594D01*
X1873578Y181636D01*
X1873995Y181553D01*
X1874287Y181344D01*
X1874370Y181094D01*
X1874328Y180844D01*
X1874162Y180636D01*
X1873328Y180219D01*
X1872953Y179928D01*
X1872703Y179511D01*
X1872620Y179136D01*
X1874370D01*
G01X1875678Y179636D02*
X1875928Y179344D01*
X1876262Y179178D01*
X1876637Y179136D01*
X1876970Y179178D01*
X1877303Y179386D01*
X1877512Y179636D01*
X1877553Y179886D01*
X1877470Y180178D01*
X1877178Y180386D01*
X1876887Y180469D01*
X1876512D01*
G01X1876887D02*
X1877137Y180594D01*
X1877345Y180803D01*
X1877428Y181053D01*
X1877345Y181303D01*
X1877137Y181511D01*
X1876762Y181636D01*
X1876387Y181594D01*
X1876012Y181428D01*
G01X1862817Y203700D02*
Y206200D01*
X1863858D01*
X1864192Y206075D01*
X1864400Y205908D01*
X1864483Y205575D01*
X1864400Y205242D01*
X1864150Y205033D01*
X1863858Y204908D01*
X1862817D01*
G01X1863858D02*
X1864483Y203700D01*
G01X1866042Y203992D02*
X1866333Y203783D01*
X1866667Y203700D01*
X1867000Y203783D01*
X1867292Y204033D01*
X1867500Y204408D01*
X1867583Y204783D01*
Y205242D01*
X1867500Y205617D01*
X1867292Y205950D01*
X1867042Y206117D01*
X1866750Y206200D01*
X1866417Y206117D01*
X1866167Y205950D01*
X1866000Y205700D01*
X1865917Y205367D01*
X1866000Y205075D01*
X1866208Y204783D01*
X1866458Y204617D01*
X1866750Y204575D01*
X1867083Y204658D01*
X1867333Y204867D01*
X1867583Y205242D01*
G01X1868600Y206200D02*
X1869183Y203700D01*
X1869850Y206200D01*
X1870517Y203700D01*
X1871100Y206200D01*
G01X1872033Y204200D02*
X1872283Y203908D01*
X1872617Y203742D01*
X1872992Y203700D01*
X1873325Y203742D01*
X1873658Y203950D01*
X1873867Y204200D01*
X1873908Y204450D01*
X1873825Y204742D01*
X1873533Y204950D01*
X1873242Y205033D01*
X1872867D01*
G01X1873242D02*
X1873492Y205158D01*
X1873700Y205367D01*
X1873783Y205617D01*
X1873700Y205867D01*
X1873492Y206075D01*
X1873117Y206200D01*
X1872742Y206158D01*
X1872367Y205992D01*
G01X1875258Y204742D02*
X1875550Y205033D01*
X1875800Y205200D01*
X1876133Y205283D01*
X1876425Y205200D01*
X1876633Y205033D01*
X1876800Y204783D01*
X1876842Y204492D01*
X1876800Y204242D01*
X1876633Y203992D01*
X1876383Y203783D01*
X1876092Y203700D01*
X1875758Y203783D01*
X1875467Y204033D01*
X1875300Y204408D01*
X1875258Y204825D01*
X1875342Y205367D01*
X1875467Y205658D01*
X1875675Y205950D01*
X1875967Y206158D01*
X1876258Y206200D01*
X1876550Y206117D01*
X1876758Y205908D01*
G01X1867950Y174500D02*
Y175625D01*
X1867117Y177000D01*
G01X1868783D02*
X1867950Y175625D01*
G01X1870342Y174792D02*
X1870633Y174583D01*
X1870967Y174500D01*
X1871300Y174583D01*
X1871592Y174833D01*
X1871800Y175208D01*
X1871883Y175583D01*
Y176042D01*
X1871800Y176417D01*
X1871592Y176750D01*
X1871342Y176917D01*
X1871050Y177000D01*
X1870717Y176917D01*
X1870467Y176750D01*
X1870300Y176500D01*
X1870217Y176167D01*
X1870300Y175875D01*
X1870508Y175583D01*
X1870758Y175417D01*
X1871050Y175375D01*
X1871383Y175458D01*
X1871633Y175667D01*
X1871883Y176042D01*
G01X1874983Y174500D02*
X1873317D01*
Y177000D01*
X1874983D01*
G01X1874317Y175792D02*
X1873317D01*
G01X1877250Y174500D02*
Y177000D01*
X1876750Y176500D01*
G01Y174500D02*
X1877750D01*
G01X1869390Y213387D02*
X1869265Y213137D01*
X1869182Y212845D01*
Y212512D01*
X1869307Y212137D01*
X1869515Y211845D01*
X1869765Y211637D01*
X1870182Y211470D01*
X1870557Y211428D01*
X1870932Y211512D01*
X1871182Y211637D01*
X1871432Y211887D01*
X1871599Y212178D01*
X1871682Y212470D01*
Y212762D01*
X1871599Y213053D01*
X1871474Y213303D01*
X1871307Y213512D01*
G01X1871390Y214862D02*
X1871599Y215153D01*
X1871682Y215487D01*
X1871599Y215820D01*
X1871349Y216112D01*
X1870974Y216320D01*
X1870599Y216403D01*
X1870140D01*
X1869765Y216320D01*
X1869432Y216112D01*
X1869265Y215862D01*
X1869182Y215570D01*
X1869265Y215237D01*
X1869432Y214987D01*
X1869682Y214820D01*
X1870015Y214737D01*
X1870307Y214820D01*
X1870599Y215028D01*
X1870765Y215278D01*
X1870807Y215570D01*
X1870724Y215903D01*
X1870515Y216153D01*
X1870140Y216403D01*
G01X1871682Y219503D02*
Y217837D01*
X1869182D01*
Y219503D01*
G01X1870390Y218837D02*
Y217837D01*
G01X1871307Y220853D02*
X1871515Y221103D01*
X1871640Y221395D01*
X1871682Y221770D01*
X1871599Y222145D01*
X1871432Y222437D01*
X1871140Y222645D01*
X1870807Y222687D01*
X1870474Y222603D01*
X1870265Y222395D01*
X1870099Y222103D01*
X1870057Y221812D01*
X1870099Y221520D01*
X1870265Y221145D01*
X1869182Y221270D01*
Y222395D01*
G01X1865833Y213469D02*
X1865708Y213219D01*
X1865625Y212927D01*
Y212594D01*
X1865750Y212219D01*
X1865958Y211927D01*
X1866208Y211719D01*
X1866625Y211552D01*
X1867000Y211510D01*
X1867375Y211594D01*
X1867625Y211719D01*
X1867875Y211969D01*
X1868042Y212260D01*
X1868125Y212552D01*
Y212844D01*
X1868042Y213135D01*
X1867917Y213385D01*
X1867750Y213594D01*
G01X1867833Y214944D02*
X1868042Y215235D01*
X1868125Y215569D01*
X1868042Y215902D01*
X1867792Y216194D01*
X1867417Y216402D01*
X1867042Y216485D01*
X1866583D01*
X1866208Y216402D01*
X1865875Y216194D01*
X1865708Y215944D01*
X1865625Y215652D01*
X1865708Y215319D01*
X1865875Y215069D01*
X1866125Y214902D01*
X1866458Y214819D01*
X1866750Y214902D01*
X1867042Y215110D01*
X1867208Y215360D01*
X1867250Y215652D01*
X1867167Y215985D01*
X1866958Y216235D01*
X1866583Y216485D01*
G01X1868125Y219585D02*
Y217919D01*
X1865625D01*
Y219585D01*
G01X1866833Y218919D02*
Y217919D01*
G01X1868125Y222352D02*
X1865625D01*
X1867417Y220810D01*
Y222894D01*
G01X1872125Y198003D02*
X1871875Y198128D01*
X1871583Y198211D01*
X1871250D01*
X1870875Y198086D01*
X1870583Y197878D01*
X1870375Y197628D01*
X1870208Y197211D01*
X1870166Y196836D01*
X1870250Y196461D01*
X1870375Y196211D01*
X1870625Y195961D01*
X1870916Y195794D01*
X1871208Y195711D01*
X1871500D01*
X1871791Y195794D01*
X1872041Y195919D01*
X1872250Y196086D01*
G01X1873600Y196003D02*
X1873891Y195794D01*
X1874225Y195711D01*
X1874558Y195794D01*
X1874850Y196044D01*
X1875058Y196419D01*
X1875141Y196794D01*
Y197253D01*
X1875058Y197628D01*
X1874850Y197961D01*
X1874600Y198128D01*
X1874308Y198211D01*
X1873975Y198128D01*
X1873725Y197961D01*
X1873558Y197711D01*
X1873475Y197378D01*
X1873558Y197086D01*
X1873766Y196794D01*
X1874016Y196628D01*
X1874308Y196586D01*
X1874641Y196669D01*
X1874891Y196878D01*
X1875141Y197253D01*
G01X1878241Y195711D02*
X1876575D01*
Y198211D01*
X1878241D01*
G01X1877575Y197003D02*
X1876575D01*
G01X1880425Y195711D02*
X1880508Y196253D01*
X1880633Y196711D01*
X1880800Y197128D01*
X1881008Y197586D01*
X1881341Y198211D01*
X1879675D01*
G01X1847741Y169300D02*
X1847616Y169050D01*
X1847533Y168758D01*
Y168425D01*
X1847658Y168050D01*
X1847866Y167758D01*
X1848116Y167550D01*
X1848533Y167383D01*
X1848908Y167341D01*
X1849283Y167425D01*
X1849533Y167550D01*
X1849783Y167800D01*
X1849950Y168091D01*
X1850033Y168383D01*
Y168675D01*
X1849950Y168966D01*
X1849825Y169216D01*
X1849658Y169425D01*
G01X1849741Y170775D02*
X1849950Y171066D01*
X1850033Y171400D01*
X1849950Y171733D01*
X1849700Y172025D01*
X1849325Y172233D01*
X1848950Y172316D01*
X1848491D01*
X1848116Y172233D01*
X1847783Y172025D01*
X1847616Y171775D01*
X1847533Y171483D01*
X1847616Y171150D01*
X1847783Y170900D01*
X1848033Y170733D01*
X1848366Y170650D01*
X1848658Y170733D01*
X1848950Y170941D01*
X1849116Y171191D01*
X1849158Y171483D01*
X1849075Y171816D01*
X1848866Y172066D01*
X1848491Y172316D01*
G01X1850033Y173791D02*
X1847533D01*
Y175375D01*
G01X1848741Y174791D02*
Y173791D01*
G01X1849658Y176766D02*
X1849866Y177016D01*
X1849991Y177308D01*
X1850033Y177683D01*
X1849950Y178058D01*
X1849783Y178350D01*
X1849491Y178558D01*
X1849158Y178600D01*
X1848825Y178516D01*
X1848616Y178308D01*
X1848450Y178016D01*
X1848408Y177725D01*
X1848450Y177433D01*
X1848616Y177058D01*
X1847533Y177183D01*
Y178308D01*
G01X1852964Y173682D02*
X1852714Y173807D01*
X1852422Y173890D01*
X1852089D01*
X1851714Y173765D01*
X1851422Y173557D01*
X1851214Y173307D01*
X1851047Y172890D01*
X1851005Y172515D01*
X1851089Y172140D01*
X1851214Y171890D01*
X1851464Y171640D01*
X1851755Y171473D01*
X1852047Y171390D01*
X1852339D01*
X1852630Y171473D01*
X1852880Y171598D01*
X1853089Y171765D01*
G01X1854439Y171682D02*
X1854730Y171473D01*
X1855064Y171390D01*
X1855397Y171473D01*
X1855689Y171723D01*
X1855897Y172098D01*
X1855980Y172473D01*
Y172932D01*
X1855897Y173307D01*
X1855689Y173640D01*
X1855439Y173807D01*
X1855147Y173890D01*
X1854814Y173807D01*
X1854564Y173640D01*
X1854397Y173390D01*
X1854314Y173057D01*
X1854397Y172765D01*
X1854605Y172473D01*
X1854855Y172307D01*
X1855147Y172265D01*
X1855480Y172348D01*
X1855730Y172557D01*
X1855980Y172932D01*
G01X1857455Y171390D02*
Y173890D01*
X1859039D01*
G01X1858455Y172682D02*
X1857455D01*
G01X1860555Y172432D02*
X1860847Y172723D01*
X1861097Y172890D01*
X1861430Y172973D01*
X1861722Y172890D01*
X1861930Y172723D01*
X1862097Y172473D01*
X1862139Y172182D01*
X1862097Y171932D01*
X1861930Y171682D01*
X1861680Y171473D01*
X1861389Y171390D01*
X1861055Y171473D01*
X1860764Y171723D01*
X1860597Y172098D01*
X1860555Y172515D01*
X1860639Y173057D01*
X1860764Y173348D01*
X1860972Y173640D01*
X1861264Y173848D01*
X1861555Y173890D01*
X1861847Y173807D01*
X1862055Y173598D01*
G01X1860031Y176746D02*
X1859906Y176496D01*
X1859823Y176204D01*
Y175871D01*
X1859948Y175496D01*
X1860156Y175204D01*
X1860406Y174996D01*
X1860823Y174829D01*
X1861198Y174787D01*
X1861573Y174871D01*
X1861823Y174996D01*
X1862073Y175246D01*
X1862240Y175537D01*
X1862323Y175829D01*
Y176121D01*
X1862240Y176412D01*
X1862115Y176662D01*
X1861948Y176871D01*
G01X1862031Y178221D02*
X1862240Y178512D01*
X1862323Y178846D01*
X1862240Y179179D01*
X1861990Y179471D01*
X1861615Y179679D01*
X1861240Y179762D01*
X1860781D01*
X1860406Y179679D01*
X1860073Y179471D01*
X1859906Y179221D01*
X1859823Y178929D01*
X1859906Y178596D01*
X1860073Y178346D01*
X1860323Y178179D01*
X1860656Y178096D01*
X1860948Y178179D01*
X1861240Y178387D01*
X1861406Y178637D01*
X1861448Y178929D01*
X1861365Y179262D01*
X1861156Y179512D01*
X1860781Y179762D01*
G01X1862323Y182862D02*
Y181196D01*
X1859823D01*
Y182862D01*
G01X1861031Y182196D02*
Y181196D01*
G01X1862031Y184421D02*
X1862240Y184712D01*
X1862323Y185046D01*
X1862240Y185379D01*
X1861990Y185671D01*
X1861615Y185879D01*
X1861240Y185962D01*
X1860781D01*
X1860406Y185879D01*
X1860073Y185671D01*
X1859906Y185421D01*
X1859823Y185129D01*
X1859906Y184796D01*
X1860073Y184546D01*
X1860323Y184379D01*
X1860656Y184296D01*
X1860948Y184379D01*
X1861240Y184587D01*
X1861406Y184837D01*
X1861448Y185129D01*
X1861365Y185462D01*
X1861156Y185712D01*
X1860781Y185962D01*
G01X1859385Y189429D02*
X1859260Y189179D01*
X1859177Y188887D01*
Y188554D01*
X1859302Y188179D01*
X1859510Y187887D01*
X1859760Y187679D01*
X1860177Y187512D01*
X1860552Y187470D01*
X1860927Y187554D01*
X1861177Y187679D01*
X1861427Y187929D01*
X1861594Y188220D01*
X1861677Y188512D01*
Y188804D01*
X1861594Y189095D01*
X1861469Y189345D01*
X1861302Y189554D01*
G01X1861385Y190904D02*
X1861594Y191195D01*
X1861677Y191529D01*
X1861594Y191862D01*
X1861344Y192154D01*
X1860969Y192362D01*
X1860594Y192445D01*
X1860135D01*
X1859760Y192362D01*
X1859427Y192154D01*
X1859260Y191904D01*
X1859177Y191612D01*
X1859260Y191279D01*
X1859427Y191029D01*
X1859677Y190862D01*
X1860010Y190779D01*
X1860302Y190862D01*
X1860594Y191070D01*
X1860760Y191320D01*
X1860802Y191612D01*
X1860719Y191945D01*
X1860510Y192195D01*
X1860135Y192445D01*
G01X1861677Y195545D02*
Y193879D01*
X1859177D01*
Y195545D01*
G01X1860385Y194879D02*
Y193879D01*
G01X1861677Y197812D02*
X1861635Y198104D01*
X1861510Y198437D01*
X1861302Y198645D01*
X1861010Y198729D01*
X1860719Y198645D01*
X1860469Y198395D01*
X1860344Y198020D01*
Y197604D01*
X1860260Y197354D01*
X1860052Y197145D01*
X1859760Y197062D01*
X1859469Y197187D01*
X1859260Y197479D01*
X1859177Y197812D01*
X1859260Y198145D01*
X1859469Y198437D01*
X1859760Y198562D01*
X1860052Y198479D01*
X1860260Y198270D01*
X1860344Y198020D01*
Y197604D01*
X1860469Y197229D01*
X1860719Y196979D01*
X1861010Y196895D01*
X1861302Y196979D01*
X1861510Y197187D01*
X1861635Y197520D01*
X1861677Y197812D01*
G01X1845665Y174222D02*
X1844993Y174299D01*
X1844425Y174414D01*
X1843908Y174567D01*
X1843340Y174759D01*
X1842565Y175066D01*
Y173532D01*
G01X1845303Y176747D02*
X1845562Y177016D01*
X1845665Y177322D01*
X1845562Y177629D01*
X1845252Y177897D01*
X1844787Y178089D01*
X1844322Y178166D01*
X1843753D01*
X1843288Y178089D01*
X1842875Y177897D01*
X1842668Y177667D01*
X1842565Y177399D01*
X1842668Y177092D01*
X1842875Y176862D01*
X1843185Y176709D01*
X1843598Y176632D01*
X1843960Y176709D01*
X1844322Y176901D01*
X1844528Y177131D01*
X1844580Y177399D01*
X1844477Y177706D01*
X1844218Y177936D01*
X1843753Y178166D01*
G01X1849154Y209500D02*
X1849422Y209552D01*
X1849729Y209707D01*
X1849921Y209965D01*
X1849997Y210327D01*
X1849921Y210688D01*
X1849691Y210998D01*
X1849346Y211153D01*
X1848962D01*
X1848732Y211257D01*
X1848541Y211515D01*
X1848464Y211877D01*
X1848579Y212238D01*
X1848847Y212497D01*
X1849154Y212600D01*
X1849461Y212497D01*
X1849729Y212238D01*
X1849844Y211877D01*
X1849767Y211515D01*
X1849576Y211257D01*
X1849346Y211153D01*
X1848962D01*
X1848617Y210998D01*
X1848387Y210688D01*
X1848311Y210327D01*
X1848387Y209965D01*
X1848579Y209707D01*
X1848886Y209552D01*
X1849154Y209500D01*
G01X1852254Y212600D02*
X1851947Y212497D01*
X1851717Y212238D01*
X1851564Y211928D01*
X1851449Y211515D01*
X1851411Y211050D01*
X1851449Y210585D01*
X1851564Y210172D01*
X1851717Y209862D01*
X1851947Y209603D01*
X1852254Y209500D01*
X1852561Y209603D01*
X1852791Y209862D01*
X1852944Y210172D01*
X1853059Y210585D01*
X1853097Y211050D01*
X1853059Y211515D01*
X1852944Y211928D01*
X1852791Y212238D01*
X1852561Y212497D01*
X1852254Y212600D01*
G01X1888785Y189764D02*
Y190815D01*
X1889836D01*
G01X1875573Y245251D02*
Y242151D01*
G01X1874691Y245251D02*
X1876455D01*
G01X1878673Y242151D02*
Y243546D01*
X1877906Y245251D01*
G01X1879440D02*
X1878673Y243546D01*
G01X1881006Y242151D02*
Y245251D01*
X1881926D01*
X1882233Y245096D01*
X1882463Y244734D01*
X1882540Y244321D01*
X1882463Y243908D01*
X1882271Y243598D01*
X1881926Y243443D01*
X1881006D01*
G01X1885640Y242151D02*
X1884106D01*
Y245251D01*
X1885640D01*
G01X1885026Y243753D02*
X1884106D01*
G01X1891916Y244993D02*
X1891686Y245148D01*
X1891418Y245251D01*
X1891111D01*
X1890766Y245096D01*
X1890498Y244838D01*
X1890306Y244528D01*
X1890153Y244011D01*
X1890115Y243546D01*
X1890191Y243081D01*
X1890306Y242771D01*
X1890536Y242461D01*
X1890805Y242254D01*
X1891073Y242151D01*
X1891341D01*
X1891610Y242254D01*
X1891840Y242409D01*
X1892031Y242616D01*
G01X1898116Y244993D02*
X1897886Y245148D01*
X1897618Y245251D01*
X1897311D01*
X1896966Y245096D01*
X1896698Y244838D01*
X1896506Y244528D01*
X1896353Y244011D01*
X1896315Y243546D01*
X1896391Y243081D01*
X1896506Y242771D01*
X1896736Y242461D01*
X1897005Y242254D01*
X1897273Y242151D01*
X1897541D01*
X1897810Y242254D01*
X1898040Y242409D01*
X1898231Y242616D01*
G01X1900373Y242151D02*
X1900066Y242203D01*
X1899798Y242409D01*
X1899568Y242719D01*
X1899415Y243081D01*
X1899338Y243494D01*
Y243908D01*
X1899415Y244321D01*
X1899568Y244683D01*
X1899798Y244993D01*
X1900066Y245199D01*
X1900373Y245251D01*
X1900680Y245199D01*
X1900948Y244993D01*
X1901178Y244683D01*
X1901331Y244321D01*
X1901408Y243908D01*
Y243494D01*
X1901331Y243081D01*
X1901178Y242719D01*
X1900948Y242409D01*
X1900680Y242203D01*
X1900373Y242151D01*
G01X1902591D02*
Y245251D01*
X1904355Y242151D01*
Y245251D01*
G01X1905691Y242151D02*
Y245251D01*
X1907455Y242151D01*
Y245251D01*
G01X1856767Y250223D02*
Y248001D01*
X1856920Y247536D01*
X1857227Y247226D01*
X1857610Y247123D01*
X1857993Y247226D01*
X1858300Y247536D01*
X1858453Y248001D01*
Y250223D01*
G01X1859905Y247536D02*
X1860212Y247278D01*
X1860557Y247123D01*
X1860863D01*
X1861170Y247278D01*
X1861400Y247536D01*
X1861515Y247898D01*
X1861438Y248260D01*
X1861247Y248570D01*
X1860902Y248776D01*
X1860442Y248880D01*
X1860173Y249086D01*
X1860058Y249448D01*
X1860135Y249810D01*
X1860327Y250068D01*
X1860595Y250223D01*
X1860863D01*
X1861132Y250120D01*
X1861362Y249861D01*
G01X1864117Y248776D02*
X1864270Y248931D01*
X1864385Y249190D01*
X1864462Y249551D01*
X1864385Y249861D01*
X1864232Y250068D01*
X1863963Y250223D01*
X1862928D01*
Y247123D01*
X1864193D01*
X1864462Y247330D01*
X1864615Y247640D01*
X1864692Y248001D01*
X1864615Y248363D01*
X1864385Y248673D01*
X1864117Y248776D01*
X1862928D01*
G01X1866067Y247743D02*
X1866297Y247381D01*
X1866603Y247175D01*
X1866948Y247123D01*
X1867255Y247175D01*
X1867562Y247433D01*
X1867753Y247743D01*
X1867792Y248053D01*
X1867715Y248415D01*
X1867447Y248673D01*
X1867178Y248776D01*
X1866833D01*
G01X1867178D02*
X1867408Y248931D01*
X1867600Y249190D01*
X1867677Y249500D01*
X1867600Y249810D01*
X1867408Y250068D01*
X1867063Y250223D01*
X1866718Y250171D01*
X1866373Y249965D01*
G01X1870010Y247020D02*
X1869933Y247071D01*
Y247175D01*
X1870010Y247226D01*
X1870087Y247175D01*
Y247071D01*
X1870010Y247020D01*
G01X1873110Y250223D02*
X1872803Y250120D01*
X1872573Y249861D01*
X1872420Y249551D01*
X1872305Y249138D01*
X1872267Y248673D01*
X1872305Y248208D01*
X1872420Y247795D01*
X1872573Y247485D01*
X1872803Y247226D01*
X1873110Y247123D01*
X1873417Y247226D01*
X1873647Y247485D01*
X1873800Y247795D01*
X1873915Y248208D01*
X1873953Y248673D01*
X1873915Y249138D01*
X1873800Y249551D01*
X1873647Y249861D01*
X1873417Y250120D01*
X1873110Y250223D01*
G01X1886328Y222748D02*
Y225248D01*
X1887369D01*
X1887703Y225123D01*
X1887911Y224956D01*
X1887994Y224623D01*
X1887911Y224290D01*
X1887661Y224081D01*
X1887369Y223956D01*
X1886328D01*
G01X1887369D02*
X1887994Y222748D01*
G01X1889553Y223040D02*
X1889844Y222831D01*
X1890178Y222748D01*
X1890511Y222831D01*
X1890803Y223081D01*
X1891011Y223456D01*
X1891094Y223831D01*
Y224290D01*
X1891011Y224665D01*
X1890803Y224998D01*
X1890553Y225165D01*
X1890261Y225248D01*
X1889928Y225165D01*
X1889678Y224998D01*
X1889511Y224748D01*
X1889428Y224415D01*
X1889511Y224123D01*
X1889719Y223831D01*
X1889969Y223665D01*
X1890261Y223623D01*
X1890594Y223706D01*
X1890844Y223915D01*
X1891094Y224290D01*
G01X1894194Y222748D02*
X1892528D01*
Y225248D01*
X1894194D01*
G01X1893528Y224040D02*
X1892528D01*
G01X1895544Y223123D02*
X1895794Y222915D01*
X1896086Y222790D01*
X1896461Y222748D01*
X1896836Y222831D01*
X1897128Y222998D01*
X1897336Y223290D01*
X1897378Y223623D01*
X1897294Y223956D01*
X1897086Y224165D01*
X1896794Y224331D01*
X1896503Y224373D01*
X1896211Y224331D01*
X1895836Y224165D01*
X1895961Y225248D01*
X1897086D01*
G01X1886312Y219204D02*
Y221704D01*
X1887353D01*
X1887687Y221579D01*
X1887895Y221412D01*
X1887978Y221079D01*
X1887895Y220746D01*
X1887645Y220537D01*
X1887353Y220412D01*
X1886312D01*
G01X1887353D02*
X1887978Y219204D01*
G01X1889537Y219496D02*
X1889828Y219287D01*
X1890162Y219204D01*
X1890495Y219287D01*
X1890787Y219537D01*
X1890995Y219912D01*
X1891078Y220287D01*
Y220746D01*
X1890995Y221121D01*
X1890787Y221454D01*
X1890537Y221621D01*
X1890245Y221704D01*
X1889912Y221621D01*
X1889662Y221454D01*
X1889495Y221204D01*
X1889412Y220871D01*
X1889495Y220579D01*
X1889703Y220287D01*
X1889953Y220121D01*
X1890245Y220079D01*
X1890578Y220162D01*
X1890828Y220371D01*
X1891078Y220746D01*
G01X1894178Y219204D02*
X1892512D01*
Y221704D01*
X1894178D01*
G01X1893512Y220496D02*
X1892512D01*
G01X1895653Y220246D02*
X1895945Y220537D01*
X1896195Y220704D01*
X1896528Y220787D01*
X1896820Y220704D01*
X1897028Y220537D01*
X1897195Y220287D01*
X1897237Y219996D01*
X1897195Y219746D01*
X1897028Y219496D01*
X1896778Y219287D01*
X1896487Y219204D01*
X1896153Y219287D01*
X1895862Y219537D01*
X1895695Y219912D01*
X1895653Y220329D01*
X1895737Y220871D01*
X1895862Y221162D01*
X1896070Y221454D01*
X1896362Y221662D01*
X1896653Y221704D01*
X1896945Y221621D01*
X1897153Y221412D01*
G01X1890593Y237733D02*
Y240233D01*
X1892177D01*
G01X1891593Y239025D02*
X1890593D01*
G01X1893568Y238233D02*
X1893818Y237941D01*
X1894152Y237775D01*
X1894527Y237733D01*
X1894860Y237775D01*
X1895193Y237983D01*
X1895402Y238233D01*
X1895443Y238483D01*
X1895360Y238775D01*
X1895068Y238983D01*
X1894777Y239066D01*
X1894402D01*
G01X1894777D02*
X1895027Y239191D01*
X1895235Y239400D01*
X1895318Y239650D01*
X1895235Y239900D01*
X1895027Y240108D01*
X1894652Y240233D01*
X1894277Y240191D01*
X1893902Y240025D01*
G01X1897585Y240233D02*
X1897252Y240150D01*
X1897002Y239941D01*
X1896835Y239691D01*
X1896710Y239358D01*
X1896668Y238983D01*
X1896710Y238608D01*
X1896835Y238275D01*
X1897002Y238025D01*
X1897252Y237816D01*
X1897585Y237733D01*
X1897918Y237816D01*
X1898168Y238025D01*
X1898335Y238275D01*
X1898460Y238608D01*
X1898502Y238983D01*
X1898460Y239358D01*
X1898335Y239691D01*
X1898168Y239941D01*
X1897918Y240150D01*
X1897585Y240233D01*
G01X1899435D02*
X1900018Y237733D01*
X1900685Y240233D01*
X1901352Y237733D01*
X1901935Y240233D01*
G01X1903785Y237733D02*
Y240233D01*
X1903285Y239733D01*
G01Y237733D02*
X1904285D01*
G01X1891763Y472730D02*
Y475830D01*
X1892683D01*
X1892990Y475675D01*
X1893220Y475313D01*
X1893297Y474900D01*
X1893220Y474487D01*
X1893028Y474177D01*
X1892683Y474022D01*
X1891763D01*
G01X1894787Y473195D02*
X1895017Y472937D01*
X1895285Y472782D01*
X1895630Y472730D01*
X1895975Y472833D01*
X1896243Y473040D01*
X1896435Y473402D01*
X1896473Y473815D01*
X1896397Y474228D01*
X1896205Y474487D01*
X1895937Y474693D01*
X1895668Y474745D01*
X1895400Y474693D01*
X1895055Y474487D01*
X1895170Y475830D01*
X1896205D01*
G01X1897772D02*
X1898730Y472730D01*
X1899688Y475830D01*
G01X1900680Y471697D02*
X1902980D01*
G01X1904125Y473143D02*
X1904432Y472885D01*
X1904777Y472730D01*
X1905083D01*
X1905390Y472885D01*
X1905620Y473143D01*
X1905735Y473505D01*
X1905658Y473867D01*
X1905467Y474177D01*
X1905122Y474383D01*
X1904662Y474487D01*
X1904393Y474693D01*
X1904278Y475055D01*
X1904355Y475417D01*
X1904547Y475675D01*
X1904815Y475830D01*
X1905083D01*
X1905352Y475727D01*
X1905582Y475468D01*
G01X1908030Y475830D02*
Y472730D01*
G01X1907148Y475830D02*
X1908912D01*
G01X1911437Y474383D02*
X1911590Y474538D01*
X1911705Y474797D01*
X1911782Y475158D01*
X1911705Y475468D01*
X1911552Y475675D01*
X1911283Y475830D01*
X1910248D01*
Y472730D01*
X1911513D01*
X1911782Y472937D01*
X1911935Y473247D01*
X1912012Y473608D01*
X1911935Y473970D01*
X1911705Y474280D01*
X1911437Y474383D01*
X1910248D01*
G01X1914230Y472730D02*
Y474125D01*
X1913463Y475830D01*
G01X1914997D02*
X1914230Y474125D01*
G01X1842247Y481336D02*
X1842400Y481491D01*
X1842515Y481750D01*
X1842592Y482111D01*
X1842515Y482421D01*
X1842362Y482628D01*
X1842093Y482783D01*
X1841058D01*
Y479683D01*
X1842323D01*
X1842592Y479890D01*
X1842745Y480200D01*
X1842822Y480561D01*
X1842745Y480923D01*
X1842515Y481233D01*
X1842247Y481336D01*
X1841058D01*
G01X1844043Y479683D02*
Y482783D01*
X1845040Y480200D01*
X1846037Y482783D01*
Y479683D01*
G01X1848983Y482525D02*
X1848753Y482680D01*
X1848485Y482783D01*
X1848178D01*
X1847833Y482628D01*
X1847565Y482370D01*
X1847373Y482060D01*
X1847220Y481543D01*
X1847182Y481078D01*
X1847258Y480613D01*
X1847373Y480303D01*
X1847603Y479993D01*
X1847872Y479786D01*
X1848140Y479683D01*
X1848408D01*
X1848677Y479786D01*
X1848907Y479941D01*
X1849098Y480148D01*
G01X1850090Y478650D02*
X1852390D01*
G01X1853497Y479683D02*
Y482783D01*
X1854263D01*
X1854570Y482628D01*
X1854800Y482421D01*
X1854992Y482111D01*
X1855145Y481750D01*
X1855183Y481233D01*
X1855145Y480716D01*
X1854992Y480355D01*
X1854800Y480045D01*
X1854570Y479838D01*
X1854263Y479683D01*
X1853497D01*
G01X1857747Y481336D02*
X1857900Y481491D01*
X1858015Y481750D01*
X1858092Y482111D01*
X1858015Y482421D01*
X1857862Y482628D01*
X1857593Y482783D01*
X1856558D01*
Y479683D01*
X1857823D01*
X1858092Y479890D01*
X1858245Y480200D01*
X1858322Y480561D01*
X1858245Y480923D01*
X1858015Y481233D01*
X1857747Y481336D01*
X1856558D01*
G01X1860770Y481233D02*
X1861537D01*
Y480303D01*
X1861307Y479993D01*
X1861038Y479786D01*
X1860655Y479683D01*
X1860272Y479786D01*
X1860003Y479993D01*
X1859773Y480303D01*
X1859620Y480665D01*
X1859543Y481078D01*
Y481440D01*
X1859620Y481750D01*
X1859773Y482111D01*
X1860003Y482421D01*
X1860233Y482628D01*
X1860540Y482783D01*
X1860808D01*
X1861115Y482680D01*
X1861345Y482473D01*
G01X1844475Y511445D02*
X1841975D01*
Y512486D01*
X1842100Y512820D01*
X1842267Y513028D01*
X1842600Y513111D01*
X1842933Y513028D01*
X1843142Y512778D01*
X1843267Y512486D01*
Y511445D01*
G01Y512486D02*
X1844475Y513111D01*
G01X1844183Y514670D02*
X1844392Y514961D01*
X1844475Y515295D01*
X1844392Y515628D01*
X1844142Y515920D01*
X1843767Y516128D01*
X1843392Y516211D01*
X1842933D01*
X1842558Y516128D01*
X1842225Y515920D01*
X1842058Y515670D01*
X1841975Y515378D01*
X1842058Y515045D01*
X1842225Y514795D01*
X1842475Y514628D01*
X1842808Y514545D01*
X1843100Y514628D01*
X1843392Y514836D01*
X1843558Y515086D01*
X1843600Y515378D01*
X1843517Y515711D01*
X1843308Y515961D01*
X1842933Y516211D01*
G01X1843142Y518811D02*
X1843017Y518978D01*
X1842808Y519103D01*
X1842517Y519186D01*
X1842267Y519103D01*
X1842100Y518936D01*
X1841975Y518645D01*
Y517520D01*
X1844475D01*
Y518895D01*
X1844308Y519186D01*
X1844058Y519353D01*
X1843767Y519436D01*
X1843475Y519353D01*
X1843225Y519103D01*
X1843142Y518811D01*
Y517520D01*
G01X1844475Y521578D02*
X1841975D01*
X1842475Y521078D01*
G01X1844475D02*
Y522078D01*
G01X1842392Y523886D02*
X1842142Y524136D01*
X1842017Y524428D01*
X1841975Y524761D01*
X1842058Y525178D01*
X1842267Y525470D01*
X1842517Y525553D01*
X1842767Y525511D01*
X1842975Y525345D01*
X1843392Y524511D01*
X1843683Y524136D01*
X1844100Y523886D01*
X1844475Y523803D01*
Y525553D01*
G01X1838346Y481866D02*
X1835846D01*
Y482907D01*
X1835971Y483241D01*
X1836138Y483449D01*
X1836471Y483532D01*
X1836804Y483449D01*
X1837013Y483199D01*
X1837138Y482907D01*
Y481866D01*
G01Y482907D02*
X1838346Y483532D01*
G01X1838054Y485091D02*
X1838263Y485382D01*
X1838346Y485716D01*
X1838263Y486049D01*
X1838013Y486341D01*
X1837638Y486549D01*
X1837263Y486632D01*
X1836804D01*
X1836429Y486549D01*
X1836096Y486341D01*
X1835929Y486091D01*
X1835846Y485799D01*
X1835929Y485466D01*
X1836096Y485216D01*
X1836346Y485049D01*
X1836679Y484966D01*
X1836971Y485049D01*
X1837263Y485257D01*
X1837429Y485507D01*
X1837471Y485799D01*
X1837388Y486132D01*
X1837179Y486382D01*
X1836804Y486632D01*
G01X1837013Y489232D02*
X1836888Y489399D01*
X1836679Y489524D01*
X1836388Y489607D01*
X1836138Y489524D01*
X1835971Y489357D01*
X1835846Y489066D01*
Y487941D01*
X1838346D01*
Y489316D01*
X1838179Y489607D01*
X1837929Y489774D01*
X1837638Y489857D01*
X1837346Y489774D01*
X1837096Y489524D01*
X1837013Y489232D01*
Y487941D01*
G01X1838346Y491999D02*
X1835846D01*
X1836346Y491499D01*
G01X1838346D02*
Y492499D01*
G01X1837846Y494182D02*
X1838138Y494432D01*
X1838304Y494766D01*
X1838346Y495141D01*
X1838304Y495474D01*
X1838096Y495807D01*
X1837846Y496016D01*
X1837596Y496057D01*
X1837304Y495974D01*
X1837096Y495682D01*
X1837013Y495391D01*
Y495016D01*
G01Y495391D02*
X1836888Y495641D01*
X1836679Y495849D01*
X1836429Y495932D01*
X1836179Y495849D01*
X1835971Y495641D01*
X1835846Y495266D01*
X1835888Y494891D01*
X1836054Y494516D01*
G01X1878757Y468210D02*
X1878965Y467960D01*
X1879215Y467793D01*
X1879507Y467710D01*
X1879840Y467793D01*
X1880090Y467960D01*
X1880340Y468210D01*
X1880423Y468543D01*
Y470210D01*
G01X1881982Y468002D02*
X1882273Y467793D01*
X1882607Y467710D01*
X1882940Y467793D01*
X1883232Y468043D01*
X1883440Y468418D01*
X1883523Y468793D01*
Y469252D01*
X1883440Y469627D01*
X1883232Y469960D01*
X1882982Y470127D01*
X1882690Y470210D01*
X1882357Y470127D01*
X1882107Y469960D01*
X1881940Y469710D01*
X1881857Y469377D01*
X1881940Y469085D01*
X1882148Y468793D01*
X1882398Y468627D01*
X1882690Y468585D01*
X1883023Y468668D01*
X1883273Y468877D01*
X1883523Y469252D01*
G01X1886123Y469043D02*
X1886290Y469168D01*
X1886415Y469377D01*
X1886498Y469668D01*
X1886415Y469918D01*
X1886248Y470085D01*
X1885957Y470210D01*
X1884832D01*
Y467710D01*
X1886207D01*
X1886498Y467877D01*
X1886665Y468127D01*
X1886748Y468418D01*
X1886665Y468710D01*
X1886415Y468960D01*
X1886123Y469043D01*
X1884832D01*
G01X1887973Y468210D02*
X1888223Y467918D01*
X1888557Y467752D01*
X1888932Y467710D01*
X1889265Y467752D01*
X1889598Y467960D01*
X1889807Y468210D01*
X1889848Y468460D01*
X1889765Y468752D01*
X1889473Y468960D01*
X1889182Y469043D01*
X1888807D01*
G01X1889182D02*
X1889432Y469168D01*
X1889640Y469377D01*
X1889723Y469627D01*
X1889640Y469877D01*
X1889432Y470085D01*
X1889057Y470210D01*
X1888682Y470168D01*
X1888307Y470002D01*
G01X1875087Y491481D02*
X1875317Y491119D01*
X1875623Y490913D01*
X1875968Y490861D01*
X1876275Y490913D01*
X1876582Y491171D01*
X1876773Y491481D01*
X1876812Y491791D01*
X1876735Y492153D01*
X1876467Y492411D01*
X1876198Y492514D01*
X1875853D01*
G01X1876198D02*
X1876428Y492669D01*
X1876620Y492928D01*
X1876697Y493238D01*
X1876620Y493548D01*
X1876428Y493806D01*
X1876083Y493961D01*
X1875738Y493909D01*
X1875393Y493703D01*
G01X1886457Y484820D02*
X1886665Y484570D01*
X1886915Y484403D01*
X1887207Y484320D01*
X1887540Y484403D01*
X1887790Y484570D01*
X1888040Y484820D01*
X1888123Y485153D01*
Y486820D01*
G01X1889682Y484612D02*
X1889973Y484403D01*
X1890307Y484320D01*
X1890640Y484403D01*
X1890932Y484653D01*
X1891140Y485028D01*
X1891223Y485403D01*
Y485862D01*
X1891140Y486237D01*
X1890932Y486570D01*
X1890682Y486737D01*
X1890390Y486820D01*
X1890057Y486737D01*
X1889807Y486570D01*
X1889640Y486320D01*
X1889557Y485987D01*
X1889640Y485695D01*
X1889848Y485403D01*
X1890098Y485237D01*
X1890390Y485195D01*
X1890723Y485278D01*
X1890973Y485487D01*
X1891223Y485862D01*
G01X1893823Y485653D02*
X1893990Y485778D01*
X1894115Y485987D01*
X1894198Y486278D01*
X1894115Y486528D01*
X1893948Y486695D01*
X1893657Y486820D01*
X1892532D01*
Y484320D01*
X1893907D01*
X1894198Y484487D01*
X1894365Y484737D01*
X1894448Y485028D01*
X1894365Y485320D01*
X1894115Y485570D01*
X1893823Y485653D01*
X1892532D01*
G01X1895798Y486403D02*
X1896048Y486653D01*
X1896340Y486778D01*
X1896673Y486820D01*
X1897090Y486737D01*
X1897382Y486528D01*
X1897465Y486278D01*
X1897423Y486028D01*
X1897257Y485820D01*
X1896423Y485403D01*
X1896048Y485112D01*
X1895798Y484695D01*
X1895715Y484320D01*
X1897465D01*
G01X1909885Y498000D02*
Y488000D01*
X1878315D01*
Y498000D01*
X1909885D01*
G01X1876942Y521955D02*
X1877211Y521696D01*
X1877517Y521593D01*
X1877824Y521696D01*
X1878092Y522006D01*
X1878284Y522471D01*
X1878361Y522936D01*
Y523505D01*
X1878284Y523970D01*
X1878092Y524383D01*
X1877862Y524590D01*
X1877594Y524693D01*
X1877287Y524590D01*
X1877057Y524383D01*
X1876904Y524073D01*
X1876827Y523660D01*
X1876904Y523298D01*
X1877096Y522936D01*
X1877326Y522730D01*
X1877594Y522678D01*
X1877901Y522781D01*
X1878131Y523040D01*
X1878361Y523505D01*
G01X1877400Y507917D02*
X1877650Y508125D01*
X1877817Y508375D01*
X1877900Y508667D01*
X1877817Y509000D01*
X1877650Y509250D01*
X1877400Y509500D01*
X1877067Y509583D01*
X1875400D01*
G01X1877608Y511142D02*
X1877817Y511433D01*
X1877900Y511767D01*
X1877817Y512100D01*
X1877567Y512392D01*
X1877192Y512600D01*
X1876817Y512683D01*
X1876358D01*
X1875983Y512600D01*
X1875650Y512392D01*
X1875483Y512142D01*
X1875400Y511850D01*
X1875483Y511517D01*
X1875650Y511267D01*
X1875900Y511100D01*
X1876233Y511017D01*
X1876525Y511100D01*
X1876817Y511308D01*
X1876983Y511558D01*
X1877025Y511850D01*
X1876942Y512183D01*
X1876733Y512433D01*
X1876358Y512683D01*
G01X1876567Y515283D02*
X1876442Y515450D01*
X1876233Y515575D01*
X1875942Y515658D01*
X1875692Y515575D01*
X1875525Y515408D01*
X1875400Y515117D01*
Y513992D01*
X1877900D01*
Y515367D01*
X1877733Y515658D01*
X1877483Y515825D01*
X1877192Y515908D01*
X1876900Y515825D01*
X1876650Y515575D01*
X1876567Y515283D01*
Y513992D01*
G01X1877900Y518050D02*
X1875400D01*
X1875900Y517550D01*
G01X1877900D02*
Y518550D01*
G01X1881697Y508741D02*
X1879059D01*
Y535001D01*
X1881697D01*
G01X1921264Y508741D02*
X1893508D01*
G01X1843532Y502182D02*
X1843801Y501923D01*
X1844107Y501820D01*
X1844414Y501923D01*
X1844682Y502233D01*
X1844874Y502698D01*
X1844951Y503163D01*
Y503732D01*
X1844874Y504197D01*
X1844682Y504610D01*
X1844452Y504817D01*
X1844184Y504920D01*
X1843877Y504817D01*
X1843647Y504610D01*
X1843494Y504300D01*
X1843417Y503887D01*
X1843494Y503525D01*
X1843686Y503163D01*
X1843916Y502957D01*
X1844184Y502905D01*
X1844491Y503008D01*
X1844721Y503267D01*
X1844951Y503732D01*
G01X1874990Y500060D02*
Y503160D01*
X1874530Y502540D01*
G01Y500060D02*
X1875450D01*
G01X1878090Y503160D02*
X1877783Y503057D01*
X1877553Y502798D01*
X1877400Y502488D01*
X1877285Y502075D01*
X1877247Y501610D01*
X1877285Y501145D01*
X1877400Y500732D01*
X1877553Y500422D01*
X1877783Y500163D01*
X1878090Y500060D01*
X1878397Y500163D01*
X1878627Y500422D01*
X1878780Y500732D01*
X1878895Y501145D01*
X1878933Y501610D01*
X1878895Y502075D01*
X1878780Y502488D01*
X1878627Y502798D01*
X1878397Y503057D01*
X1878090Y503160D01*
G01X1855817Y484896D02*
X1856025Y484646D01*
X1856275Y484479D01*
X1856567Y484396D01*
X1856900Y484479D01*
X1857150Y484646D01*
X1857400Y484896D01*
X1857483Y485229D01*
Y486896D01*
G01X1859042Y484688D02*
X1859333Y484479D01*
X1859667Y484396D01*
X1860000Y484479D01*
X1860292Y484729D01*
X1860500Y485104D01*
X1860583Y485479D01*
Y485938D01*
X1860500Y486313D01*
X1860292Y486646D01*
X1860042Y486813D01*
X1859750Y486896D01*
X1859417Y486813D01*
X1859167Y486646D01*
X1859000Y486396D01*
X1858917Y486063D01*
X1859000Y485771D01*
X1859208Y485479D01*
X1859458Y485313D01*
X1859750Y485271D01*
X1860083Y485354D01*
X1860333Y485563D01*
X1860583Y485938D01*
G01X1863183Y485729D02*
X1863350Y485854D01*
X1863475Y486063D01*
X1863558Y486354D01*
X1863475Y486604D01*
X1863308Y486771D01*
X1863017Y486896D01*
X1861892D01*
Y484396D01*
X1863267D01*
X1863558Y484563D01*
X1863725Y484813D01*
X1863808Y485104D01*
X1863725Y485396D01*
X1863475Y485646D01*
X1863183Y485729D01*
X1861892D01*
G01X1866450Y484396D02*
Y486896D01*
X1864908Y485104D01*
X1866992D01*
G01X1847059Y494204D02*
X1847054Y487952D01*
X1872654D01*
X1872649Y494204D01*
G01X1846967Y540107D02*
Y542607D01*
X1847967D01*
X1848300Y542482D01*
X1848550Y542190D01*
X1848633Y541857D01*
X1848550Y541524D01*
X1848342Y541274D01*
X1847967Y541149D01*
X1846967D01*
G01X1849650Y542607D02*
X1850233Y540107D01*
X1850900Y542607D01*
X1851567Y540107D01*
X1852150Y542607D01*
G01X1853167Y540107D02*
Y542607D01*
X1854208D01*
X1854542Y542482D01*
X1854750Y542315D01*
X1854833Y541982D01*
X1854750Y541649D01*
X1854500Y541440D01*
X1854208Y541315D01*
X1853167D01*
G01X1854208D02*
X1854833Y540107D01*
G01X1855850Y539274D02*
X1858350D01*
G01X1859367Y542607D02*
Y540107D01*
X1861033D01*
G01X1864133D02*
X1862467D01*
Y542607D01*
X1864133D01*
G01X1863467Y541399D02*
X1862467D01*
G01X1865483Y540107D02*
Y542607D01*
X1866317D01*
X1866650Y542482D01*
X1866900Y542315D01*
X1867108Y542065D01*
X1867275Y541774D01*
X1867317Y541357D01*
X1867275Y540940D01*
X1867108Y540649D01*
X1866900Y540399D01*
X1866650Y540232D01*
X1866317Y540107D01*
X1865483D01*
G01X1897263Y583790D02*
Y586890D01*
X1898183D01*
X1898490Y586735D01*
X1898720Y586373D01*
X1898797Y585960D01*
X1898720Y585547D01*
X1898528Y585237D01*
X1898183Y585082D01*
X1897263D01*
G01X1899980Y586890D02*
X1900517Y583790D01*
X1901130Y586890D01*
X1901743Y583790D01*
X1902280Y586890D01*
G01X1903463Y583790D02*
Y586890D01*
X1904422D01*
X1904728Y586735D01*
X1904920Y586528D01*
X1904997Y586115D01*
X1904920Y585702D01*
X1904690Y585443D01*
X1904422Y585288D01*
X1903463D01*
G01X1904422D02*
X1904997Y583790D01*
G01X1906180Y582757D02*
X1908480D01*
G01X1910737Y585443D02*
X1910890Y585598D01*
X1911005Y585857D01*
X1911082Y586218D01*
X1911005Y586528D01*
X1910852Y586735D01*
X1910583Y586890D01*
X1909548D01*
Y583790D01*
X1910813D01*
X1911082Y583997D01*
X1911235Y584307D01*
X1911312Y584668D01*
X1911235Y585030D01*
X1911005Y585340D01*
X1910737Y585443D01*
X1909548D01*
G01X1913530Y586890D02*
Y583790D01*
G01X1912648Y586890D02*
X1914412D01*
G01X1915748Y583790D02*
Y586890D01*
X1917512Y583790D01*
Y586890D01*
G01X1840500Y557883D02*
X1837400D01*
Y558842D01*
X1837555Y559148D01*
X1837762Y559340D01*
X1838175Y559417D01*
X1838588Y559340D01*
X1838847Y559110D01*
X1839002Y558842D01*
Y557883D01*
G01Y558842D02*
X1840500Y559417D01*
G01Y560792D02*
X1837400Y561750D01*
X1840500Y562708D01*
G01X1839415Y562363D02*
Y561137D01*
G01X1837400Y564390D02*
Y565310D01*
G01Y564850D02*
X1840500D01*
G01Y564390D02*
Y565310D01*
G01Y567107D02*
X1837400D01*
Y567873D01*
X1837555Y568180D01*
X1837762Y568410D01*
X1838072Y568602D01*
X1838433Y568755D01*
X1838950Y568793D01*
X1839467Y568755D01*
X1839828Y568602D01*
X1840138Y568410D01*
X1840345Y568180D01*
X1840500Y567873D01*
Y567107D01*
G01X1841533Y569900D02*
Y572200D01*
G01X1840500Y573307D02*
X1837400D01*
G01Y574763D02*
X1839312Y573307D01*
G01X1840500Y574993D02*
X1838433Y573958D01*
G01X1840500Y578017D02*
Y576483D01*
X1837400D01*
Y578017D01*
G01X1838898Y577403D02*
Y576483D01*
G01X1840500Y580350D02*
X1839105D01*
X1837400Y579583D01*
G01Y581117D02*
X1839105Y580350D01*
G01X1896918Y561254D02*
Y572460D01*
G01Y580490D02*
Y581700D01*
X1883400D01*
Y593834D01*
X1865730D01*
Y588680D01*
X1859700D01*
Y545800D01*
G01X1899800Y536800D02*
X1874278D01*
Y537784D01*
G01X1845744Y535947D02*
X1843244D01*
Y536988D01*
X1843369Y537322D01*
X1843536Y537530D01*
X1843869Y537613D01*
X1844202Y537530D01*
X1844411Y537280D01*
X1844536Y536988D01*
Y535947D01*
G01Y536988D02*
X1845744Y537613D01*
G01X1845452Y539172D02*
X1845661Y539463D01*
X1845744Y539797D01*
X1845661Y540130D01*
X1845411Y540422D01*
X1845036Y540630D01*
X1844661Y540713D01*
X1844202D01*
X1843827Y540630D01*
X1843494Y540422D01*
X1843327Y540172D01*
X1843244Y539880D01*
X1843327Y539547D01*
X1843494Y539297D01*
X1843744Y539130D01*
X1844077Y539047D01*
X1844369Y539130D01*
X1844661Y539338D01*
X1844827Y539588D01*
X1844869Y539880D01*
X1844786Y540213D01*
X1844577Y540463D01*
X1844202Y540713D01*
G01X1844411Y543313D02*
X1844286Y543480D01*
X1844077Y543605D01*
X1843786Y543688D01*
X1843536Y543605D01*
X1843369Y543438D01*
X1843244Y543147D01*
Y542022D01*
X1845744D01*
Y543397D01*
X1845577Y543688D01*
X1845327Y543855D01*
X1845036Y543938D01*
X1844744Y543855D01*
X1844494Y543605D01*
X1844411Y543313D01*
Y542022D01*
G01X1845744Y546080D02*
X1843244D01*
X1843744Y545580D01*
G01X1845744D02*
Y546580D01*
G01Y549180D02*
X1843244D01*
X1843744Y548680D01*
G01X1845744D02*
Y549680D01*
G01X1892360Y545030D02*
X1896783D01*
G01Y546923D02*
Y543137D01*
G01X1903651Y545030D02*
X1900062D01*
Y543137D01*
X1896783Y545030D01*
X1900062Y546923D01*
Y545030D01*
G01X1868565Y541063D02*
X1872988D01*
G01Y542956D02*
Y539170D01*
G01X1879856Y541063D02*
X1876267D01*
Y539170D01*
X1872988Y541063D01*
X1876267Y542956D01*
Y541063D01*
G01X1898240Y588450D02*
Y591550D01*
X1896822Y589328D01*
X1898738D01*
G01X1897054Y547694D02*
Y550794D01*
X1895636Y548572D01*
X1897552D01*
G01X1896117Y576250D02*
X1896347Y575888D01*
X1896653Y575682D01*
X1896998Y575630D01*
X1897305Y575682D01*
X1897612Y575940D01*
X1897803Y576250D01*
X1897842Y576560D01*
X1897765Y576922D01*
X1897497Y577180D01*
X1897228Y577283D01*
X1896883D01*
G01X1897228D02*
X1897458Y577438D01*
X1897650Y577697D01*
X1897727Y578007D01*
X1897650Y578317D01*
X1897458Y578575D01*
X1897113Y578730D01*
X1896768Y578678D01*
X1896423Y578472D01*
G01X1840756Y583578D02*
X1841006Y583786D01*
X1841173Y584036D01*
X1841256Y584328D01*
X1841173Y584661D01*
X1841006Y584911D01*
X1840756Y585161D01*
X1840423Y585244D01*
X1838756D01*
G01X1840964Y586803D02*
X1841173Y587094D01*
X1841256Y587428D01*
X1841173Y587761D01*
X1840923Y588053D01*
X1840548Y588261D01*
X1840173Y588344D01*
X1839714D01*
X1839339Y588261D01*
X1839006Y588053D01*
X1838839Y587803D01*
X1838756Y587511D01*
X1838839Y587178D01*
X1839006Y586928D01*
X1839256Y586761D01*
X1839589Y586678D01*
X1839881Y586761D01*
X1840173Y586969D01*
X1840339Y587219D01*
X1840381Y587511D01*
X1840298Y587844D01*
X1840089Y588094D01*
X1839714Y588344D01*
G01X1841256Y589569D02*
X1838756Y590611D01*
X1841256Y591653D01*
G01X1840381Y591278D02*
Y589944D01*
G01X1841256Y593711D02*
X1838756D01*
X1839256Y593211D01*
G01X1841256D02*
Y594211D01*
G01X1858126Y550567D02*
X1842772D01*
Y595055D01*
X1858126D01*
Y550567D01*
G01X1884917Y583300D02*
X1885125Y583050D01*
X1885375Y582883D01*
X1885667Y582800D01*
X1886000Y582883D01*
X1886250Y583050D01*
X1886500Y583300D01*
X1886583Y583633D01*
Y585300D01*
G01X1888850Y582800D02*
X1889142Y582842D01*
X1889475Y582967D01*
X1889683Y583175D01*
X1889767Y583467D01*
X1889683Y583758D01*
X1889433Y584008D01*
X1889058Y584133D01*
X1888642D01*
X1888392Y584217D01*
X1888183Y584425D01*
X1888100Y584717D01*
X1888225Y585008D01*
X1888517Y585217D01*
X1888850Y585300D01*
X1889183Y585217D01*
X1889475Y585008D01*
X1889600Y584717D01*
X1889517Y584425D01*
X1889308Y584217D01*
X1889058Y584133D01*
X1888642D01*
X1888267Y584008D01*
X1888017Y583758D01*
X1887933Y583467D01*
X1888017Y583175D01*
X1888225Y582967D01*
X1888558Y582842D01*
X1888850Y582800D01*
G01X1892867Y585092D02*
X1892617Y585217D01*
X1892325Y585300D01*
X1891992D01*
X1891617Y585175D01*
X1891325Y584967D01*
X1891117Y584717D01*
X1890950Y584300D01*
X1890908Y583925D01*
X1890992Y583550D01*
X1891117Y583300D01*
X1891367Y583050D01*
X1891658Y582883D01*
X1891950Y582800D01*
X1892242D01*
X1892533Y582883D01*
X1892783Y583008D01*
X1892992Y583175D01*
G01X1895050Y582800D02*
Y585300D01*
X1894550Y584800D01*
G01Y582800D02*
X1895550D01*
G01X1896086Y586320D02*
X1886086D01*
Y617890D01*
X1896086D01*
Y586320D01*
G01X1893508Y535001D02*
X1921264D01*
G01X1875435Y531016D02*
X1875665Y531326D01*
X1875933Y531481D01*
X1876240Y531533D01*
X1876623Y531430D01*
X1876891Y531171D01*
X1876968Y530861D01*
X1876930Y530551D01*
X1876776Y530293D01*
X1876010Y529776D01*
X1875665Y529415D01*
X1875435Y528898D01*
X1875358Y528433D01*
X1876968D01*
G01X1847059Y532300D02*
X1847054Y538552D01*
X1872654D01*
X1872649Y532300D01*
G01X1865150Y570600D02*
Y567350D01*
X1868650D01*
G01X1877150Y570600D02*
Y567350D01*
X1873650D01*
G01X1872400Y572850D02*
X1869900D01*
G01X1883300Y565300D02*
X1894700D01*
G01X1883300Y578700D02*
Y565300D01*
G01X1894700Y578700D02*
X1883300D01*
G01X1894700Y565300D02*
Y578700D01*
G01X1893400Y548900D02*
Y560300D01*
G01X1880000Y548900D02*
X1893400D01*
G01X1880000Y560300D02*
Y548900D01*
G01X1893400Y560300D02*
X1880000D01*
G01X1880553Y621800D02*
Y624900D01*
X1881550Y622317D01*
X1882547Y624900D01*
Y621800D01*
G01X1885417D02*
X1883883D01*
Y624900D01*
X1885417D01*
G01X1884803Y623402D02*
X1883883D01*
G01X1886600Y620767D02*
X1888900D01*
G01X1890007Y621800D02*
Y624900D01*
X1890773D01*
X1891080Y624745D01*
X1891310Y624538D01*
X1891502Y624228D01*
X1891655Y623867D01*
X1891693Y623350D01*
X1891655Y622833D01*
X1891502Y622472D01*
X1891310Y622162D01*
X1891080Y621955D01*
X1890773Y621800D01*
X1890007D01*
G01X1894257Y623453D02*
X1894410Y623608D01*
X1894525Y623867D01*
X1894602Y624228D01*
X1894525Y624538D01*
X1894372Y624745D01*
X1894103Y624900D01*
X1893068D01*
Y621800D01*
X1894333D01*
X1894602Y622007D01*
X1894755Y622317D01*
X1894832Y622678D01*
X1894755Y623040D01*
X1894525Y623350D01*
X1894257Y623453D01*
X1893068D01*
G01X1897280Y623350D02*
X1898047D01*
Y622420D01*
X1897817Y622110D01*
X1897548Y621903D01*
X1897165Y621800D01*
X1896782Y621903D01*
X1896513Y622110D01*
X1896283Y622420D01*
X1896130Y622782D01*
X1896053Y623195D01*
Y623557D01*
X1896130Y623867D01*
X1896283Y624228D01*
X1896513Y624538D01*
X1896743Y624745D01*
X1897050Y624900D01*
X1897318D01*
X1897625Y624797D01*
X1897855Y624590D01*
G01X1882842Y600085D02*
X1883111Y599826D01*
X1883417Y599723D01*
X1883724Y599826D01*
X1883992Y600136D01*
X1884184Y600601D01*
X1884261Y601066D01*
Y601635D01*
X1884184Y602100D01*
X1883992Y602513D01*
X1883762Y602720D01*
X1883494Y602823D01*
X1883187Y602720D01*
X1882957Y602513D01*
X1882804Y602203D01*
X1882727Y601790D01*
X1882804Y601428D01*
X1882996Y601066D01*
X1883226Y600860D01*
X1883494Y600808D01*
X1883801Y600911D01*
X1884031Y601170D01*
X1884261Y601635D01*
G01X1837611Y625040D02*
Y622540D01*
G01X1836653Y625040D02*
X1838569D01*
G01X1839836Y622540D02*
Y625040D01*
G01X1841586D02*
Y622540D01*
G01Y623790D02*
X1839836D01*
G01X1843103Y622832D02*
X1843394Y622623D01*
X1843728Y622540D01*
X1844061Y622623D01*
X1844353Y622873D01*
X1844561Y623248D01*
X1844644Y623623D01*
Y624082D01*
X1844561Y624457D01*
X1844353Y624790D01*
X1844103Y624957D01*
X1843811Y625040D01*
X1843478Y624957D01*
X1843228Y624790D01*
X1843061Y624540D01*
X1842978Y624207D01*
X1843061Y623915D01*
X1843269Y623623D01*
X1843519Y623457D01*
X1843811Y623415D01*
X1844144Y623498D01*
X1844394Y623707D01*
X1844644Y624082D01*
G01X1845869Y622540D02*
X1846911Y625040D01*
X1847953Y622540D01*
G01X1847578Y623415D02*
X1846244D01*
G01X1850011Y622540D02*
Y625040D01*
X1849511Y624540D01*
G01Y622540D02*
X1850511D01*
G01X1849910Y595900D02*
Y599000D01*
X1848492Y596778D01*
X1850408D01*
G01X1883377Y617590D02*
X1883607Y617228D01*
X1883913Y617022D01*
X1884258Y616970D01*
X1884565Y617022D01*
X1884872Y617280D01*
X1885063Y617590D01*
X1885102Y617900D01*
X1885025Y618262D01*
X1884757Y618520D01*
X1884488Y618623D01*
X1884143D01*
G01X1884488D02*
X1884718Y618778D01*
X1884910Y619037D01*
X1884987Y619347D01*
X1884910Y619657D01*
X1884718Y619915D01*
X1884373Y620070D01*
X1884028Y620018D01*
X1883683Y619812D01*
G01X1839834Y608517D02*
X1840084Y608725D01*
X1840251Y608975D01*
X1840334Y609267D01*
X1840251Y609600D01*
X1840084Y609850D01*
X1839834Y610100D01*
X1839501Y610183D01*
X1837834D01*
G01X1840334Y612450D02*
X1840292Y612742D01*
X1840167Y613075D01*
X1839959Y613283D01*
X1839667Y613367D01*
X1839376Y613283D01*
X1839126Y613033D01*
X1839001Y612658D01*
Y612242D01*
X1838917Y611992D01*
X1838709Y611783D01*
X1838417Y611700D01*
X1838126Y611825D01*
X1837917Y612117D01*
X1837834Y612450D01*
X1837917Y612783D01*
X1838126Y613075D01*
X1838417Y613200D01*
X1838709Y613117D01*
X1838917Y612908D01*
X1839001Y612658D01*
Y612242D01*
X1839126Y611867D01*
X1839376Y611617D01*
X1839667Y611533D01*
X1839959Y611617D01*
X1840167Y611825D01*
X1840292Y612158D01*
X1840334Y612450D01*
G01Y614633D02*
X1837834D01*
Y615467D01*
X1837959Y615800D01*
X1838126Y616050D01*
X1838376Y616258D01*
X1838667Y616425D01*
X1839084Y616467D01*
X1839501Y616425D01*
X1839792Y616258D01*
X1840042Y616050D01*
X1840209Y615800D01*
X1840334Y615467D01*
Y614633D01*
G01Y619150D02*
X1837834D01*
X1839626Y617608D01*
Y619692D01*
G01X1900967Y-18500D02*
Y-16000D01*
X1902008D01*
X1902342Y-16125D01*
X1902550Y-16292D01*
X1902633Y-16625D01*
X1902550Y-16958D01*
X1902300Y-17167D01*
X1902008Y-17292D01*
X1900967D01*
G01X1902008D02*
X1902633Y-18500D01*
G01X1904192Y-18208D02*
X1904483Y-18417D01*
X1904817Y-18500D01*
X1905150Y-18417D01*
X1905442Y-18167D01*
X1905650Y-17792D01*
X1905733Y-17417D01*
Y-16958D01*
X1905650Y-16583D01*
X1905442Y-16250D01*
X1905192Y-16083D01*
X1904900Y-16000D01*
X1904567Y-16083D01*
X1904317Y-16250D01*
X1904150Y-16500D01*
X1904067Y-16833D01*
X1904150Y-17125D01*
X1904358Y-17417D01*
X1904608Y-17583D01*
X1904900Y-17625D01*
X1905233Y-17542D01*
X1905483Y-17333D01*
X1905733Y-16958D01*
G01X1908250Y-17250D02*
X1909083D01*
Y-18000D01*
X1908833Y-18250D01*
X1908542Y-18417D01*
X1908125Y-18500D01*
X1907708Y-18417D01*
X1907417Y-18250D01*
X1907167Y-18000D01*
X1907000Y-17708D01*
X1906917Y-17375D01*
Y-17083D01*
X1907000Y-16833D01*
X1907167Y-16542D01*
X1907417Y-16292D01*
X1907667Y-16125D01*
X1908000Y-16000D01*
X1908292D01*
X1908625Y-16083D01*
X1908875Y-16250D01*
G01X1911100Y-18500D02*
Y-16000D01*
X1910600Y-16500D01*
G01Y-18500D02*
X1911600D01*
G01X1914117D02*
X1914200Y-17958D01*
X1914325Y-17500D01*
X1914492Y-17083D01*
X1914700Y-16625D01*
X1915033Y-16000D01*
X1913367D01*
G01X1900767Y-22100D02*
Y-19600D01*
X1901808D01*
X1902142Y-19725D01*
X1902350Y-19892D01*
X1902433Y-20225D01*
X1902350Y-20558D01*
X1902100Y-20767D01*
X1901808Y-20892D01*
X1900767D01*
G01X1901808D02*
X1902433Y-22100D01*
G01X1903992Y-21808D02*
X1904283Y-22017D01*
X1904617Y-22100D01*
X1904950Y-22017D01*
X1905242Y-21767D01*
X1905450Y-21392D01*
X1905533Y-21017D01*
Y-20558D01*
X1905450Y-20183D01*
X1905242Y-19850D01*
X1904992Y-19683D01*
X1904700Y-19600D01*
X1904367Y-19683D01*
X1904117Y-19850D01*
X1903950Y-20100D01*
X1903867Y-20433D01*
X1903950Y-20725D01*
X1904158Y-21017D01*
X1904408Y-21183D01*
X1904700Y-21225D01*
X1905033Y-21142D01*
X1905283Y-20933D01*
X1905533Y-20558D01*
G01X1908050Y-20850D02*
X1908883D01*
Y-21600D01*
X1908633Y-21850D01*
X1908342Y-22017D01*
X1907925Y-22100D01*
X1907508Y-22017D01*
X1907217Y-21850D01*
X1906967Y-21600D01*
X1906800Y-21308D01*
X1906717Y-20975D01*
Y-20683D01*
X1906800Y-20433D01*
X1906967Y-20142D01*
X1907217Y-19892D01*
X1907467Y-19725D01*
X1907800Y-19600D01*
X1908092D01*
X1908425Y-19683D01*
X1908675Y-19850D01*
G01X1910900Y-22100D02*
Y-19600D01*
X1910400Y-20100D01*
G01Y-22100D02*
X1911400D01*
G01X1914000D02*
X1914292Y-22058D01*
X1914625Y-21933D01*
X1914833Y-21725D01*
X1914917Y-21433D01*
X1914833Y-21142D01*
X1914583Y-20892D01*
X1914208Y-20767D01*
X1913792D01*
X1913542Y-20683D01*
X1913333Y-20475D01*
X1913250Y-20183D01*
X1913375Y-19892D01*
X1913667Y-19683D01*
X1914000Y-19600D01*
X1914333Y-19683D01*
X1914625Y-19892D01*
X1914750Y-20183D01*
X1914667Y-20475D01*
X1914458Y-20683D01*
X1914208Y-20767D01*
X1913792D01*
X1913417Y-20892D01*
X1913167Y-21142D01*
X1913083Y-21433D01*
X1913167Y-21725D01*
X1913375Y-21933D01*
X1913708Y-22058D01*
X1914000Y-22100D01*
G01X1923367Y-18092D02*
X1923117Y-17967D01*
X1922825Y-17884D01*
X1922492D01*
X1922117Y-18009D01*
X1921825Y-18217D01*
X1921617Y-18467D01*
X1921450Y-18884D01*
X1921408Y-19259D01*
X1921492Y-19634D01*
X1921617Y-19884D01*
X1921867Y-20134D01*
X1922158Y-20301D01*
X1922450Y-20384D01*
X1922742D01*
X1923033Y-20301D01*
X1923283Y-20176D01*
X1923492Y-20009D01*
G01X1924842Y-20092D02*
X1925133Y-20301D01*
X1925467Y-20384D01*
X1925800Y-20301D01*
X1926092Y-20051D01*
X1926300Y-19676D01*
X1926383Y-19301D01*
Y-18842D01*
X1926300Y-18467D01*
X1926092Y-18134D01*
X1925842Y-17967D01*
X1925550Y-17884D01*
X1925217Y-17967D01*
X1924967Y-18134D01*
X1924800Y-18384D01*
X1924717Y-18717D01*
X1924800Y-19009D01*
X1925008Y-19301D01*
X1925258Y-19467D01*
X1925550Y-19509D01*
X1925883Y-19426D01*
X1926133Y-19217D01*
X1926383Y-18842D01*
G01X1928900Y-19134D02*
X1929733D01*
Y-19884D01*
X1929483Y-20134D01*
X1929192Y-20301D01*
X1928775Y-20384D01*
X1928358Y-20301D01*
X1928067Y-20134D01*
X1927817Y-19884D01*
X1927650Y-19592D01*
X1927567Y-19259D01*
Y-18967D01*
X1927650Y-18717D01*
X1927817Y-18426D01*
X1928067Y-18176D01*
X1928317Y-18009D01*
X1928650Y-17884D01*
X1928942D01*
X1929275Y-17967D01*
X1929525Y-18134D01*
G01X1931750Y-20384D02*
Y-17884D01*
X1931250Y-18384D01*
G01Y-20384D02*
X1932250D01*
G01X1934058Y-19342D02*
X1934350Y-19051D01*
X1934600Y-18884D01*
X1934933Y-18801D01*
X1935225Y-18884D01*
X1935433Y-19051D01*
X1935600Y-19301D01*
X1935642Y-19592D01*
X1935600Y-19842D01*
X1935433Y-20092D01*
X1935183Y-20301D01*
X1934892Y-20384D01*
X1934558Y-20301D01*
X1934267Y-20051D01*
X1934100Y-19676D01*
X1934058Y-19259D01*
X1934142Y-18717D01*
X1934267Y-18426D01*
X1934475Y-18134D01*
X1934767Y-17926D01*
X1935058Y-17884D01*
X1935350Y-17967D01*
X1935558Y-18176D01*
G01X1922967Y-14212D02*
X1922717Y-14087D01*
X1922425Y-14004D01*
X1922092D01*
X1921717Y-14129D01*
X1921425Y-14337D01*
X1921217Y-14587D01*
X1921050Y-15004D01*
X1921008Y-15379D01*
X1921092Y-15754D01*
X1921217Y-16004D01*
X1921467Y-16254D01*
X1921758Y-16421D01*
X1922050Y-16504D01*
X1922342D01*
X1922633Y-16421D01*
X1922883Y-16296D01*
X1923092Y-16129D01*
G01X1924442Y-16212D02*
X1924733Y-16421D01*
X1925067Y-16504D01*
X1925400Y-16421D01*
X1925692Y-16171D01*
X1925900Y-15796D01*
X1925983Y-15421D01*
Y-14962D01*
X1925900Y-14587D01*
X1925692Y-14254D01*
X1925442Y-14087D01*
X1925150Y-14004D01*
X1924817Y-14087D01*
X1924567Y-14254D01*
X1924400Y-14504D01*
X1924317Y-14837D01*
X1924400Y-15129D01*
X1924608Y-15421D01*
X1924858Y-15587D01*
X1925150Y-15629D01*
X1925483Y-15546D01*
X1925733Y-15337D01*
X1925983Y-14962D01*
G01X1928500Y-15254D02*
X1929333D01*
Y-16004D01*
X1929083Y-16254D01*
X1928792Y-16421D01*
X1928375Y-16504D01*
X1927958Y-16421D01*
X1927667Y-16254D01*
X1927417Y-16004D01*
X1927250Y-15712D01*
X1927167Y-15379D01*
Y-15087D01*
X1927250Y-14837D01*
X1927417Y-14546D01*
X1927667Y-14296D01*
X1927917Y-14129D01*
X1928250Y-14004D01*
X1928542D01*
X1928875Y-14087D01*
X1929125Y-14254D01*
G01X1931350Y-16504D02*
Y-14004D01*
X1930850Y-14504D01*
G01Y-16504D02*
X1931850D01*
G01X1933533Y-16004D02*
X1933783Y-16296D01*
X1934117Y-16462D01*
X1934492Y-16504D01*
X1934825Y-16462D01*
X1935158Y-16254D01*
X1935367Y-16004D01*
X1935408Y-15754D01*
X1935325Y-15462D01*
X1935033Y-15254D01*
X1934742Y-15171D01*
X1934367D01*
G01X1934742D02*
X1934992Y-15046D01*
X1935200Y-14837D01*
X1935283Y-14587D01*
X1935200Y-14337D01*
X1934992Y-14129D01*
X1934617Y-14004D01*
X1934242Y-14046D01*
X1933867Y-14212D01*
G01X1925089Y13254D02*
X1925506Y13787D01*
X1925756Y14387D01*
Y14921D01*
X1925506Y15454D01*
X1925089Y15854D01*
X1924506Y16054D01*
X1923923Y15921D01*
X1923423Y15587D01*
X1923089Y14987D01*
X1922923Y14187D01*
X1922589Y13721D01*
X1922006Y13521D01*
X1921423Y13654D01*
X1921006Y13987D01*
X1920756Y14454D01*
Y14921D01*
X1920923Y15387D01*
X1921339Y15787D01*
G01X1925756Y19754D02*
X1920756D01*
G01X1922423Y24854D02*
X1925756D01*
G01X1921089D02*
X1921006Y24721D01*
X1920839D01*
X1920756Y24854D01*
X1920839Y24987D01*
X1921006D01*
X1921089Y24854D01*
G01X1920756Y29954D02*
X1925756D01*
G01X1922423Y29021D02*
Y30887D01*
G01X1912968Y61600D02*
Y64700D01*
X1914732Y61600D01*
Y64700D01*
G01X1916490D02*
X1917410D01*
G01X1916950D02*
Y61600D01*
G01X1916490D02*
X1917410D01*
G01X1920893Y64442D02*
X1920663Y64597D01*
X1920395Y64700D01*
X1920088D01*
X1919743Y64545D01*
X1919475Y64287D01*
X1919283Y63977D01*
X1919130Y63460D01*
X1919092Y62995D01*
X1919168Y62530D01*
X1919283Y62220D01*
X1919513Y61910D01*
X1919782Y61703D01*
X1920050Y61600D01*
X1920318D01*
X1920587Y61703D01*
X1920817Y61858D01*
X1921008Y62065D01*
G01X1922000Y60567D02*
X1924300D01*
G01X1926250Y61600D02*
Y64700D01*
X1925790Y64080D01*
G01Y61600D02*
X1926710D01*
G01X1904967Y74953D02*
X1908699D01*
Y99500D01*
G01X1953523Y65407D02*
X1953273Y65532D01*
X1952981Y65615D01*
X1952648D01*
X1952273Y65490D01*
X1951981Y65282D01*
X1951773Y65032D01*
X1951606Y64615D01*
X1951564Y64240D01*
X1951648Y63865D01*
X1951773Y63615D01*
X1952023Y63365D01*
X1952314Y63198D01*
X1952606Y63115D01*
X1952898D01*
X1953189Y63198D01*
X1953439Y63323D01*
X1953648Y63490D01*
G01X1955623Y63115D02*
X1955706Y63657D01*
X1955831Y64115D01*
X1955998Y64532D01*
X1956206Y64990D01*
X1956539Y65615D01*
X1954873D01*
G01X1959639Y63115D02*
X1957973D01*
Y65615D01*
X1959639D01*
G01X1958973Y64407D02*
X1957973D01*
G01X1961906Y63115D02*
X1962198Y63157D01*
X1962531Y63282D01*
X1962739Y63490D01*
X1962823Y63782D01*
X1962739Y64073D01*
X1962489Y64323D01*
X1962114Y64448D01*
X1961698D01*
X1961448Y64532D01*
X1961239Y64740D01*
X1961156Y65032D01*
X1961281Y65323D01*
X1961573Y65532D01*
X1961906Y65615D01*
X1962239Y65532D01*
X1962531Y65323D01*
X1962656Y65032D01*
X1962573Y64740D01*
X1962364Y64532D01*
X1962114Y64448D01*
X1961698D01*
X1961323Y64323D01*
X1961073Y64073D01*
X1960989Y63782D01*
X1961073Y63490D01*
X1961281Y63282D01*
X1961614Y63157D01*
X1961906Y63115D01*
G01X1953685Y72727D02*
X1953435Y72852D01*
X1953143Y72935D01*
X1952810D01*
X1952435Y72810D01*
X1952143Y72602D01*
X1951935Y72352D01*
X1951768Y71935D01*
X1951726Y71560D01*
X1951810Y71185D01*
X1951935Y70935D01*
X1952185Y70685D01*
X1952476Y70518D01*
X1952768Y70435D01*
X1953060D01*
X1953351Y70518D01*
X1953601Y70643D01*
X1953810Y70810D01*
G01X1955785Y70435D02*
X1955868Y70977D01*
X1955993Y71435D01*
X1956160Y71852D01*
X1956368Y72310D01*
X1956701Y72935D01*
X1955035D01*
G01X1959801Y70435D02*
X1958135D01*
Y72935D01*
X1959801D01*
G01X1959135Y71727D02*
X1958135D01*
G01X1961276Y71477D02*
X1961568Y71768D01*
X1961818Y71935D01*
X1962151Y72018D01*
X1962443Y71935D01*
X1962651Y71768D01*
X1962818Y71518D01*
X1962860Y71227D01*
X1962818Y70977D01*
X1962651Y70727D01*
X1962401Y70518D01*
X1962110Y70435D01*
X1961776Y70518D01*
X1961485Y70768D01*
X1961318Y71143D01*
X1961276Y71560D01*
X1961360Y72102D01*
X1961485Y72393D01*
X1961693Y72685D01*
X1961985Y72893D01*
X1962276Y72935D01*
X1962568Y72852D01*
X1962776Y72643D01*
G01X1924372Y64868D02*
X1921872D01*
Y65909D01*
X1921997Y66243D01*
X1922164Y66451D01*
X1922497Y66534D01*
X1922830Y66451D01*
X1923039Y66201D01*
X1923164Y65909D01*
Y64868D01*
G01Y65909D02*
X1924372Y66534D01*
G01X1922289Y68009D02*
X1922039Y68259D01*
X1921914Y68551D01*
X1921872Y68884D01*
X1921955Y69301D01*
X1922164Y69593D01*
X1922414Y69676D01*
X1922664Y69634D01*
X1922872Y69468D01*
X1923289Y68634D01*
X1923580Y68259D01*
X1923997Y68009D01*
X1924372Y67926D01*
Y69676D01*
G01X1923997Y70984D02*
X1924205Y71234D01*
X1924330Y71526D01*
X1924372Y71901D01*
X1924289Y72276D01*
X1924122Y72568D01*
X1923830Y72776D01*
X1923497Y72818D01*
X1923164Y72734D01*
X1922955Y72526D01*
X1922789Y72234D01*
X1922747Y71943D01*
X1922789Y71651D01*
X1922955Y71276D01*
X1921872Y71401D01*
Y72526D01*
G01Y73751D02*
X1924372Y74334D01*
X1921872Y75001D01*
X1924372Y75668D01*
X1921872Y76251D01*
G01X1924372Y78101D02*
X1921872D01*
X1922372Y77601D01*
G01X1924372D02*
Y78601D01*
G01X1923997Y80284D02*
X1924205Y80534D01*
X1924330Y80826D01*
X1924372Y81201D01*
X1924289Y81576D01*
X1924122Y81868D01*
X1923830Y82076D01*
X1923497Y82118D01*
X1923164Y82034D01*
X1922955Y81826D01*
X1922789Y81534D01*
X1922747Y81243D01*
X1922789Y80951D01*
X1922955Y80576D01*
X1921872Y80701D01*
Y81826D01*
G01X1923330Y83509D02*
X1923039Y83801D01*
X1922872Y84051D01*
X1922789Y84384D01*
X1922872Y84676D01*
X1923039Y84884D01*
X1923289Y85051D01*
X1923580Y85093D01*
X1923830Y85051D01*
X1924080Y84884D01*
X1924289Y84634D01*
X1924372Y84343D01*
X1924289Y84009D01*
X1924039Y83718D01*
X1923664Y83551D01*
X1923247Y83509D01*
X1922705Y83593D01*
X1922414Y83718D01*
X1922122Y83926D01*
X1921914Y84218D01*
X1921872Y84509D01*
X1921955Y84801D01*
X1922164Y85009D01*
G01X1916700Y71667D02*
X1914200D01*
Y72708D01*
X1914325Y73042D01*
X1914492Y73250D01*
X1914825Y73333D01*
X1915158Y73250D01*
X1915367Y73000D01*
X1915492Y72708D01*
Y71667D01*
G01Y72708D02*
X1916700Y73333D01*
G01X1916408Y74892D02*
X1916617Y75183D01*
X1916700Y75517D01*
X1916617Y75850D01*
X1916367Y76142D01*
X1915992Y76350D01*
X1915617Y76433D01*
X1915158D01*
X1914783Y76350D01*
X1914450Y76142D01*
X1914283Y75892D01*
X1914200Y75600D01*
X1914283Y75267D01*
X1914450Y75017D01*
X1914700Y74850D01*
X1915033Y74767D01*
X1915325Y74850D01*
X1915617Y75058D01*
X1915783Y75308D01*
X1915825Y75600D01*
X1915742Y75933D01*
X1915533Y76183D01*
X1915158Y76433D01*
G01X1916700Y77908D02*
X1914200D01*
Y79492D01*
G01X1915408Y78908D02*
Y77908D01*
G01X1915658Y81008D02*
X1915367Y81300D01*
X1915200Y81550D01*
X1915117Y81883D01*
X1915200Y82175D01*
X1915367Y82383D01*
X1915617Y82550D01*
X1915908Y82592D01*
X1916158Y82550D01*
X1916408Y82383D01*
X1916617Y82133D01*
X1916700Y81842D01*
X1916617Y81508D01*
X1916367Y81217D01*
X1915992Y81050D01*
X1915575Y81008D01*
X1915033Y81092D01*
X1914742Y81217D01*
X1914450Y81425D01*
X1914242Y81717D01*
X1914200Y82008D01*
X1914283Y82300D01*
X1914492Y82508D01*
G01X1916700Y84900D02*
X1916658Y85192D01*
X1916533Y85525D01*
X1916325Y85733D01*
X1916033Y85817D01*
X1915742Y85733D01*
X1915492Y85483D01*
X1915367Y85108D01*
Y84692D01*
X1915283Y84442D01*
X1915075Y84233D01*
X1914783Y84150D01*
X1914492Y84275D01*
X1914283Y84567D01*
X1914200Y84900D01*
X1914283Y85233D01*
X1914492Y85525D01*
X1914783Y85650D01*
X1915075Y85567D01*
X1915283Y85358D01*
X1915367Y85108D01*
Y84692D01*
X1915492Y84317D01*
X1915742Y84067D01*
X1916033Y83983D01*
X1916325Y84067D01*
X1916533Y84275D01*
X1916658Y84608D01*
X1916700Y84900D01*
G01Y87367D02*
X1914200D01*
Y88408D01*
X1914325Y88742D01*
X1914492Y88950D01*
X1914825Y89033D01*
X1915158Y88950D01*
X1915367Y88700D01*
X1915492Y88408D01*
Y87367D01*
G01Y88408D02*
X1916700Y89033D01*
G01X1916408Y90592D02*
X1916617Y90883D01*
X1916700Y91217D01*
X1916617Y91550D01*
X1916367Y91842D01*
X1915992Y92050D01*
X1915617Y92133D01*
X1915158D01*
X1914783Y92050D01*
X1914450Y91842D01*
X1914283Y91592D01*
X1914200Y91300D01*
X1914283Y90967D01*
X1914450Y90717D01*
X1914700Y90550D01*
X1915033Y90467D01*
X1915325Y90550D01*
X1915617Y90758D01*
X1915783Y91008D01*
X1915825Y91300D01*
X1915742Y91633D01*
X1915533Y91883D01*
X1915158Y92133D01*
G01X1916700Y93608D02*
X1914200D01*
Y95192D01*
G01X1915408Y94608D02*
Y93608D01*
G01X1915658Y96708D02*
X1915367Y97000D01*
X1915200Y97250D01*
X1915117Y97583D01*
X1915200Y97875D01*
X1915367Y98083D01*
X1915617Y98250D01*
X1915908Y98292D01*
X1916158Y98250D01*
X1916408Y98083D01*
X1916617Y97833D01*
X1916700Y97542D01*
X1916617Y97208D01*
X1916367Y96917D01*
X1915992Y96750D01*
X1915575Y96708D01*
X1915033Y96792D01*
X1914742Y96917D01*
X1914450Y97125D01*
X1914242Y97417D01*
X1914200Y97708D01*
X1914283Y98000D01*
X1914492Y98208D01*
G01X1916408Y99892D02*
X1916617Y100183D01*
X1916700Y100517D01*
X1916617Y100850D01*
X1916367Y101142D01*
X1915992Y101350D01*
X1915617Y101433D01*
X1915158D01*
X1914783Y101350D01*
X1914450Y101142D01*
X1914283Y100892D01*
X1914200Y100600D01*
X1914283Y100267D01*
X1914450Y100017D01*
X1914700Y99850D01*
X1915033Y99767D01*
X1915325Y99850D01*
X1915617Y100058D01*
X1915783Y100308D01*
X1915825Y100600D01*
X1915742Y100933D01*
X1915533Y101183D01*
X1915158Y101433D01*
G01X1913300Y87367D02*
X1910800D01*
Y88408D01*
X1910925Y88742D01*
X1911092Y88950D01*
X1911425Y89033D01*
X1911758Y88950D01*
X1911967Y88700D01*
X1912092Y88408D01*
Y87367D01*
G01Y88408D02*
X1913300Y89033D01*
G01X1913008Y90592D02*
X1913217Y90883D01*
X1913300Y91217D01*
X1913217Y91550D01*
X1912967Y91842D01*
X1912592Y92050D01*
X1912217Y92133D01*
X1911758D01*
X1911383Y92050D01*
X1911050Y91842D01*
X1910883Y91592D01*
X1910800Y91300D01*
X1910883Y90967D01*
X1911050Y90717D01*
X1911300Y90550D01*
X1911633Y90467D01*
X1911925Y90550D01*
X1912217Y90758D01*
X1912383Y91008D01*
X1912425Y91300D01*
X1912342Y91633D01*
X1912133Y91883D01*
X1911758Y92133D01*
G01X1913300Y93608D02*
X1910800D01*
Y95192D01*
G01X1912008Y94608D02*
Y93608D01*
G01X1912258Y96708D02*
X1911967Y97000D01*
X1911800Y97250D01*
X1911717Y97583D01*
X1911800Y97875D01*
X1911967Y98083D01*
X1912217Y98250D01*
X1912508Y98292D01*
X1912758Y98250D01*
X1913008Y98083D01*
X1913217Y97833D01*
X1913300Y97542D01*
X1913217Y97208D01*
X1912967Y96917D01*
X1912592Y96750D01*
X1912175Y96708D01*
X1911633Y96792D01*
X1911342Y96917D01*
X1911050Y97125D01*
X1910842Y97417D01*
X1910800Y97708D01*
X1910883Y98000D01*
X1911092Y98208D01*
G01X1913300Y100517D02*
X1912758Y100600D01*
X1912300Y100725D01*
X1911883Y100892D01*
X1911425Y101100D01*
X1910800Y101433D01*
Y99767D01*
G01X1913300Y71667D02*
X1910800D01*
Y72708D01*
X1910925Y73042D01*
X1911092Y73250D01*
X1911425Y73333D01*
X1911758Y73250D01*
X1911967Y73000D01*
X1912092Y72708D01*
Y71667D01*
G01Y72708D02*
X1913300Y73333D01*
G01X1913008Y74892D02*
X1913217Y75183D01*
X1913300Y75517D01*
X1913217Y75850D01*
X1912967Y76142D01*
X1912592Y76350D01*
X1912217Y76433D01*
X1911758D01*
X1911383Y76350D01*
X1911050Y76142D01*
X1910883Y75892D01*
X1910800Y75600D01*
X1910883Y75267D01*
X1911050Y75017D01*
X1911300Y74850D01*
X1911633Y74767D01*
X1911925Y74850D01*
X1912217Y75058D01*
X1912383Y75308D01*
X1912425Y75600D01*
X1912342Y75933D01*
X1912133Y76183D01*
X1911758Y76433D01*
G01X1913300Y77908D02*
X1910800D01*
Y79492D01*
G01X1912008Y78908D02*
Y77908D01*
G01X1913300Y81717D02*
X1912758Y81800D01*
X1912300Y81925D01*
X1911883Y82092D01*
X1911425Y82300D01*
X1910800Y82633D01*
Y80967D01*
G01Y84900D02*
X1910883Y84567D01*
X1911092Y84317D01*
X1911342Y84150D01*
X1911675Y84025D01*
X1912050Y83983D01*
X1912425Y84025D01*
X1912758Y84150D01*
X1913008Y84317D01*
X1913217Y84567D01*
X1913300Y84900D01*
X1913217Y85233D01*
X1913008Y85483D01*
X1912758Y85650D01*
X1912425Y85775D01*
X1912050Y85817D01*
X1911675Y85775D01*
X1911342Y85650D01*
X1911092Y85483D01*
X1910883Y85233D01*
X1910800Y84900D01*
G01X1898664Y62296D02*
X1898539Y62046D01*
X1898456Y61754D01*
Y61421D01*
X1898581Y61046D01*
X1898789Y60754D01*
X1899039Y60546D01*
X1899456Y60379D01*
X1899831Y60337D01*
X1900206Y60421D01*
X1900456Y60546D01*
X1900706Y60796D01*
X1900873Y61087D01*
X1900956Y61379D01*
Y61671D01*
X1900873Y61962D01*
X1900748Y62212D01*
X1900581Y62421D01*
G01X1900664Y63771D02*
X1900873Y64062D01*
X1900956Y64396D01*
X1900873Y64729D01*
X1900623Y65021D01*
X1900248Y65229D01*
X1899873Y65312D01*
X1899414D01*
X1899039Y65229D01*
X1898706Y65021D01*
X1898539Y64771D01*
X1898456Y64479D01*
X1898539Y64146D01*
X1898706Y63896D01*
X1898956Y63729D01*
X1899289Y63646D01*
X1899581Y63729D01*
X1899873Y63937D01*
X1900039Y64187D01*
X1900081Y64479D01*
X1899998Y64812D01*
X1899789Y65062D01*
X1899414Y65312D01*
G01X1899706Y67829D02*
Y68662D01*
X1900456D01*
X1900706Y68412D01*
X1900873Y68121D01*
X1900956Y67704D01*
X1900873Y67287D01*
X1900706Y66996D01*
X1900456Y66746D01*
X1900164Y66579D01*
X1899831Y66496D01*
X1899539D01*
X1899289Y66579D01*
X1898998Y66746D01*
X1898748Y66996D01*
X1898581Y67246D01*
X1898456Y67579D01*
Y67871D01*
X1898539Y68204D01*
X1898706Y68454D01*
G01X1900581Y69762D02*
X1900789Y70012D01*
X1900914Y70304D01*
X1900956Y70679D01*
X1900873Y71054D01*
X1900706Y71346D01*
X1900414Y71554D01*
X1900081Y71596D01*
X1899748Y71512D01*
X1899539Y71304D01*
X1899373Y71012D01*
X1899331Y70721D01*
X1899373Y70429D01*
X1899539Y70054D01*
X1898456Y70179D01*
Y71304D01*
G01X1902664Y62296D02*
X1902539Y62046D01*
X1902456Y61754D01*
Y61421D01*
X1902581Y61046D01*
X1902789Y60754D01*
X1903039Y60546D01*
X1903456Y60379D01*
X1903831Y60337D01*
X1904206Y60421D01*
X1904456Y60546D01*
X1904706Y60796D01*
X1904873Y61087D01*
X1904956Y61379D01*
Y61671D01*
X1904873Y61962D01*
X1904748Y62212D01*
X1904581Y62421D01*
G01X1904664Y63771D02*
X1904873Y64062D01*
X1904956Y64396D01*
X1904873Y64729D01*
X1904623Y65021D01*
X1904248Y65229D01*
X1903873Y65312D01*
X1903414D01*
X1903039Y65229D01*
X1902706Y65021D01*
X1902539Y64771D01*
X1902456Y64479D01*
X1902539Y64146D01*
X1902706Y63896D01*
X1902956Y63729D01*
X1903289Y63646D01*
X1903581Y63729D01*
X1903873Y63937D01*
X1904039Y64187D01*
X1904081Y64479D01*
X1903998Y64812D01*
X1903789Y65062D01*
X1903414Y65312D01*
G01X1903706Y67829D02*
Y68662D01*
X1904456D01*
X1904706Y68412D01*
X1904873Y68121D01*
X1904956Y67704D01*
X1904873Y67287D01*
X1904706Y66996D01*
X1904456Y66746D01*
X1904164Y66579D01*
X1903831Y66496D01*
X1903539D01*
X1903289Y66579D01*
X1902998Y66746D01*
X1902748Y66996D01*
X1902581Y67246D01*
X1902456Y67579D01*
Y67871D01*
X1902539Y68204D01*
X1902706Y68454D01*
G01X1903914Y69887D02*
X1903623Y70179D01*
X1903456Y70429D01*
X1903373Y70762D01*
X1903456Y71054D01*
X1903623Y71262D01*
X1903873Y71429D01*
X1904164Y71471D01*
X1904414Y71429D01*
X1904664Y71262D01*
X1904873Y71012D01*
X1904956Y70721D01*
X1904873Y70387D01*
X1904623Y70096D01*
X1904248Y69929D01*
X1903831Y69887D01*
X1903289Y69971D01*
X1902998Y70096D01*
X1902706Y70304D01*
X1902498Y70596D01*
X1902456Y70887D01*
X1902539Y71179D01*
X1902748Y71387D01*
G01X1953523Y69046D02*
X1953273Y69171D01*
X1952981Y69254D01*
X1952648D01*
X1952273Y69129D01*
X1951981Y68921D01*
X1951773Y68671D01*
X1951606Y68254D01*
X1951564Y67879D01*
X1951648Y67504D01*
X1951773Y67254D01*
X1952023Y67004D01*
X1952314Y66837D01*
X1952606Y66754D01*
X1952898D01*
X1953189Y66837D01*
X1953439Y66962D01*
X1953648Y67129D01*
G01X1955623Y66754D02*
X1955706Y67296D01*
X1955831Y67754D01*
X1955998Y68171D01*
X1956206Y68629D01*
X1956539Y69254D01*
X1954873D01*
G01X1959639Y66754D02*
X1957973D01*
Y69254D01*
X1959639D01*
G01X1958973Y68046D02*
X1957973D01*
G01X1961198Y67046D02*
X1961489Y66837D01*
X1961823Y66754D01*
X1962156Y66837D01*
X1962448Y67087D01*
X1962656Y67462D01*
X1962739Y67837D01*
Y68296D01*
X1962656Y68671D01*
X1962448Y69004D01*
X1962198Y69171D01*
X1961906Y69254D01*
X1961573Y69171D01*
X1961323Y69004D01*
X1961156Y68754D01*
X1961073Y68421D01*
X1961156Y68129D01*
X1961364Y67837D01*
X1961614Y67671D01*
X1961906Y67629D01*
X1962239Y67712D01*
X1962489Y67921D01*
X1962739Y68296D01*
G01X1931500Y82850D02*
X1931458Y82517D01*
X1931292Y82225D01*
X1931042Y81975D01*
X1930750Y81808D01*
X1930417Y81725D01*
X1930083D01*
X1929750Y81808D01*
X1929458Y81975D01*
X1929208Y82225D01*
X1929042Y82517D01*
X1929000Y82850D01*
X1929042Y83183D01*
X1929208Y83475D01*
X1929458Y83725D01*
X1929750Y83892D01*
X1930083Y83975D01*
X1930417D01*
X1930750Y83892D01*
X1931042Y83725D01*
X1931292Y83475D01*
X1931458Y83183D01*
X1931500Y82850D01*
G01X1930833Y83183D02*
X1931500Y83683D01*
G01Y85867D02*
X1930958Y85950D01*
X1930500Y86075D01*
X1930083Y86242D01*
X1929625Y86450D01*
X1929000Y86783D01*
Y85117D01*
G01X1931500Y89883D02*
Y88217D01*
X1929000D01*
Y89883D01*
G01X1930208Y89217D02*
Y88217D01*
G01X1931500Y92067D02*
X1930958Y92150D01*
X1930500Y92275D01*
X1930083Y92442D01*
X1929625Y92650D01*
X1929000Y92983D01*
Y91317D01*
G01X1932816Y79936D02*
Y93322D01*
G01X1946202Y79936D02*
Y93322D01*
G01X1936572Y131600D02*
X1937530Y128500D01*
X1938488Y131600D01*
G01X1940860Y130050D02*
X1941627D01*
Y129120D01*
X1941397Y128810D01*
X1941128Y128603D01*
X1940745Y128500D01*
X1940362Y128603D01*
X1940093Y128810D01*
X1939863Y129120D01*
X1939710Y129482D01*
X1939633Y129895D01*
Y130257D01*
X1939710Y130567D01*
X1939863Y130928D01*
X1940093Y131238D01*
X1940323Y131445D01*
X1940630Y131600D01*
X1940898D01*
X1941205Y131497D01*
X1941435Y131290D01*
G01X1942772Y128500D02*
X1943730Y131600D01*
X1944688Y128500D01*
G01X1944343Y129585D02*
X1943117D01*
G01X1950773Y131342D02*
X1950543Y131497D01*
X1950275Y131600D01*
X1949968D01*
X1949623Y131445D01*
X1949355Y131187D01*
X1949163Y130877D01*
X1949010Y130360D01*
X1948972Y129895D01*
X1949048Y129430D01*
X1949163Y129120D01*
X1949393Y128810D01*
X1949662Y128603D01*
X1949930Y128500D01*
X1950198D01*
X1950467Y128603D01*
X1950697Y128758D01*
X1950888Y128965D01*
G01X1953030Y128500D02*
X1952723Y128552D01*
X1952455Y128758D01*
X1952225Y129068D01*
X1952072Y129430D01*
X1951995Y129843D01*
Y130257D01*
X1952072Y130670D01*
X1952225Y131032D01*
X1952455Y131342D01*
X1952723Y131548D01*
X1953030Y131600D01*
X1953337Y131548D01*
X1953605Y131342D01*
X1953835Y131032D01*
X1953988Y130670D01*
X1954065Y130257D01*
Y129843D01*
X1953988Y129430D01*
X1953835Y129068D01*
X1953605Y128758D01*
X1953337Y128552D01*
X1953030Y128500D01*
G01X1955248D02*
Y131600D01*
X1957012Y128500D01*
Y131600D01*
G01X1958348Y128500D02*
Y131600D01*
X1960112Y128500D01*
Y131600D01*
G01X1914333Y143000D02*
Y136000D01*
X1919667D01*
G01X1901400Y145699D02*
X1902300D01*
G01X1929700Y131500D02*
Y140400D01*
X1927500D01*
Y143800D01*
X1917000D01*
G01X1928600Y131000D02*
X1921380D01*
G01X1908699Y106000D02*
Y114461D01*
G01X1920600Y124836D02*
Y120901D01*
X1920599Y120900D01*
X1908701D01*
X1908700Y120899D01*
Y120000D01*
G01X1938227Y113080D02*
X1935727D01*
Y114121D01*
X1935852Y114455D01*
X1936019Y114663D01*
X1936352Y114746D01*
X1936685Y114663D01*
X1936894Y114413D01*
X1937019Y114121D01*
Y113080D01*
G01Y114121D02*
X1938227Y114746D01*
G01X1937935Y116305D02*
X1938144Y116596D01*
X1938227Y116930D01*
X1938144Y117263D01*
X1937894Y117555D01*
X1937519Y117763D01*
X1937144Y117846D01*
X1936685D01*
X1936310Y117763D01*
X1935977Y117555D01*
X1935810Y117305D01*
X1935727Y117013D01*
X1935810Y116680D01*
X1935977Y116430D01*
X1936227Y116263D01*
X1936560Y116180D01*
X1936852Y116263D01*
X1937144Y116471D01*
X1937310Y116721D01*
X1937352Y117013D01*
X1937269Y117346D01*
X1937060Y117596D01*
X1936685Y117846D01*
G01X1938227Y119321D02*
X1935727D01*
Y120905D01*
G01X1936935Y120321D02*
Y119321D01*
G01X1936144Y122421D02*
X1935894Y122671D01*
X1935769Y122963D01*
X1935727Y123296D01*
X1935810Y123713D01*
X1936019Y124005D01*
X1936269Y124088D01*
X1936519Y124046D01*
X1936727Y123880D01*
X1937144Y123046D01*
X1937435Y122671D01*
X1937852Y122421D01*
X1938227Y122338D01*
Y124088D01*
G01X1937852Y125396D02*
X1938060Y125646D01*
X1938185Y125938D01*
X1938227Y126313D01*
X1938144Y126688D01*
X1937977Y126980D01*
X1937685Y127188D01*
X1937352Y127230D01*
X1937019Y127146D01*
X1936810Y126938D01*
X1936644Y126646D01*
X1936602Y126355D01*
X1936644Y126063D01*
X1936810Y125688D01*
X1935727Y125813D01*
Y126938D01*
G01X1939217Y148900D02*
Y151400D01*
X1940258D01*
X1940592Y151275D01*
X1940800Y151108D01*
X1940883Y150775D01*
X1940800Y150442D01*
X1940550Y150233D01*
X1940258Y150108D01*
X1939217D01*
G01X1940258D02*
X1940883Y148900D01*
G01X1942442Y149192D02*
X1942733Y148983D01*
X1943067Y148900D01*
X1943400Y148983D01*
X1943692Y149233D01*
X1943900Y149608D01*
X1943983Y149983D01*
Y150442D01*
X1943900Y150817D01*
X1943692Y151150D01*
X1943442Y151317D01*
X1943150Y151400D01*
X1942817Y151317D01*
X1942567Y151150D01*
X1942400Y150900D01*
X1942317Y150567D01*
X1942400Y150275D01*
X1942608Y149983D01*
X1942858Y149817D01*
X1943150Y149775D01*
X1943483Y149858D01*
X1943733Y150067D01*
X1943983Y150442D01*
G01X1945458Y148900D02*
Y151400D01*
X1947042D01*
G01X1946458Y150192D02*
X1945458D01*
G01X1948433Y149275D02*
X1948683Y149067D01*
X1948975Y148942D01*
X1949350Y148900D01*
X1949725Y148983D01*
X1950017Y149150D01*
X1950225Y149442D01*
X1950267Y149775D01*
X1950183Y150108D01*
X1949975Y150317D01*
X1949683Y150483D01*
X1949392Y150525D01*
X1949100Y150483D01*
X1948725Y150317D01*
X1948850Y151400D01*
X1949975D01*
G01X1939317Y153500D02*
Y156000D01*
X1940358D01*
X1940692Y155875D01*
X1940900Y155708D01*
X1940983Y155375D01*
X1940900Y155042D01*
X1940650Y154833D01*
X1940358Y154708D01*
X1939317D01*
G01X1940358D02*
X1940983Y153500D01*
G01X1942542Y153792D02*
X1942833Y153583D01*
X1943167Y153500D01*
X1943500Y153583D01*
X1943792Y153833D01*
X1944000Y154208D01*
X1944083Y154583D01*
Y155042D01*
X1944000Y155417D01*
X1943792Y155750D01*
X1943542Y155917D01*
X1943250Y156000D01*
X1942917Y155917D01*
X1942667Y155750D01*
X1942500Y155500D01*
X1942417Y155167D01*
X1942500Y154875D01*
X1942708Y154583D01*
X1942958Y154417D01*
X1943250Y154375D01*
X1943583Y154458D01*
X1943833Y154667D01*
X1944083Y155042D01*
G01X1945558Y153500D02*
Y156000D01*
X1947142D01*
G01X1946558Y154792D02*
X1945558D01*
G01X1949450Y153500D02*
Y156000D01*
X1948950Y155500D01*
G01Y153500D02*
X1949950D01*
G01X1906831Y144821D02*
Y147321D01*
X1907872D01*
X1908206Y147196D01*
X1908414Y147029D01*
X1908497Y146696D01*
X1908414Y146363D01*
X1908164Y146154D01*
X1907872Y146029D01*
X1906831D01*
G01X1907872D02*
X1908497Y144821D01*
G01X1909972Y146904D02*
X1910222Y147154D01*
X1910514Y147279D01*
X1910847Y147321D01*
X1911264Y147238D01*
X1911556Y147029D01*
X1911639Y146779D01*
X1911597Y146529D01*
X1911431Y146321D01*
X1910597Y145904D01*
X1910222Y145613D01*
X1909972Y145196D01*
X1909889Y144821D01*
X1911639D01*
G01X1912947Y145196D02*
X1913197Y144988D01*
X1913489Y144863D01*
X1913864Y144821D01*
X1914239Y144904D01*
X1914531Y145071D01*
X1914739Y145363D01*
X1914781Y145696D01*
X1914697Y146029D01*
X1914489Y146238D01*
X1914197Y146404D01*
X1913906Y146446D01*
X1913614Y146404D01*
X1913239Y146238D01*
X1913364Y147321D01*
X1914489D01*
G01X1915714D02*
X1916297Y144821D01*
X1916964Y147321D01*
X1917631Y144821D01*
X1918214Y147321D01*
G01X1920064Y144821D02*
Y147321D01*
X1919564Y146821D01*
G01Y144821D02*
X1920564D01*
G01X1922372Y146904D02*
X1922622Y147154D01*
X1922914Y147279D01*
X1923247Y147321D01*
X1923664Y147238D01*
X1923956Y147029D01*
X1924039Y146779D01*
X1923997Y146529D01*
X1923831Y146321D01*
X1922997Y145904D01*
X1922622Y145613D01*
X1922372Y145196D01*
X1922289Y144821D01*
X1924039D01*
G01X1925472Y145863D02*
X1925764Y146154D01*
X1926014Y146321D01*
X1926347Y146404D01*
X1926639Y146321D01*
X1926847Y146154D01*
X1927014Y145904D01*
X1927056Y145613D01*
X1927014Y145363D01*
X1926847Y145113D01*
X1926597Y144904D01*
X1926306Y144821D01*
X1925972Y144904D01*
X1925681Y145154D01*
X1925514Y145529D01*
X1925472Y145946D01*
X1925556Y146488D01*
X1925681Y146779D01*
X1925889Y147071D01*
X1926181Y147279D01*
X1926472Y147321D01*
X1926764Y147238D01*
X1926972Y147029D01*
G01X1933800Y116867D02*
X1931300D01*
Y117908D01*
X1931425Y118242D01*
X1931592Y118450D01*
X1931925Y118533D01*
X1932258Y118450D01*
X1932467Y118200D01*
X1932592Y117908D01*
Y116867D01*
G01Y117908D02*
X1933800Y118533D01*
G01X1933508Y120092D02*
X1933717Y120383D01*
X1933800Y120717D01*
X1933717Y121050D01*
X1933467Y121342D01*
X1933092Y121550D01*
X1932717Y121633D01*
X1932258D01*
X1931883Y121550D01*
X1931550Y121342D01*
X1931383Y121092D01*
X1931300Y120800D01*
X1931383Y120467D01*
X1931550Y120217D01*
X1931800Y120050D01*
X1932133Y119967D01*
X1932425Y120050D01*
X1932717Y120258D01*
X1932883Y120508D01*
X1932925Y120800D01*
X1932842Y121133D01*
X1932633Y121383D01*
X1932258Y121633D01*
G01X1933800Y123108D02*
X1931300D01*
Y124692D01*
G01X1932508Y124108D02*
Y123108D01*
G01X1932758Y126208D02*
X1932467Y126500D01*
X1932300Y126750D01*
X1932217Y127083D01*
X1932300Y127375D01*
X1932467Y127583D01*
X1932717Y127750D01*
X1933008Y127792D01*
X1933258Y127750D01*
X1933508Y127583D01*
X1933717Y127333D01*
X1933800Y127042D01*
X1933717Y126708D01*
X1933467Y126417D01*
X1933092Y126250D01*
X1932675Y126208D01*
X1932133Y126292D01*
X1931842Y126417D01*
X1931550Y126625D01*
X1931342Y126917D01*
X1931300Y127208D01*
X1931383Y127500D01*
X1931592Y127708D01*
G01X1933800Y130600D02*
X1931300D01*
X1933092Y129058D01*
Y131142D01*
G01X1927588Y109786D02*
Y112286D01*
X1928629D01*
X1928963Y112161D01*
X1929171Y111994D01*
X1929254Y111661D01*
X1929171Y111328D01*
X1928921Y111119D01*
X1928629Y110994D01*
X1927588D01*
G01X1928629D02*
X1929254Y109786D01*
G01X1930813Y110078D02*
X1931104Y109869D01*
X1931438Y109786D01*
X1931771Y109869D01*
X1932063Y110119D01*
X1932271Y110494D01*
X1932354Y110869D01*
Y111328D01*
X1932271Y111703D01*
X1932063Y112036D01*
X1931813Y112203D01*
X1931521Y112286D01*
X1931188Y112203D01*
X1930938Y112036D01*
X1930771Y111786D01*
X1930688Y111453D01*
X1930771Y111161D01*
X1930979Y110869D01*
X1931229Y110703D01*
X1931521Y110661D01*
X1931854Y110744D01*
X1932104Y110953D01*
X1932354Y111328D01*
G01X1933829Y109786D02*
Y112286D01*
X1935413D01*
G01X1934829Y111078D02*
X1933829D01*
G01X1936929Y110828D02*
X1937221Y111119D01*
X1937471Y111286D01*
X1937804Y111369D01*
X1938096Y111286D01*
X1938304Y111119D01*
X1938471Y110869D01*
X1938513Y110578D01*
X1938471Y110328D01*
X1938304Y110078D01*
X1938054Y109869D01*
X1937763Y109786D01*
X1937429Y109869D01*
X1937138Y110119D01*
X1936971Y110494D01*
X1936929Y110911D01*
X1937013Y111453D01*
X1937138Y111744D01*
X1937346Y112036D01*
X1937638Y112244D01*
X1937929Y112286D01*
X1938221Y112203D01*
X1938429Y111994D01*
G01X1939904Y110286D02*
X1940154Y109994D01*
X1940488Y109828D01*
X1940863Y109786D01*
X1941196Y109828D01*
X1941529Y110036D01*
X1941738Y110286D01*
X1941779Y110536D01*
X1941696Y110828D01*
X1941404Y111036D01*
X1941113Y111119D01*
X1940738D01*
G01X1941113D02*
X1941363Y111244D01*
X1941571Y111453D01*
X1941654Y111703D01*
X1941571Y111953D01*
X1941363Y112161D01*
X1940988Y112286D01*
X1940613Y112244D01*
X1940238Y112078D01*
G01X1922875Y106516D02*
Y109016D01*
X1923916D01*
X1924250Y108891D01*
X1924458Y108724D01*
X1924541Y108391D01*
X1924458Y108058D01*
X1924208Y107849D01*
X1923916Y107724D01*
X1922875D01*
G01X1923916D02*
X1924541Y106516D01*
G01X1926100Y106808D02*
X1926391Y106599D01*
X1926725Y106516D01*
X1927058Y106599D01*
X1927350Y106849D01*
X1927558Y107224D01*
X1927641Y107599D01*
Y108058D01*
X1927558Y108433D01*
X1927350Y108766D01*
X1927100Y108933D01*
X1926808Y109016D01*
X1926475Y108933D01*
X1926225Y108766D01*
X1926058Y108516D01*
X1925975Y108183D01*
X1926058Y107891D01*
X1926266Y107599D01*
X1926516Y107433D01*
X1926808Y107391D01*
X1927141Y107474D01*
X1927391Y107683D01*
X1927641Y108058D01*
G01X1929116Y106516D02*
Y109016D01*
X1930700D01*
G01X1930116Y107808D02*
X1929116D01*
G01X1932216Y108599D02*
X1932466Y108849D01*
X1932758Y108974D01*
X1933091Y109016D01*
X1933508Y108933D01*
X1933800Y108724D01*
X1933883Y108474D01*
X1933841Y108224D01*
X1933675Y108016D01*
X1932841Y107599D01*
X1932466Y107308D01*
X1932216Y106891D01*
X1932133Y106516D01*
X1933883D01*
G01X1936608D02*
Y109016D01*
X1935066Y107224D01*
X1937150D01*
G01X1940586Y115321D02*
X1940461Y115071D01*
X1940378Y114779D01*
Y114446D01*
X1940503Y114071D01*
X1940711Y113779D01*
X1940961Y113571D01*
X1941378Y113404D01*
X1941753Y113362D01*
X1942128Y113446D01*
X1942378Y113571D01*
X1942628Y113821D01*
X1942795Y114112D01*
X1942878Y114404D01*
Y114696D01*
X1942795Y114987D01*
X1942670Y115237D01*
X1942503Y115446D01*
G01X1942878Y117504D02*
X1942836Y117796D01*
X1942711Y118129D01*
X1942503Y118337D01*
X1942211Y118421D01*
X1941920Y118337D01*
X1941670Y118087D01*
X1941545Y117712D01*
Y117296D01*
X1941461Y117046D01*
X1941253Y116837D01*
X1940961Y116754D01*
X1940670Y116879D01*
X1940461Y117171D01*
X1940378Y117504D01*
X1940461Y117837D01*
X1940670Y118129D01*
X1940961Y118254D01*
X1941253Y118171D01*
X1941461Y117962D01*
X1941545Y117712D01*
Y117296D01*
X1941670Y116921D01*
X1941920Y116671D01*
X1942211Y116587D01*
X1942503Y116671D01*
X1942711Y116879D01*
X1942836Y117212D01*
X1942878Y117504D01*
G01Y121437D02*
Y119771D01*
X1940378D01*
Y121437D01*
G01X1941586Y120771D02*
Y119771D01*
G01X1942878Y123704D02*
X1940378D01*
X1940878Y123204D01*
G01X1942878D02*
Y124204D01*
G01X1942586Y126096D02*
X1942795Y126387D01*
X1942878Y126721D01*
X1942795Y127054D01*
X1942545Y127346D01*
X1942170Y127554D01*
X1941795Y127637D01*
X1941336D01*
X1940961Y127554D01*
X1940628Y127346D01*
X1940461Y127096D01*
X1940378Y126804D01*
X1940461Y126471D01*
X1940628Y126221D01*
X1940878Y126054D01*
X1941211Y125971D01*
X1941503Y126054D01*
X1941795Y126262D01*
X1941961Y126512D01*
X1942003Y126804D01*
X1941920Y127137D01*
X1941711Y127387D01*
X1941336Y127637D01*
G01X1953853Y108587D02*
X1952187D01*
Y111087D01*
X1953853D01*
G01X1953187Y109879D02*
X1952187D01*
G01X1955203Y111087D02*
Y109295D01*
X1955370Y108920D01*
X1955703Y108670D01*
X1956120Y108587D01*
X1956537Y108670D01*
X1956870Y108920D01*
X1957037Y109295D01*
Y111087D01*
G01X1959137Y108587D02*
X1959220Y109129D01*
X1959345Y109587D01*
X1959512Y110004D01*
X1959720Y110462D01*
X1960053Y111087D01*
X1958387D01*
G01X1963153Y108587D02*
X1961487D01*
Y111087D01*
X1963153D01*
G01X1962487Y109879D02*
X1961487D01*
G01X1965420Y108587D02*
Y111087D01*
X1964920Y110587D01*
G01Y108587D02*
X1965920D01*
G01X1938470Y135200D02*
X1938220Y135325D01*
X1937928Y135408D01*
X1937595D01*
X1937220Y135283D01*
X1936928Y135075D01*
X1936720Y134825D01*
X1936553Y134408D01*
X1936511Y134033D01*
X1936595Y133658D01*
X1936720Y133408D01*
X1936970Y133158D01*
X1937261Y132991D01*
X1937553Y132908D01*
X1937845D01*
X1938136Y132991D01*
X1938386Y133116D01*
X1938595Y133283D01*
G01X1939820Y132908D02*
Y135408D01*
X1940861D01*
X1941195Y135283D01*
X1941403Y135116D01*
X1941486Y134783D01*
X1941403Y134450D01*
X1941153Y134241D01*
X1940861Y134116D01*
X1939820D01*
G01X1940861D02*
X1941486Y132908D01*
G01X1942961Y134991D02*
X1943211Y135241D01*
X1943503Y135366D01*
X1943836Y135408D01*
X1944253Y135325D01*
X1944545Y135116D01*
X1944628Y134866D01*
X1944586Y134616D01*
X1944420Y134408D01*
X1943586Y133991D01*
X1943211Y133700D01*
X1942961Y133283D01*
X1942878Y132908D01*
X1944628D01*
G01X1945936Y133283D02*
X1946186Y133075D01*
X1946478Y132950D01*
X1946853Y132908D01*
X1947228Y132991D01*
X1947520Y133158D01*
X1947728Y133450D01*
X1947770Y133783D01*
X1947686Y134116D01*
X1947478Y134325D01*
X1947186Y134491D01*
X1946895Y134533D01*
X1946603Y134491D01*
X1946228Y134325D01*
X1946353Y135408D01*
X1947478D01*
G01X1948703D02*
X1949286Y132908D01*
X1949953Y135408D01*
X1950620Y132908D01*
X1951203Y135408D01*
G01X1953053Y132908D02*
Y135408D01*
X1952553Y134908D01*
G01Y132908D02*
X1953553D01*
G01X1958992Y133358D02*
X1959200Y133108D01*
X1959450Y132941D01*
X1959742Y132858D01*
X1960075Y132941D01*
X1960325Y133108D01*
X1960575Y133358D01*
X1960658Y133691D01*
Y135358D01*
G01X1962133Y134941D02*
X1962383Y135191D01*
X1962675Y135316D01*
X1963008Y135358D01*
X1963425Y135275D01*
X1963717Y135066D01*
X1963800Y134816D01*
X1963758Y134566D01*
X1963592Y134358D01*
X1962758Y133941D01*
X1962383Y133650D01*
X1962133Y133233D01*
X1962050Y132858D01*
X1963800D01*
G01X1965108Y133233D02*
X1965358Y133025D01*
X1965650Y132900D01*
X1966025Y132858D01*
X1966400Y132941D01*
X1966692Y133108D01*
X1966900Y133400D01*
X1966942Y133733D01*
X1966858Y134066D01*
X1966650Y134275D01*
X1966358Y134441D01*
X1966067Y134483D01*
X1965775Y134441D01*
X1965400Y134275D01*
X1965525Y135358D01*
X1966650D01*
G01X1967875D02*
X1968458Y132858D01*
X1969125Y135358D01*
X1969792Y132858D01*
X1970375Y135358D01*
G01X1972225Y132858D02*
Y135358D01*
X1971725Y134858D01*
G01Y132858D02*
X1972725D01*
G01X1975337Y136445D02*
X1955837D01*
Y141945D01*
X1951437D01*
Y193645D01*
X1955837D01*
Y199145D01*
X1975337D01*
Y136445D01*
G01X1924215Y156436D02*
Y155385D01*
X1923164D01*
G01X1937439Y197072D02*
Y188752D01*
X1943550D01*
Y180149D01*
X1941905D01*
Y160078D01*
X1941904Y160077D01*
X1928133D01*
X1928132Y160078D01*
Y166300D01*
G01Y168000D02*
Y168539D01*
X1929143D01*
Y179456D01*
X1927498D01*
Y194462D01*
X1917838D01*
Y196131D01*
X1916404D01*
G01X1900900Y206450D02*
X1901386D01*
Y202665D01*
X1907473D01*
Y197071D01*
X1909142D01*
G01X1920941Y219541D02*
X1922289D01*
Y212206D01*
X1924329D01*
G01X1931500Y212469D02*
X1934855D01*
Y203752D01*
G01X1911269Y207963D02*
Y210463D01*
X1912310D01*
X1912644Y210338D01*
X1912852Y210171D01*
X1912935Y209838D01*
X1912852Y209505D01*
X1912602Y209296D01*
X1912310Y209171D01*
X1911269D01*
G01X1912310D02*
X1912935Y207963D01*
G01X1914410Y210046D02*
X1914660Y210296D01*
X1914952Y210421D01*
X1915285Y210463D01*
X1915702Y210380D01*
X1915994Y210171D01*
X1916077Y209921D01*
X1916035Y209671D01*
X1915869Y209463D01*
X1915035Y209046D01*
X1914660Y208755D01*
X1914410Y208338D01*
X1914327Y207963D01*
X1916077D01*
G01X1917385Y208338D02*
X1917635Y208130D01*
X1917927Y208005D01*
X1918302Y207963D01*
X1918677Y208046D01*
X1918969Y208213D01*
X1919177Y208505D01*
X1919219Y208838D01*
X1919135Y209171D01*
X1918927Y209380D01*
X1918635Y209546D01*
X1918344Y209588D01*
X1918052Y209546D01*
X1917677Y209380D01*
X1917802Y210463D01*
X1918927D01*
G01X1920152D02*
X1920735Y207963D01*
X1921402Y210463D01*
X1922069Y207963D01*
X1922652Y210463D01*
G01X1924502Y207963D02*
Y210463D01*
X1924002Y209963D01*
G01Y207963D02*
X1925002D01*
G01X1926685Y208463D02*
X1926935Y208171D01*
X1927269Y208005D01*
X1927644Y207963D01*
X1927977Y208005D01*
X1928310Y208213D01*
X1928519Y208463D01*
X1928560Y208713D01*
X1928477Y209005D01*
X1928185Y209213D01*
X1927894Y209296D01*
X1927519D01*
G01X1927894D02*
X1928144Y209421D01*
X1928352Y209630D01*
X1928435Y209880D01*
X1928352Y210130D01*
X1928144Y210338D01*
X1927769Y210463D01*
X1927394Y210421D01*
X1927019Y210255D01*
G01X1929994Y208255D02*
X1930285Y208046D01*
X1930619Y207963D01*
X1930952Y208046D01*
X1931244Y208296D01*
X1931452Y208671D01*
X1931535Y209046D01*
Y209505D01*
X1931452Y209880D01*
X1931244Y210213D01*
X1930994Y210380D01*
X1930702Y210463D01*
X1930369Y210380D01*
X1930119Y210213D01*
X1929952Y209963D01*
X1929869Y209630D01*
X1929952Y209338D01*
X1930160Y209046D01*
X1930410Y208880D01*
X1930702Y208838D01*
X1931035Y208921D01*
X1931285Y209130D01*
X1931535Y209505D01*
G01X1898405Y212458D02*
Y214958D01*
X1899446D01*
X1899780Y214833D01*
X1899988Y214666D01*
X1900071Y214333D01*
X1899988Y214000D01*
X1899738Y213791D01*
X1899446Y213666D01*
X1898405D01*
G01X1899446D02*
X1900071Y212458D01*
G01X1901630Y212750D02*
X1901921Y212541D01*
X1902255Y212458D01*
X1902588Y212541D01*
X1902880Y212791D01*
X1903088Y213166D01*
X1903171Y213541D01*
Y214000D01*
X1903088Y214375D01*
X1902880Y214708D01*
X1902630Y214875D01*
X1902338Y214958D01*
X1902005Y214875D01*
X1901755Y214708D01*
X1901588Y214458D01*
X1901505Y214125D01*
X1901588Y213833D01*
X1901796Y213541D01*
X1902046Y213375D01*
X1902338Y213333D01*
X1902671Y213416D01*
X1902921Y213625D01*
X1903171Y214000D01*
G01X1906271Y212458D02*
X1904605D01*
Y214958D01*
X1906271D01*
G01X1905605Y213750D02*
X1904605D01*
G01X1908538Y212458D02*
Y214958D01*
X1908038Y214458D01*
G01Y212458D02*
X1909038D01*
G01X1910930Y212750D02*
X1911221Y212541D01*
X1911555Y212458D01*
X1911888Y212541D01*
X1912180Y212791D01*
X1912388Y213166D01*
X1912471Y213541D01*
Y214000D01*
X1912388Y214375D01*
X1912180Y214708D01*
X1911930Y214875D01*
X1911638Y214958D01*
X1911305Y214875D01*
X1911055Y214708D01*
X1910888Y214458D01*
X1910805Y214125D01*
X1910888Y213833D01*
X1911096Y213541D01*
X1911346Y213375D01*
X1911638Y213333D01*
X1911971Y213416D01*
X1912221Y213625D01*
X1912471Y214000D01*
G01X1899409Y215858D02*
Y218358D01*
X1900450D01*
X1900784Y218233D01*
X1900992Y218066D01*
X1901075Y217733D01*
X1900992Y217400D01*
X1900742Y217191D01*
X1900450Y217066D01*
X1899409D01*
G01X1900450D02*
X1901075Y215858D01*
G01X1902634Y216150D02*
X1902925Y215941D01*
X1903259Y215858D01*
X1903592Y215941D01*
X1903884Y216191D01*
X1904092Y216566D01*
X1904175Y216941D01*
Y217400D01*
X1904092Y217775D01*
X1903884Y218108D01*
X1903634Y218275D01*
X1903342Y218358D01*
X1903009Y218275D01*
X1902759Y218108D01*
X1902592Y217858D01*
X1902509Y217525D01*
X1902592Y217233D01*
X1902800Y216941D01*
X1903050Y216775D01*
X1903342Y216733D01*
X1903675Y216816D01*
X1903925Y217025D01*
X1904175Y217400D01*
G01X1907275Y215858D02*
X1905609D01*
Y218358D01*
X1907275D01*
G01X1906609Y217150D02*
X1905609D01*
G01X1909542Y215858D02*
Y218358D01*
X1909042Y217858D01*
G01Y215858D02*
X1910042D01*
G01X1912559D02*
X1912642Y216400D01*
X1912767Y216858D01*
X1912934Y217275D01*
X1913142Y217733D01*
X1913475Y218358D01*
X1911809D01*
G01X1918582Y206636D02*
X1918332Y206761D01*
X1918040Y206844D01*
X1917707D01*
X1917332Y206719D01*
X1917040Y206511D01*
X1916832Y206261D01*
X1916665Y205844D01*
X1916623Y205469D01*
X1916707Y205094D01*
X1916832Y204844D01*
X1917082Y204594D01*
X1917373Y204427D01*
X1917665Y204344D01*
X1917957D01*
X1918248Y204427D01*
X1918498Y204552D01*
X1918707Y204719D01*
G01X1919973Y206427D02*
X1920223Y206677D01*
X1920515Y206802D01*
X1920848Y206844D01*
X1921265Y206761D01*
X1921557Y206552D01*
X1921640Y206302D01*
X1921598Y206052D01*
X1921432Y205844D01*
X1920598Y205427D01*
X1920223Y205136D01*
X1919973Y204719D01*
X1919890Y204344D01*
X1921640D01*
G01X1922948Y204719D02*
X1923198Y204511D01*
X1923490Y204386D01*
X1923865Y204344D01*
X1924240Y204427D01*
X1924532Y204594D01*
X1924740Y204886D01*
X1924782Y205219D01*
X1924698Y205552D01*
X1924490Y205761D01*
X1924198Y205927D01*
X1923907Y205969D01*
X1923615Y205927D01*
X1923240Y205761D01*
X1923365Y206844D01*
X1924490D01*
G01X1925715D02*
X1926298Y204344D01*
X1926965Y206844D01*
X1927632Y204344D01*
X1928215Y206844D01*
G01X1930065Y204344D02*
X1930357Y204386D01*
X1930690Y204511D01*
X1930898Y204719D01*
X1930982Y205011D01*
X1930898Y205302D01*
X1930648Y205552D01*
X1930273Y205677D01*
X1929857D01*
X1929607Y205761D01*
X1929398Y205969D01*
X1929315Y206261D01*
X1929440Y206552D01*
X1929732Y206761D01*
X1930065Y206844D01*
X1930398Y206761D01*
X1930690Y206552D01*
X1930815Y206261D01*
X1930732Y205969D01*
X1930523Y205761D01*
X1930273Y205677D01*
X1929857D01*
X1929482Y205552D01*
X1929232Y205302D01*
X1929148Y205011D01*
X1929232Y204719D01*
X1929440Y204511D01*
X1929773Y204386D01*
X1930065Y204344D01*
G01X1932373Y206427D02*
X1932623Y206677D01*
X1932915Y206802D01*
X1933248Y206844D01*
X1933665Y206761D01*
X1933957Y206552D01*
X1934040Y206302D01*
X1933998Y206052D01*
X1933832Y205844D01*
X1932998Y205427D01*
X1932623Y205136D01*
X1932373Y204719D01*
X1932290Y204344D01*
X1934040D01*
G01X1935813Y199614D02*
X1935688Y199364D01*
X1935605Y199072D01*
Y198739D01*
X1935730Y198364D01*
X1935938Y198072D01*
X1936188Y197864D01*
X1936605Y197697D01*
X1936980Y197655D01*
X1937355Y197739D01*
X1937605Y197864D01*
X1937855Y198114D01*
X1938022Y198405D01*
X1938105Y198697D01*
Y198989D01*
X1938022Y199280D01*
X1937897Y199530D01*
X1937730Y199739D01*
G01X1937605Y200880D02*
X1937897Y201130D01*
X1938063Y201464D01*
X1938105Y201839D01*
X1938063Y202172D01*
X1937855Y202505D01*
X1937605Y202714D01*
X1937355Y202755D01*
X1937063Y202672D01*
X1936855Y202380D01*
X1936772Y202089D01*
Y201714D01*
G01Y202089D02*
X1936647Y202339D01*
X1936438Y202547D01*
X1936188Y202630D01*
X1935938Y202547D01*
X1935730Y202339D01*
X1935605Y201964D01*
X1935647Y201589D01*
X1935813Y201214D01*
G01X1935605Y204897D02*
X1935688Y204564D01*
X1935897Y204314D01*
X1936147Y204147D01*
X1936480Y204022D01*
X1936855Y203980D01*
X1937230Y204022D01*
X1937563Y204147D01*
X1937813Y204314D01*
X1938022Y204564D01*
X1938105Y204897D01*
X1938022Y205230D01*
X1937813Y205480D01*
X1937563Y205647D01*
X1937230Y205772D01*
X1936855Y205814D01*
X1936480Y205772D01*
X1936147Y205647D01*
X1935897Y205480D01*
X1935688Y205230D01*
X1935605Y204897D01*
G01Y206747D02*
X1938105Y207330D01*
X1935605Y207997D01*
X1938105Y208664D01*
X1935605Y209247D01*
G01X1938105Y211597D02*
X1935605D01*
X1937397Y210055D01*
Y212139D01*
G01X1941508Y200117D02*
X1941383Y199867D01*
X1941300Y199575D01*
Y199242D01*
X1941425Y198867D01*
X1941633Y198575D01*
X1941883Y198367D01*
X1942300Y198200D01*
X1942675Y198158D01*
X1943050Y198242D01*
X1943300Y198367D01*
X1943550Y198617D01*
X1943717Y198908D01*
X1943800Y199200D01*
Y199492D01*
X1943717Y199783D01*
X1943592Y200033D01*
X1943425Y200242D01*
G01X1943300Y201383D02*
X1943592Y201633D01*
X1943758Y201967D01*
X1943800Y202342D01*
X1943758Y202675D01*
X1943550Y203008D01*
X1943300Y203217D01*
X1943050Y203258D01*
X1942758Y203175D01*
X1942550Y202883D01*
X1942467Y202592D01*
Y202217D01*
G01Y202592D02*
X1942342Y202842D01*
X1942133Y203050D01*
X1941883Y203133D01*
X1941633Y203050D01*
X1941425Y202842D01*
X1941300Y202467D01*
X1941342Y202092D01*
X1941508Y201717D01*
G01X1941300Y205400D02*
X1941383Y205067D01*
X1941592Y204817D01*
X1941842Y204650D01*
X1942175Y204525D01*
X1942550Y204483D01*
X1942925Y204525D01*
X1943258Y204650D01*
X1943508Y204817D01*
X1943717Y205067D01*
X1943800Y205400D01*
X1943717Y205733D01*
X1943508Y205983D01*
X1943258Y206150D01*
X1942925Y206275D01*
X1942550Y206317D01*
X1942175Y206275D01*
X1941842Y206150D01*
X1941592Y205983D01*
X1941383Y205733D01*
X1941300Y205400D01*
G01Y207250D02*
X1943800Y207833D01*
X1941300Y208500D01*
X1943800Y209167D01*
X1941300Y209750D01*
G01X1942758Y210808D02*
X1942467Y211100D01*
X1942300Y211350D01*
X1942217Y211683D01*
X1942300Y211975D01*
X1942467Y212183D01*
X1942717Y212350D01*
X1943008Y212392D01*
X1943258Y212350D01*
X1943508Y212183D01*
X1943717Y211933D01*
X1943800Y211642D01*
X1943717Y211308D01*
X1943467Y211017D01*
X1943092Y210850D01*
X1942675Y210808D01*
X1942133Y210892D01*
X1941842Y211017D01*
X1941550Y211225D01*
X1941342Y211517D01*
X1941300Y211808D01*
X1941383Y212100D01*
X1941592Y212308D01*
G01X1950267Y200600D02*
X1950475Y200350D01*
X1950725Y200183D01*
X1951017Y200100D01*
X1951350Y200183D01*
X1951600Y200350D01*
X1951850Y200600D01*
X1951933Y200933D01*
Y202600D01*
G01X1953283Y200600D02*
X1953533Y200308D01*
X1953867Y200142D01*
X1954242Y200100D01*
X1954575Y200142D01*
X1954908Y200350D01*
X1955117Y200600D01*
X1955158Y200850D01*
X1955075Y201142D01*
X1954783Y201350D01*
X1954492Y201433D01*
X1954117D01*
G01X1954492D02*
X1954742Y201558D01*
X1954950Y201767D01*
X1955033Y202017D01*
X1954950Y202267D01*
X1954742Y202475D01*
X1954367Y202600D01*
X1953992Y202558D01*
X1953617Y202392D01*
G01X1957300Y202600D02*
X1956967Y202517D01*
X1956717Y202308D01*
X1956550Y202058D01*
X1956425Y201725D01*
X1956383Y201350D01*
X1956425Y200975D01*
X1956550Y200642D01*
X1956717Y200392D01*
X1956967Y200183D01*
X1957300Y200100D01*
X1957633Y200183D01*
X1957883Y200392D01*
X1958050Y200642D01*
X1958175Y200975D01*
X1958217Y201350D01*
X1958175Y201725D01*
X1958050Y202058D01*
X1957883Y202308D01*
X1957633Y202517D01*
X1957300Y202600D01*
G01X1959150D02*
X1959733Y200100D01*
X1960400Y202600D01*
X1961067Y200100D01*
X1961650Y202600D01*
G01X1963500Y200100D02*
Y202600D01*
X1963000Y202100D01*
G01Y200100D02*
X1964000D01*
G01X1985890Y245824D02*
X1946590D01*
Y203624D01*
X1985890D01*
Y245824D01*
G01X1903884Y193562D02*
X1902218D01*
Y196062D01*
X1903884D01*
G01X1903218Y194854D02*
X1902218D01*
G01X1905234Y196062D02*
Y194270D01*
X1905401Y193895D01*
X1905734Y193645D01*
X1906151Y193562D01*
X1906568Y193645D01*
X1906901Y193895D01*
X1907068Y194270D01*
Y196062D01*
G01X1908543Y193854D02*
X1908834Y193645D01*
X1909168Y193562D01*
X1909501Y193645D01*
X1909793Y193895D01*
X1910001Y194270D01*
X1910084Y194645D01*
Y195104D01*
X1910001Y195479D01*
X1909793Y195812D01*
X1909543Y195979D01*
X1909251Y196062D01*
X1908918Y195979D01*
X1908668Y195812D01*
X1908501Y195562D01*
X1908418Y195229D01*
X1908501Y194937D01*
X1908709Y194645D01*
X1908959Y194479D01*
X1909251Y194437D01*
X1909584Y194520D01*
X1909834Y194729D01*
X1910084Y195104D01*
G01X1913184Y193562D02*
X1911518D01*
Y196062D01*
X1913184D01*
G01X1912518Y194854D02*
X1911518D01*
G01X1915451Y193562D02*
Y196062D01*
X1914951Y195562D01*
G01Y193562D02*
X1915951D01*
G01X1923164Y190815D02*
X1924215D01*
Y189764D01*
G01X1899025Y219848D02*
Y222348D01*
X1900066D01*
X1900400Y222223D01*
X1900608Y222056D01*
X1900691Y221723D01*
X1900608Y221390D01*
X1900358Y221181D01*
X1900066Y221056D01*
X1899025D01*
G01X1900066D02*
X1900691Y219848D01*
G01X1902250Y220140D02*
X1902541Y219931D01*
X1902875Y219848D01*
X1903208Y219931D01*
X1903500Y220181D01*
X1903708Y220556D01*
X1903791Y220931D01*
Y221390D01*
X1903708Y221765D01*
X1903500Y222098D01*
X1903250Y222265D01*
X1902958Y222348D01*
X1902625Y222265D01*
X1902375Y222098D01*
X1902208Y221848D01*
X1902125Y221515D01*
X1902208Y221223D01*
X1902416Y220931D01*
X1902666Y220765D01*
X1902958Y220723D01*
X1903291Y220806D01*
X1903541Y221015D01*
X1903791Y221390D01*
G01X1906891Y219848D02*
X1905225D01*
Y222348D01*
X1906891D01*
G01X1906225Y221140D02*
X1905225D01*
G01X1909158Y219848D02*
Y222348D01*
X1908658Y221848D01*
G01Y219848D02*
X1909658D01*
G01X1911341Y220348D02*
X1911591Y220056D01*
X1911925Y219890D01*
X1912300Y219848D01*
X1912633Y219890D01*
X1912966Y220098D01*
X1913175Y220348D01*
X1913216Y220598D01*
X1913133Y220890D01*
X1912841Y221098D01*
X1912550Y221181D01*
X1912175D01*
G01X1912550D02*
X1912800Y221306D01*
X1913008Y221515D01*
X1913091Y221765D01*
X1913008Y222015D01*
X1912800Y222223D01*
X1912425Y222348D01*
X1912050Y222306D01*
X1911675Y222140D01*
G01X1910517Y229027D02*
X1910392Y228777D01*
X1910309Y228485D01*
Y228152D01*
X1910434Y227777D01*
X1910642Y227485D01*
X1910892Y227277D01*
X1911309Y227110D01*
X1911684Y227068D01*
X1912059Y227152D01*
X1912309Y227277D01*
X1912559Y227527D01*
X1912726Y227818D01*
X1912809Y228110D01*
Y228402D01*
X1912726Y228693D01*
X1912601Y228943D01*
X1912434Y229152D01*
G01X1912309Y230293D02*
X1912601Y230543D01*
X1912767Y230877D01*
X1912809Y231252D01*
X1912767Y231585D01*
X1912559Y231918D01*
X1912309Y232127D01*
X1912059Y232168D01*
X1911767Y232085D01*
X1911559Y231793D01*
X1911476Y231502D01*
Y231127D01*
G01Y231502D02*
X1911351Y231752D01*
X1911142Y231960D01*
X1910892Y232043D01*
X1910642Y231960D01*
X1910434Y231752D01*
X1910309Y231377D01*
X1910351Y231002D01*
X1910517Y230627D01*
G01X1910309Y234310D02*
X1910392Y233977D01*
X1910601Y233727D01*
X1910851Y233560D01*
X1911184Y233435D01*
X1911559Y233393D01*
X1911934Y233435D01*
X1912267Y233560D01*
X1912517Y233727D01*
X1912726Y233977D01*
X1912809Y234310D01*
X1912726Y234643D01*
X1912517Y234893D01*
X1912267Y235060D01*
X1911934Y235185D01*
X1911559Y235227D01*
X1911184Y235185D01*
X1910851Y235060D01*
X1910601Y234893D01*
X1910392Y234643D01*
X1910309Y234310D01*
G01Y236160D02*
X1912809Y236743D01*
X1910309Y237410D01*
X1912809Y238077D01*
X1910309Y238660D01*
G01X1912309Y239593D02*
X1912601Y239843D01*
X1912767Y240177D01*
X1912809Y240552D01*
X1912767Y240885D01*
X1912559Y241218D01*
X1912309Y241427D01*
X1912059Y241468D01*
X1911767Y241385D01*
X1911559Y241093D01*
X1911476Y240802D01*
Y240427D01*
G01Y240802D02*
X1911351Y241052D01*
X1911142Y241260D01*
X1910892Y241343D01*
X1910642Y241260D01*
X1910434Y241052D01*
X1910309Y240677D01*
X1910351Y240302D01*
X1910517Y239927D01*
G01X1906786Y229218D02*
X1906661Y228968D01*
X1906578Y228676D01*
Y228343D01*
X1906703Y227968D01*
X1906911Y227676D01*
X1907161Y227468D01*
X1907578Y227301D01*
X1907953Y227259D01*
X1908328Y227343D01*
X1908578Y227468D01*
X1908828Y227718D01*
X1908995Y228009D01*
X1909078Y228301D01*
Y228593D01*
X1908995Y228884D01*
X1908870Y229134D01*
X1908703Y229343D01*
G01X1908578Y230484D02*
X1908870Y230734D01*
X1909036Y231068D01*
X1909078Y231443D01*
X1909036Y231776D01*
X1908828Y232109D01*
X1908578Y232318D01*
X1908328Y232359D01*
X1908036Y232276D01*
X1907828Y231984D01*
X1907745Y231693D01*
Y231318D01*
G01Y231693D02*
X1907620Y231943D01*
X1907411Y232151D01*
X1907161Y232234D01*
X1906911Y232151D01*
X1906703Y231943D01*
X1906578Y231568D01*
X1906620Y231193D01*
X1906786Y230818D01*
G01X1906578Y234501D02*
X1906661Y234168D01*
X1906870Y233918D01*
X1907120Y233751D01*
X1907453Y233626D01*
X1907828Y233584D01*
X1908203Y233626D01*
X1908536Y233751D01*
X1908786Y233918D01*
X1908995Y234168D01*
X1909078Y234501D01*
X1908995Y234834D01*
X1908786Y235084D01*
X1908536Y235251D01*
X1908203Y235376D01*
X1907828Y235418D01*
X1907453Y235376D01*
X1907120Y235251D01*
X1906870Y235084D01*
X1906661Y234834D01*
X1906578Y234501D01*
G01Y236351D02*
X1909078Y236934D01*
X1906578Y237601D01*
X1909078Y238268D01*
X1906578Y238851D01*
G01X1909078Y240618D02*
X1908536Y240701D01*
X1908078Y240826D01*
X1907661Y240993D01*
X1907203Y241201D01*
X1906578Y241534D01*
Y239868D01*
G01X1914135Y221510D02*
X1923635D01*
Y239210D01*
X1914135D01*
Y221510D01*
G01X1935486Y440479D02*
X1935716Y440789D01*
X1935984Y440944D01*
X1936291Y440996D01*
X1936674Y440893D01*
X1936942Y440634D01*
X1937019Y440324D01*
X1936981Y440014D01*
X1936827Y439756D01*
X1936061Y439239D01*
X1935716Y438878D01*
X1935486Y438361D01*
X1935409Y437896D01*
X1937019D01*
G01X1933763Y447340D02*
Y437497D01*
X1923921D01*
G01Y464860D02*
X1933763D01*
Y455017D01*
G01X1943967Y484670D02*
Y487170D01*
X1945008D01*
X1945342Y487045D01*
X1945550Y486878D01*
X1945633Y486545D01*
X1945550Y486212D01*
X1945300Y486003D01*
X1945008Y485878D01*
X1943967D01*
G01X1945008D02*
X1945633Y484670D01*
G01X1947900D02*
Y487170D01*
X1947400Y486670D01*
G01Y484670D02*
X1948400D01*
G01X1949917D02*
Y487170D01*
X1951000Y485087D01*
X1952083Y487170D01*
Y484670D01*
G01X1953392Y484962D02*
X1953683Y484753D01*
X1954017Y484670D01*
X1954350Y484753D01*
X1954642Y485003D01*
X1954850Y485378D01*
X1954933Y485753D01*
Y486212D01*
X1954850Y486587D01*
X1954642Y486920D01*
X1954392Y487087D01*
X1954100Y487170D01*
X1953767Y487087D01*
X1953517Y486920D01*
X1953350Y486670D01*
X1953267Y486337D01*
X1953350Y486045D01*
X1953558Y485753D01*
X1953808Y485587D01*
X1954100Y485545D01*
X1954433Y485628D01*
X1954683Y485837D01*
X1954933Y486212D01*
G01X1924857Y469010D02*
Y471510D01*
X1925898D01*
X1926232Y471385D01*
X1926440Y471218D01*
X1926523Y470885D01*
X1926440Y470552D01*
X1926190Y470343D01*
X1925898Y470218D01*
X1924857D01*
G01X1925898D02*
X1926523Y469010D01*
G01X1928082Y469302D02*
X1928373Y469093D01*
X1928707Y469010D01*
X1929040Y469093D01*
X1929332Y469343D01*
X1929540Y469718D01*
X1929623Y470093D01*
Y470552D01*
X1929540Y470927D01*
X1929332Y471260D01*
X1929082Y471427D01*
X1928790Y471510D01*
X1928457Y471427D01*
X1928207Y471260D01*
X1928040Y471010D01*
X1927957Y470677D01*
X1928040Y470385D01*
X1928248Y470093D01*
X1928498Y469927D01*
X1928790Y469885D01*
X1929123Y469968D01*
X1929373Y470177D01*
X1929623Y470552D01*
G01X1932223Y470343D02*
X1932390Y470468D01*
X1932515Y470677D01*
X1932598Y470968D01*
X1932515Y471218D01*
X1932348Y471385D01*
X1932057Y471510D01*
X1930932D01*
Y469010D01*
X1932307D01*
X1932598Y469177D01*
X1932765Y469427D01*
X1932848Y469718D01*
X1932765Y470010D01*
X1932515Y470260D01*
X1932223Y470343D01*
X1930932D01*
G01X1934990Y469010D02*
X1935282Y469052D01*
X1935615Y469177D01*
X1935823Y469385D01*
X1935907Y469677D01*
X1935823Y469968D01*
X1935573Y470218D01*
X1935198Y470343D01*
X1934782D01*
X1934532Y470427D01*
X1934323Y470635D01*
X1934240Y470927D01*
X1934365Y471218D01*
X1934657Y471427D01*
X1934990Y471510D01*
X1935323Y471427D01*
X1935615Y471218D01*
X1935740Y470927D01*
X1935657Y470635D01*
X1935448Y470427D01*
X1935198Y470343D01*
X1934782D01*
X1934407Y470218D01*
X1934157Y469968D01*
X1934073Y469677D01*
X1934157Y469385D01*
X1934365Y469177D01*
X1934698Y469052D01*
X1934990Y469010D01*
G01X1943757Y494670D02*
Y497170D01*
X1944798D01*
X1945132Y497045D01*
X1945340Y496878D01*
X1945423Y496545D01*
X1945340Y496212D01*
X1945090Y496003D01*
X1944798Y495878D01*
X1943757D01*
G01X1944798D02*
X1945423Y494670D01*
G01X1947690D02*
Y497170D01*
X1947190Y496670D01*
G01Y494670D02*
X1948190D01*
G01X1949707D02*
Y497170D01*
X1950790Y495087D01*
X1951873Y497170D01*
Y494670D01*
G01X1953890D02*
X1954182Y494712D01*
X1954515Y494837D01*
X1954723Y495045D01*
X1954807Y495337D01*
X1954723Y495628D01*
X1954473Y495878D01*
X1954098Y496003D01*
X1953682D01*
X1953432Y496087D01*
X1953223Y496295D01*
X1953140Y496587D01*
X1953265Y496878D01*
X1953557Y497087D01*
X1953890Y497170D01*
X1954223Y497087D01*
X1954515Y496878D01*
X1954640Y496587D01*
X1954557Y496295D01*
X1954348Y496087D01*
X1954098Y496003D01*
X1953682D01*
X1953307Y495878D01*
X1953057Y495628D01*
X1952973Y495337D01*
X1953057Y495045D01*
X1953265Y494837D01*
X1953598Y494712D01*
X1953890Y494670D01*
G01X1900097Y480250D02*
Y482750D01*
X1901138D01*
X1901472Y482625D01*
X1901680Y482458D01*
X1901763Y482125D01*
X1901680Y481792D01*
X1901430Y481583D01*
X1901138Y481458D01*
X1900097D01*
G01X1901138D02*
X1901763Y480250D01*
G01X1903322Y480542D02*
X1903613Y480333D01*
X1903947Y480250D01*
X1904280Y480333D01*
X1904572Y480583D01*
X1904780Y480958D01*
X1904863Y481333D01*
Y481792D01*
X1904780Y482167D01*
X1904572Y482500D01*
X1904322Y482667D01*
X1904030Y482750D01*
X1903697Y482667D01*
X1903447Y482500D01*
X1903280Y482250D01*
X1903197Y481917D01*
X1903280Y481625D01*
X1903488Y481333D01*
X1903738Y481167D01*
X1904030Y481125D01*
X1904363Y481208D01*
X1904613Y481417D01*
X1904863Y481792D01*
G01X1907463Y481583D02*
X1907630Y481708D01*
X1907755Y481917D01*
X1907838Y482208D01*
X1907755Y482458D01*
X1907588Y482625D01*
X1907297Y482750D01*
X1906172D01*
Y480250D01*
X1907547D01*
X1907838Y480417D01*
X1908005Y480667D01*
X1908088Y480958D01*
X1908005Y481250D01*
X1907755Y481500D01*
X1907463Y481583D01*
X1906172D01*
G01X1909313Y480625D02*
X1909563Y480417D01*
X1909855Y480292D01*
X1910230Y480250D01*
X1910605Y480333D01*
X1910897Y480500D01*
X1911105Y480792D01*
X1911147Y481125D01*
X1911063Y481458D01*
X1910855Y481667D01*
X1910563Y481833D01*
X1910272Y481875D01*
X1909980Y481833D01*
X1909605Y481667D01*
X1909730Y482750D01*
X1910855D01*
G01X1899897Y484460D02*
Y486960D01*
X1900938D01*
X1901272Y486835D01*
X1901480Y486668D01*
X1901563Y486335D01*
X1901480Y486002D01*
X1901230Y485793D01*
X1900938Y485668D01*
X1899897D01*
G01X1900938D02*
X1901563Y484460D01*
G01X1903122Y484752D02*
X1903413Y484543D01*
X1903747Y484460D01*
X1904080Y484543D01*
X1904372Y484793D01*
X1904580Y485168D01*
X1904663Y485543D01*
Y486002D01*
X1904580Y486377D01*
X1904372Y486710D01*
X1904122Y486877D01*
X1903830Y486960D01*
X1903497Y486877D01*
X1903247Y486710D01*
X1903080Y486460D01*
X1902997Y486127D01*
X1903080Y485835D01*
X1903288Y485543D01*
X1903538Y485377D01*
X1903830Y485335D01*
X1904163Y485418D01*
X1904413Y485627D01*
X1904663Y486002D01*
G01X1907263Y485793D02*
X1907430Y485918D01*
X1907555Y486127D01*
X1907638Y486418D01*
X1907555Y486668D01*
X1907388Y486835D01*
X1907097Y486960D01*
X1905972D01*
Y484460D01*
X1907347D01*
X1907638Y484627D01*
X1907805Y484877D01*
X1907888Y485168D01*
X1907805Y485460D01*
X1907555Y485710D01*
X1907263Y485793D01*
X1905972D01*
G01X1910530Y484460D02*
Y486960D01*
X1908988Y485168D01*
X1911072D01*
G01X1938843Y481930D02*
Y480138D01*
X1939010Y479763D01*
X1939343Y479513D01*
X1939760Y479430D01*
X1940177Y479513D01*
X1940510Y479763D01*
X1940677Y480138D01*
Y481930D01*
G01X1942152Y479722D02*
X1942443Y479513D01*
X1942777Y479430D01*
X1943110Y479513D01*
X1943402Y479763D01*
X1943610Y480138D01*
X1943693Y480513D01*
Y480972D01*
X1943610Y481347D01*
X1943402Y481680D01*
X1943152Y481847D01*
X1942860Y481930D01*
X1942527Y481847D01*
X1942277Y481680D01*
X1942110Y481430D01*
X1942027Y481097D01*
X1942110Y480805D01*
X1942318Y480513D01*
X1942568Y480347D01*
X1942860Y480305D01*
X1943193Y480388D01*
X1943443Y480597D01*
X1943693Y480972D01*
G01X1946293Y480763D02*
X1946460Y480888D01*
X1946585Y481097D01*
X1946668Y481388D01*
X1946585Y481638D01*
X1946418Y481805D01*
X1946127Y481930D01*
X1945002D01*
Y479430D01*
X1946377D01*
X1946668Y479597D01*
X1946835Y479847D01*
X1946918Y480138D01*
X1946835Y480430D01*
X1946585Y480680D01*
X1946293Y480763D01*
X1945002D01*
G01X1949560Y479430D02*
Y481930D01*
X1948018Y480138D01*
X1950102D01*
G01X1930134Y477470D02*
X1927701D01*
G01X1930068Y489270D02*
X1927781D01*
G01X1913374Y504691D02*
Y507791D01*
X1911956Y505569D01*
X1913872D01*
G01X1936028Y508741D02*
X1977760D01*
G01X1936380Y503570D02*
X1936047Y503612D01*
X1935755Y503778D01*
X1935505Y504028D01*
X1935338Y504320D01*
X1935255Y504653D01*
Y504987D01*
X1935338Y505320D01*
X1935505Y505612D01*
X1935755Y505862D01*
X1936047Y506028D01*
X1936380Y506070D01*
X1936713Y506028D01*
X1937005Y505862D01*
X1937255Y505612D01*
X1937422Y505320D01*
X1937505Y504987D01*
Y504653D01*
X1937422Y504320D01*
X1937255Y504028D01*
X1937005Y503778D01*
X1936713Y503612D01*
X1936380Y503570D01*
G01X1936713Y504237D02*
X1937213Y503570D01*
G01X1938772Y503862D02*
X1939063Y503653D01*
X1939397Y503570D01*
X1939730Y503653D01*
X1940022Y503903D01*
X1940230Y504278D01*
X1940313Y504653D01*
Y505112D01*
X1940230Y505487D01*
X1940022Y505820D01*
X1939772Y505987D01*
X1939480Y506070D01*
X1939147Y505987D01*
X1938897Y505820D01*
X1938730Y505570D01*
X1938647Y505237D01*
X1938730Y504945D01*
X1938938Y504653D01*
X1939188Y504487D01*
X1939480Y504445D01*
X1939813Y504528D01*
X1940063Y504737D01*
X1940313Y505112D01*
G01X1942913Y504903D02*
X1943080Y505028D01*
X1943205Y505237D01*
X1943288Y505528D01*
X1943205Y505778D01*
X1943038Y505945D01*
X1942747Y506070D01*
X1941622D01*
Y503570D01*
X1942997D01*
X1943288Y503737D01*
X1943455Y503987D01*
X1943538Y504278D01*
X1943455Y504570D01*
X1943205Y504820D01*
X1942913Y504903D01*
X1941622D01*
G01X1945680Y503570D02*
Y506070D01*
X1945180Y505570D01*
G01Y503570D02*
X1946180D01*
G01X1914544Y499025D02*
G02X1934964I10210J-2450D01*
G01X1937854D01*
Y492525D01*
X1934442D01*
G02X1933371Y490575I-9688J4052D01*
G01X1916137D01*
G02X1915066Y492525I8617J6002D01*
G01X1911654D01*
Y499025D01*
X1914544D01*
G01X1981291Y485469D02*
X1976091D01*
Y474619D01*
X1958391D01*
Y509319D01*
X1976091D01*
Y498469D01*
X1981291D01*
Y485469D01*
G01X1935062Y541411D02*
Y539189D01*
X1935215Y538724D01*
X1935522Y538414D01*
X1935905Y538311D01*
X1936288Y538414D01*
X1936595Y538724D01*
X1936748Y539189D01*
Y541411D01*
G01X1938047Y538311D02*
X1939005Y541411D01*
X1939963Y538311D01*
G01X1939618Y539396D02*
X1938392D01*
G01X1941338Y538311D02*
Y541411D01*
X1942297D01*
X1942603Y541256D01*
X1942795Y541049D01*
X1942872Y540636D01*
X1942795Y540223D01*
X1942565Y539964D01*
X1942297Y539809D01*
X1941338D01*
G01X1942297D02*
X1942872Y538311D01*
G01X1945205Y541411D02*
Y538311D01*
G01X1944323Y541411D02*
X1946087D01*
G01X1947155Y537278D02*
X1949455D01*
G01X1950408Y538311D02*
Y541411D01*
X1951405Y538828D01*
X1952402Y541411D01*
Y538311D01*
G01X1953700Y538724D02*
X1954007Y538466D01*
X1954352Y538311D01*
X1954658D01*
X1954965Y538466D01*
X1955195Y538724D01*
X1955310Y539086D01*
X1955233Y539448D01*
X1955042Y539758D01*
X1954697Y539964D01*
X1954237Y540068D01*
X1953968Y540274D01*
X1953853Y540636D01*
X1953930Y540998D01*
X1954122Y541256D01*
X1954390Y541411D01*
X1954658D01*
X1954927Y541308D01*
X1955157Y541049D01*
G01X1957912Y539964D02*
X1958065Y540119D01*
X1958180Y540378D01*
X1958257Y540739D01*
X1958180Y541049D01*
X1958027Y541256D01*
X1957758Y541411D01*
X1956723D01*
Y538311D01*
X1957988D01*
X1958257Y538518D01*
X1958410Y538828D01*
X1958487Y539189D01*
X1958410Y539551D01*
X1958180Y539861D01*
X1957912Y539964D01*
X1956723D01*
G01X1936660Y547324D02*
Y545102D01*
X1936813Y544637D01*
X1937120Y544327D01*
X1937503Y544224D01*
X1937886Y544327D01*
X1938193Y544637D01*
X1938346Y545102D01*
Y547324D01*
G01X1939645Y544224D02*
X1940603Y547324D01*
X1941561Y544224D01*
G01X1941216Y545309D02*
X1939990D01*
G01X1942936Y544224D02*
Y547324D01*
X1943895D01*
X1944201Y547169D01*
X1944393Y546962D01*
X1944470Y546549D01*
X1944393Y546136D01*
X1944163Y545877D01*
X1943895Y545722D01*
X1942936D01*
G01X1943895D02*
X1944470Y544224D01*
G01X1946803Y547324D02*
Y544224D01*
G01X1945921Y547324D02*
X1947685D01*
G01X1948753Y543191D02*
X1951053D01*
G01X1952236Y547324D02*
Y544224D01*
X1953770D01*
G01X1955298Y544637D02*
X1955605Y544379D01*
X1955950Y544224D01*
X1956256D01*
X1956563Y544379D01*
X1956793Y544637D01*
X1956908Y544999D01*
X1956831Y545361D01*
X1956640Y545671D01*
X1956295Y545877D01*
X1955835Y545981D01*
X1955566Y546187D01*
X1955451Y546549D01*
X1955528Y546911D01*
X1955720Y547169D01*
X1955988Y547324D01*
X1956256D01*
X1956525Y547221D01*
X1956755Y546962D01*
G01X1959510Y545877D02*
X1959663Y546032D01*
X1959778Y546291D01*
X1959855Y546652D01*
X1959778Y546962D01*
X1959625Y547169D01*
X1959356Y547324D01*
X1958321D01*
Y544224D01*
X1959586D01*
X1959855Y544431D01*
X1960008Y544741D01*
X1960085Y545102D01*
X1960008Y545464D01*
X1959778Y545774D01*
X1959510Y545877D01*
X1958321D01*
G01X1927341Y556492D02*
Y563492D01*
X1933475Y556492D01*
Y563492D01*
G01X1930249Y536540D02*
X1963783D01*
Y538202D01*
X1973763D01*
Y547921D01*
G01X1924883Y571231D02*
Y550944D01*
X1906900D01*
G01X1957761Y549887D02*
X1961350D01*
Y551780D01*
X1964629Y549887D01*
X1961350Y547994D01*
Y549887D01*
G01X1926222Y554383D02*
X1926452Y554693D01*
X1926720Y554848D01*
X1927027Y554900D01*
X1927410Y554797D01*
X1927678Y554538D01*
X1927755Y554228D01*
X1927717Y553918D01*
X1927563Y553660D01*
X1926797Y553143D01*
X1926452Y552782D01*
X1926222Y552265D01*
X1926145Y551800D01*
X1927755D01*
G01X1922954Y564899D02*
Y569720D01*
G01X1915653Y579607D02*
X1905644D01*
G01X1898354Y569720D02*
Y564909D01*
G01X1915670Y555007D02*
X1905644D01*
G01X1960939Y614586D02*
Y549586D01*
X1934699D01*
Y553336D01*
X1936699D01*
Y575086D01*
X1934699D01*
Y589086D01*
X1936699D01*
Y610836D01*
X1934699D01*
Y614586D01*
X1960939D01*
G01X1923797Y534465D02*
X1924027Y534207D01*
X1924295Y534052D01*
X1924640Y534000D01*
X1924985Y534103D01*
X1925253Y534310D01*
X1925445Y534672D01*
X1925483Y535085D01*
X1925407Y535498D01*
X1925215Y535757D01*
X1924947Y535963D01*
X1924678Y536015D01*
X1924410Y535963D01*
X1924065Y535757D01*
X1924180Y537100D01*
X1925215D01*
G01X1977760Y535001D02*
X1936028D01*
G01X1935750Y543750D02*
Y547000D01*
X1932250D01*
G01X1923750Y543750D02*
Y547000D01*
X1927250D01*
G01X1928500Y541500D02*
X1931000D01*
G01X1935658Y622209D02*
Y625309D01*
X1936578D01*
X1936885Y625154D01*
X1937115Y624792D01*
X1937192Y624379D01*
X1937115Y623966D01*
X1936923Y623656D01*
X1936578Y623501D01*
X1935658D01*
G01X1939525Y622209D02*
X1939218Y622261D01*
X1938950Y622467D01*
X1938720Y622777D01*
X1938567Y623139D01*
X1938490Y623552D01*
Y623966D01*
X1938567Y624379D01*
X1938720Y624741D01*
X1938950Y625051D01*
X1939218Y625257D01*
X1939525Y625309D01*
X1939832Y625257D01*
X1940100Y625051D01*
X1940330Y624741D01*
X1940483Y624379D01*
X1940560Y623966D01*
Y623552D01*
X1940483Y623139D01*
X1940330Y622777D01*
X1940100Y622467D01*
X1939832Y622261D01*
X1939525Y622209D01*
G01X1941820Y622622D02*
X1942127Y622364D01*
X1942472Y622209D01*
X1942778D01*
X1943085Y622364D01*
X1943315Y622622D01*
X1943430Y622984D01*
X1943353Y623346D01*
X1943162Y623656D01*
X1942817Y623862D01*
X1942357Y623966D01*
X1942088Y624172D01*
X1941973Y624534D01*
X1942050Y624896D01*
X1942242Y625154D01*
X1942510Y625309D01*
X1942778D01*
X1943047Y625206D01*
X1943277Y624947D01*
G01X1945725Y625309D02*
Y622209D01*
G01X1944843Y625309D02*
X1946607D01*
G01X1948135Y622106D02*
X1949515Y625309D01*
G01X1951120Y622622D02*
X1951427Y622364D01*
X1951772Y622209D01*
X1952078D01*
X1952385Y622364D01*
X1952615Y622622D01*
X1952730Y622984D01*
X1952653Y623346D01*
X1952462Y623656D01*
X1952117Y623862D01*
X1951657Y623966D01*
X1951388Y624172D01*
X1951273Y624534D01*
X1951350Y624896D01*
X1951542Y625154D01*
X1951810Y625309D01*
X1952078D01*
X1952347Y625206D01*
X1952577Y624947D01*
G01X1955025Y622209D02*
X1954718Y622261D01*
X1954450Y622467D01*
X1954220Y622777D01*
X1954067Y623139D01*
X1953990Y623552D01*
Y623966D01*
X1954067Y624379D01*
X1954220Y624741D01*
X1954450Y625051D01*
X1954718Y625257D01*
X1955025Y625309D01*
X1955332Y625257D01*
X1955600Y625051D01*
X1955830Y624741D01*
X1955983Y624379D01*
X1956060Y623966D01*
Y623552D01*
X1955983Y623139D01*
X1955830Y622777D01*
X1955600Y622467D01*
X1955332Y622261D01*
X1955025Y622209D01*
G01X1957358Y625309D02*
Y622209D01*
X1958892D01*
G01X1899983Y619800D02*
Y622900D01*
X1900942D01*
X1901248Y622745D01*
X1901440Y622538D01*
X1901517Y622125D01*
X1901440Y621712D01*
X1901210Y621453D01*
X1900942Y621298D01*
X1899983D01*
G01X1900942D02*
X1901517Y619800D01*
G01X1903045Y620213D02*
X1903352Y619955D01*
X1903697Y619800D01*
X1904003D01*
X1904310Y619955D01*
X1904540Y620213D01*
X1904655Y620575D01*
X1904578Y620937D01*
X1904387Y621247D01*
X1904042Y621453D01*
X1903582Y621557D01*
X1903313Y621763D01*
X1903198Y622125D01*
X1903275Y622487D01*
X1903467Y622745D01*
X1903735Y622900D01*
X1904003D01*
X1904272Y622797D01*
X1904502Y622538D01*
G01X1906950Y622900D02*
Y619800D01*
G01X1906068Y622900D02*
X1907832D01*
G01X1908900Y618767D02*
X1911200D01*
G01X1913457Y621453D02*
X1913610Y621608D01*
X1913725Y621867D01*
X1913802Y622228D01*
X1913725Y622538D01*
X1913572Y622745D01*
X1913303Y622900D01*
X1912268D01*
Y619800D01*
X1913533D01*
X1913802Y620007D01*
X1913955Y620317D01*
X1914032Y620678D01*
X1913955Y621040D01*
X1913725Y621350D01*
X1913457Y621453D01*
X1912268D01*
G01X1916250Y622900D02*
Y619800D01*
G01X1915368Y622900D02*
X1917132D01*
G01X1918468Y619800D02*
Y622900D01*
X1920232Y619800D01*
Y622900D01*
G01X1948230Y615745D02*
X1959630D01*
G01X1924944Y611820D02*
Y614600D01*
X1934000D01*
G01X1928216Y607176D02*
X1924430D01*
G01X1921143Y593558D02*
Y597147D01*
X1919250D01*
X1921143Y600426D01*
X1923036Y597147D01*
X1921143D01*
G01X1923036Y600426D02*
X1919250D01*
G01X1921143Y604849D02*
Y600426D01*
G01X1922822Y593033D02*
X1923052Y593343D01*
X1923320Y593498D01*
X1923627Y593550D01*
X1924010Y593447D01*
X1924278Y593188D01*
X1924355Y592878D01*
X1924317Y592568D01*
X1924163Y592310D01*
X1923397Y591793D01*
X1923052Y591432D01*
X1922822Y590915D01*
X1922745Y590450D01*
X1924355D01*
G01X1924825Y620043D02*
X1925158Y619835D01*
X1925533Y619710D01*
X1925867D01*
X1926200Y619835D01*
X1926450Y620043D01*
X1926575Y620335D01*
X1926492Y620627D01*
X1926283Y620877D01*
X1925908Y621043D01*
X1925408Y621127D01*
X1925117Y621293D01*
X1924992Y621585D01*
X1925075Y621877D01*
X1925283Y622085D01*
X1925575Y622210D01*
X1925867D01*
X1926158Y622127D01*
X1926408Y621918D01*
G01X1928092Y620002D02*
X1928383Y619793D01*
X1928717Y619710D01*
X1929050Y619793D01*
X1929342Y620043D01*
X1929550Y620418D01*
X1929633Y620793D01*
Y621252D01*
X1929550Y621627D01*
X1929342Y621960D01*
X1929092Y622127D01*
X1928800Y622210D01*
X1928467Y622127D01*
X1928217Y621960D01*
X1928050Y621710D01*
X1927967Y621377D01*
X1928050Y621085D01*
X1928258Y620793D01*
X1928508Y620627D01*
X1928800Y620585D01*
X1929133Y620668D01*
X1929383Y620877D01*
X1929633Y621252D01*
G01X1930858Y619710D02*
X1931900Y622210D01*
X1932942Y619710D01*
G01X1932567Y620585D02*
X1931233D01*
G01X1935000Y619710D02*
Y622210D01*
X1934500Y621710D01*
G01Y619710D02*
X1935500D01*
G01X1915670Y591201D02*
X1905644D01*
G01X1898354Y605914D02*
Y601103D01*
G01X1915653Y615801D02*
X1905644D01*
G01X1922954Y601093D02*
Y605914D01*
G01X1924605Y616583D02*
X1924938Y616375D01*
X1925313Y616250D01*
X1925647D01*
X1925980Y616375D01*
X1926230Y616583D01*
X1926355Y616875D01*
X1926272Y617167D01*
X1926063Y617417D01*
X1925688Y617583D01*
X1925188Y617667D01*
X1924897Y617833D01*
X1924772Y618125D01*
X1924855Y618417D01*
X1925063Y618625D01*
X1925355Y618750D01*
X1925647D01*
X1925938Y618667D01*
X1926188Y618458D01*
G01X1927872Y616542D02*
X1928163Y616333D01*
X1928497Y616250D01*
X1928830Y616333D01*
X1929122Y616583D01*
X1929330Y616958D01*
X1929413Y617333D01*
Y617792D01*
X1929330Y618167D01*
X1929122Y618500D01*
X1928872Y618667D01*
X1928580Y618750D01*
X1928247Y618667D01*
X1927997Y618500D01*
X1927830Y618250D01*
X1927747Y617917D01*
X1927830Y617625D01*
X1928038Y617333D01*
X1928288Y617167D01*
X1928580Y617125D01*
X1928913Y617208D01*
X1929163Y617417D01*
X1929413Y617792D01*
G01X1930638Y616250D02*
X1931680Y618750D01*
X1932722Y616250D01*
G01X1932347Y617125D02*
X1931013D01*
G01X1933988Y618333D02*
X1934238Y618583D01*
X1934530Y618708D01*
X1934863Y618750D01*
X1935280Y618667D01*
X1935572Y618458D01*
X1935655Y618208D01*
X1935613Y617958D01*
X1935447Y617750D01*
X1934613Y617333D01*
X1934238Y617042D01*
X1933988Y616625D01*
X1933905Y616250D01*
X1935655D01*
G01X1954285Y617017D02*
Y619517D01*
X1953785Y619017D01*
G01Y617017D02*
X1954785D01*
G01X1956468Y617517D02*
X1956718Y617225D01*
X1957052Y617059D01*
X1957427Y617017D01*
X1957760Y617059D01*
X1958093Y617267D01*
X1958302Y617517D01*
X1958343Y617767D01*
X1958260Y618059D01*
X1957968Y618267D01*
X1957677Y618350D01*
X1957302D01*
G01X1957677D02*
X1957927Y618475D01*
X1958135Y618684D01*
X1958218Y618934D01*
X1958135Y619184D01*
X1957927Y619392D01*
X1957552Y619517D01*
X1957177Y619475D01*
X1956802Y619309D01*
G01X1939830Y616710D02*
Y619810D01*
X1939370Y619190D01*
G01Y616710D02*
X1940290D01*
G01X1943390D02*
Y619810D01*
X1941972Y617588D01*
X1943888D01*
G01X1966408Y91467D02*
X1966283Y91217D01*
X1966200Y90925D01*
Y90592D01*
X1966325Y90217D01*
X1966533Y89925D01*
X1966783Y89717D01*
X1967200Y89550D01*
X1967575Y89508D01*
X1967950Y89592D01*
X1968200Y89717D01*
X1968450Y89967D01*
X1968617Y90258D01*
X1968700Y90550D01*
Y90842D01*
X1968617Y91133D01*
X1968492Y91383D01*
X1968325Y91592D01*
G01X1968700Y93567D02*
X1968158Y93650D01*
X1967700Y93775D01*
X1967283Y93942D01*
X1966825Y94150D01*
X1966200Y94483D01*
Y92817D01*
G01X1968700Y97583D02*
Y95917D01*
X1966200D01*
Y97583D01*
G01X1967408Y96917D02*
Y95917D01*
G01X1968325Y98933D02*
X1968533Y99183D01*
X1968658Y99475D01*
X1968700Y99850D01*
X1968617Y100225D01*
X1968450Y100517D01*
X1968158Y100725D01*
X1967825Y100767D01*
X1967492Y100683D01*
X1967283Y100475D01*
X1967117Y100183D01*
X1967075Y99892D01*
X1967117Y99600D01*
X1967283Y99225D01*
X1966200Y99350D01*
Y100475D01*
G01X1961645Y469413D02*
X1961978Y469205D01*
X1962353Y469080D01*
X1962687D01*
X1963020Y469205D01*
X1963270Y469413D01*
X1963395Y469705D01*
X1963312Y469997D01*
X1963103Y470247D01*
X1962728Y470413D01*
X1962228Y470497D01*
X1961937Y470663D01*
X1961812Y470955D01*
X1961895Y471247D01*
X1962103Y471455D01*
X1962395Y471580D01*
X1962687D01*
X1962978Y471497D01*
X1963228Y471288D01*
G01X1964912Y469372D02*
X1965203Y469163D01*
X1965537Y469080D01*
X1965870Y469163D01*
X1966162Y469413D01*
X1966370Y469788D01*
X1966453Y470163D01*
Y470622D01*
X1966370Y470997D01*
X1966162Y471330D01*
X1965912Y471497D01*
X1965620Y471580D01*
X1965287Y471497D01*
X1965037Y471330D01*
X1964870Y471080D01*
X1964787Y470747D01*
X1964870Y470455D01*
X1965078Y470163D01*
X1965328Y469997D01*
X1965620Y469955D01*
X1965953Y470038D01*
X1966203Y470247D01*
X1966453Y470622D01*
G01X1967470Y471580D02*
X1968053Y469080D01*
X1968720Y471580D01*
X1969387Y469080D01*
X1969970Y471580D01*
G01X1971820Y469080D02*
Y471580D01*
X1971320Y471080D01*
G01Y469080D02*
X1972320D01*
G01X1974287Y576745D02*
X1974545Y577052D01*
X1974700Y577397D01*
Y577703D01*
X1974545Y578010D01*
X1974287Y578240D01*
X1973925Y578355D01*
X1973563Y578278D01*
X1973253Y578087D01*
X1973047Y577742D01*
X1972943Y577282D01*
X1972737Y577013D01*
X1972375Y576898D01*
X1972013Y576975D01*
X1971755Y577167D01*
X1971600Y577435D01*
Y577703D01*
X1971703Y577972D01*
X1971962Y578202D01*
G01X1974700Y579692D02*
X1971600Y580650D01*
X1974700Y581608D01*
G01X1973615Y581263D02*
Y580037D01*
G01X1971600Y583750D02*
X1974700D01*
G01X1971600Y582868D02*
Y584632D01*
G01X1974700Y585892D02*
X1971600Y586850D01*
X1974700Y587808D01*
G01X1973615Y587463D02*
Y586237D01*
G01X1975733Y588800D02*
Y591100D01*
G01X1974700Y592245D02*
X1971600D01*
G01Y593855D02*
X1974700D01*
G01X1973150D02*
Y592245D01*
G01X1974700Y595307D02*
X1971600D01*
Y596073D01*
X1971755Y596380D01*
X1971962Y596610D01*
X1972272Y596802D01*
X1972633Y596955D01*
X1973150Y596993D01*
X1973667Y596955D01*
X1974028Y596802D01*
X1974338Y596610D01*
X1974545Y596380D01*
X1974700Y596073D01*
Y595307D01*
G01Y598407D02*
X1971600D01*
Y599173D01*
X1971755Y599480D01*
X1971962Y599710D01*
X1972272Y599902D01*
X1972633Y600055D01*
X1973150Y600093D01*
X1973667Y600055D01*
X1974028Y599902D01*
X1974338Y599710D01*
X1974545Y599480D01*
X1974700Y599173D01*
Y598407D01*
G01X1973556Y552828D02*
X1973401Y552981D01*
X1973142Y553096D01*
X1972781Y553173D01*
X1972471Y553096D01*
X1972264Y552943D01*
X1972109Y552674D01*
Y551639D01*
X1975209D01*
Y552904D01*
X1975002Y553173D01*
X1974692Y553326D01*
X1974331Y553403D01*
X1973969Y553326D01*
X1973659Y553096D01*
X1973556Y552828D01*
Y551639D01*
G01X1975209Y556388D02*
Y554854D01*
X1972109D01*
Y556388D01*
G01X1973607Y555774D02*
Y554854D01*
G01X1975209Y559488D02*
Y557954D01*
X1972109D01*
Y559488D01*
G01X1973607Y558874D02*
Y557954D01*
G01X1975209Y561054D02*
X1972109D01*
Y561974D01*
X1972264Y562281D01*
X1972626Y562511D01*
X1973039Y562588D01*
X1973452Y562511D01*
X1973762Y562319D01*
X1973917Y561974D01*
Y561054D01*
G01X1976242Y563771D02*
Y566071D01*
G01X1972109Y567254D02*
X1975209D01*
Y568788D01*
G01Y571888D02*
Y570354D01*
X1972109D01*
Y571888D01*
G01X1973607Y571274D02*
Y570354D01*
G01X1975209Y573378D02*
X1972109D01*
Y574144D01*
X1972264Y574451D01*
X1972471Y574681D01*
X1972781Y574873D01*
X1973142Y575026D01*
X1973659Y575064D01*
X1974176Y575026D01*
X1974537Y574873D01*
X1974847Y574681D01*
X1975054Y574451D01*
X1975209Y574144D01*
Y573378D01*
G01X1972401Y535139D02*
X1967978D01*
G01Y533246D02*
Y537032D01*
G01X1961110Y535139D02*
X1964699D01*
Y537032D01*
X1967978Y535139D01*
X1964699Y533246D01*
Y535139D01*
G01X1969052Y549887D02*
X1964629D01*
G01Y547994D02*
Y551780D01*
G01X1962845Y558662D02*
X1963095Y558912D01*
X1963387Y559037D01*
X1963720Y559079D01*
X1964137Y558996D01*
X1964429Y558787D01*
X1964512Y558537D01*
X1964470Y558287D01*
X1964304Y558079D01*
X1963470Y557662D01*
X1963095Y557371D01*
X1962845Y556954D01*
X1962762Y556579D01*
X1964512D01*
G01X1962704Y560410D02*
Y563999D01*
X1960811D01*
X1962704Y567278D01*
X1964597Y563999D01*
X1962704D01*
G01X1964597Y567278D02*
X1960811D01*
G01X1962704Y571701D02*
Y567278D01*
G01X1962640Y582446D02*
Y586035D01*
X1960747D01*
X1962640Y589314D01*
X1964533Y586035D01*
X1962640D01*
G01X1971400Y601990D02*
Y602910D01*
G01Y602450D02*
X1974500D01*
G01Y601990D02*
Y602910D01*
G01Y604707D02*
X1971400D01*
Y605473D01*
X1971555Y605780D01*
X1971762Y606010D01*
X1972072Y606202D01*
X1972433Y606355D01*
X1972950Y606393D01*
X1973467Y606355D01*
X1973828Y606202D01*
X1974138Y606010D01*
X1974345Y605780D01*
X1974500Y605473D01*
Y604707D01*
G01X1975533Y607500D02*
Y609800D01*
G01X1971400Y610983D02*
X1974500D01*
Y612517D01*
G01Y615617D02*
Y614083D01*
X1971400D01*
Y615617D01*
G01X1972898Y615003D02*
Y614083D01*
G01X1974500Y617107D02*
X1971400D01*
Y617873D01*
X1971555Y618180D01*
X1971762Y618410D01*
X1972072Y618602D01*
X1972433Y618755D01*
X1972950Y618793D01*
X1973467Y618755D01*
X1973828Y618602D01*
X1974138Y618410D01*
X1974345Y618180D01*
X1974500Y617873D01*
Y617107D01*
G01X1963086Y611661D02*
Y615250D01*
X1961193D01*
X1963086Y618529D01*
X1964979Y615250D01*
X1963086D01*
G01X1964979Y618529D02*
X1961193D01*
G01X1963086Y622952D02*
Y618529D01*
G01X1964533Y589314D02*
X1960747D01*
G01X1962640Y593737D02*
Y589314D01*
G54D14*
G01X21100Y0D02*
G02I-21100J0D01*
G01X-9538Y434094D02*
G02I-4950J0D01*
G01X20462D02*
G02I-4950J0D01*
G01X10462D02*
G02I-4950J0D01*
G01X462D02*
G02I-4950J0D01*
G01X114930Y145531D02*
G02I-4950J0D01*
G01X104930D02*
G02I-4950J0D01*
G01X94930D02*
G02I-4950J0D01*
G01X124930D02*
G02I-4950J0D01*
G01X1396164Y23976D02*
G02I-3900J0D01*
G01X1517818D02*
G02I-3900J0D01*
G01X1709705Y534487D02*
G02X1704705I-2500J2304D01*
G01D02*
G02X1699705I-2500J2304D01*
G01D02*
G02X1694705I-2500J2304D01*
G01D02*
G02X1689705I-2500J2304D01*
G01D02*
G02Y539095I-2500J2304D01*
G01D02*
G02X1694705I2500J-2304D01*
G01D02*
G02X1699705I2500J-2304D01*
G01D02*
G02X1704705I2500J-2304D01*
G01D02*
G02X1709705I2500J-2304D01*
G01X1714705Y534487D02*
G02X1709705I-2500J2304D01*
G01Y539095D02*
G02X1714705I2500J-2304D01*
G01D02*
G02Y534487I2500J-2304D01*
G01X1738654Y536591D02*
Y536991D01*
G01X1759370Y539255D02*
G02X1764339Y536991I1969J-2264D01*
G01D02*
Y536591D01*
G01D02*
G02X1759370Y534327I-3000J0D01*
G01D02*
G02X1755434I-1968J2264D01*
G01D02*
G02X1751496I-1969J2264D01*
G01D02*
G02X1747560I-1968J2264D01*
G01D02*
G02X1743622I-1969J2264D01*
G01D02*
G02X1738654Y536591I-1968J2264D01*
G01Y536991D02*
G02X1743622Y539255I3000J0D01*
G01D02*
G02X1747560I1969J-2264D01*
G01D02*
G02X1751496I1968J-2264D01*
G01D02*
G02X1755434I1969J-2264D01*
G01D02*
G02X1759370I1968J-2264D01*
G01X1833865Y618663D02*
G02I-4200J0D01*
G01X1823865D02*
G02I-4200J0D01*
G01X1813865D02*
G02I-4200J0D01*
G01X1896947Y25774D02*
G03Y25526I3998J-124D01*
G03X1896121Y25650I-1004J-3872D01*
G03X1896947Y25774I-178J3996D01*
G01Y17782D02*
G03Y17534I3998J-124D01*
G03X1896121Y17658I-1004J-3872D01*
G03X1896947Y17782I-178J3996D01*
G01Y9790D02*
G03Y9542I3998J-124D01*
G03X1896121Y9666I-1004J-3872D01*
G03X1896947Y9790I-178J3996D01*
G01Y1798D02*
G03Y1550I3998J-124D01*
G03X1896120Y1674I-1003J-3872D01*
G03X1896947Y1798I-176J3996D01*
G01X1895768Y9666D02*
G02Y17658I177J3996D01*
G01D02*
G02Y25650I178J3996D01*
G01D02*
G02Y33642I178J3996D01*
G01X1901124Y-2322D02*
G02X1896947Y-6194I-179J-3996D01*
G01D02*
G02X1895769Y1674I-1004J3872D01*
G01D02*
G02X1895768Y9666I177J3996D01*
G01X1896947Y41758D02*
G03Y41510I3998J-124D01*
G03X1896121Y41634I-1004J-3872D01*
G03X1896947Y41758I-178J3996D01*
G01Y33766D02*
G03Y33518I3998J-124D01*
G03X1896121Y33642I-1004J-3872D01*
G03X1896947Y33766I-178J3996D01*
G01X1895768Y41634D02*
G02X1896947Y49502I176J3996D01*
G01D02*
G02X1901122Y45630I3998J124D01*
G01X1895768Y33642D02*
G02Y41634I176J3996D01*
G01X1870300Y108800D02*
G03I-600J0D01*
G01X1940787Y-11811D02*
X1921102D01*
G01X1899943Y-2198D02*
G03X1900766Y-2322I1004J3872D01*
G03X1899943Y-2446I181J-3996D01*
G03Y-2198I-3998J124D01*
G01Y5794D02*
G03X1900768Y5670I1004J3872D01*
G03X1899943Y5546I179J-3996D01*
G03Y5794I-3998J124D01*
G01Y29770D02*
G03X1900769Y29646I1004J3872D01*
G03X1899943Y29522I178J-3996D01*
G03Y29770I-3998J124D01*
G01Y21778D02*
G03X1900769Y21654I1004J3872D01*
G03X1899943Y21530I178J-3996D01*
G03Y21778I-3998J124D01*
G01Y13786D02*
G03X1900769Y13662I1004J3872D01*
G03X1899943Y13538I178J-3996D01*
G03Y13786I-3998J124D01*
G01X1901122Y37638D02*
G02Y29646I-178J-3996D01*
G01D02*
G02Y21654I-178J-3996D01*
G01D02*
G02X1901121Y13662I-178J-3996D01*
G01D02*
G02X1901123Y5670I-176J-3996D01*
G01D02*
G02X1901124Y-2322I-177J-3996D01*
G01X1921102Y55118D02*
X1940787D01*
G01X1899943Y37762D02*
G03X1900769Y37638I1004J3872D01*
G03X1899943Y37514I178J-3996D01*
G03Y37762I-3998J124D01*
G01X1900769Y45630D02*
G03X1899943Y45506I178J-3996D01*
G03Y45754I-3998J124D01*
G03X1900769Y45630I1004J3872D01*
G01X1901122D02*
G02Y37638I-175J-3996D01*
G01X1950666Y216540D02*
G02X1946200Y219837I-1016J3297D01*
G01Y210293D02*
G02X1949746Y214085I3801J0D01*
G01X1950000Y204093D02*
G02X1946200Y207893I0J3800D01*
G01D02*
Y210293D01*
G01X1958160Y208916D02*
G02X1954500Y204093I-3660J-1023D01*
G01D02*
X1950000D01*
G01X1959211Y239515D02*
G02X1964790Y238405I2679J-1110D01*
G01X1946200Y219837D02*
Y221737D01*
G01D02*
G02X1947924Y224724I3450J0D01*
G01D02*
G02X1946200Y227711I1726J2987D01*
G01D02*
Y229611D01*
G01D02*
G02X1950698Y232898I3450J0D01*
G01X1946200Y239155D02*
Y241555D01*
G01D02*
G02X1950000Y245355I3800J0D01*
G01D02*
X1954500D01*
G01D02*
G02X1957925Y239909I0J-3800D01*
G01X1950423Y235379D02*
G02X1946200Y239155I-423J3776D01*
G01X1963616Y213374D02*
G02X1964790Y211043I-1727J-2331D01*
G01X1967583Y210807D02*
X1972183D01*
G01X1964790Y211043D02*
G02X1959448Y209479I-2900J0D01*
G01X1972183Y210807D02*
G02Y203207I0J-3800D01*
G01D02*
X1967583D01*
G01D02*
G02Y210807I0J3800D01*
G01Y246241D02*
X1972183D01*
G01X1964790Y238405D02*
G02X1963863Y236280I-2899J0D01*
G01X1972183Y246241D02*
G02Y238641I0J-3800D01*
G01D02*
X1967583D01*
G01D02*
G02Y246241I0J3800D01*
G54D24*
G01X26854Y21062D02*
Y19962D01*
G01Y23762D02*
Y22662D01*
G01X26943Y51574D02*
Y50474D01*
G01Y54274D02*
Y53174D01*
G01X22200Y561700D02*
Y560600D01*
G01Y564400D02*
Y563300D01*
G01X17500Y528300D02*
Y527200D01*
G01Y531000D02*
Y529900D01*
G01X140900Y207500D02*
Y206400D01*
G01Y210200D02*
Y209100D01*
G01X144700Y274800D02*
Y273700D01*
G01Y272100D02*
Y271000D01*
G01X140900Y242900D02*
Y241800D01*
G01Y240200D02*
Y239100D01*
G01X141600Y308000D02*
Y306900D01*
G01Y305300D02*
Y304200D01*
G01X143409Y339300D02*
Y338200D01*
G01Y336600D02*
Y335500D01*
G01X141210Y371574D02*
Y370474D01*
G01Y368874D02*
Y367774D01*
G01X681600Y226200D02*
Y227300D01*
G01Y228900D02*
Y230000D01*
G01X792899Y209500D02*
Y208400D01*
G01Y206800D02*
Y205700D01*
G01X796351Y242866D02*
Y241766D01*
G01Y240166D02*
Y239066D01*
G01X795587Y274798D02*
Y273698D01*
G01Y272098D02*
Y270998D01*
G01X793000Y338300D02*
Y337200D01*
G01Y335600D02*
Y334500D01*
G01X794770Y306900D02*
Y305800D01*
G01Y304200D02*
Y303100D01*
G01X789782Y370317D02*
Y369217D01*
G01Y367617D02*
Y366517D01*
G01X1340272Y38815D02*
Y39915D01*
G01Y41515D02*
Y42615D01*
G01X1354160Y10420D02*
Y11520D01*
G01Y7720D02*
Y8820D01*
G01X1358000Y366300D02*
Y367400D01*
G01Y369000D02*
Y370100D01*
G01X1354400Y556800D02*
Y557900D01*
G01Y554100D02*
Y555200D01*
G01X1359682Y616700D02*
Y617800D01*
G01Y619400D02*
Y620500D01*
G01X1413093Y131497D02*
X1416507D01*
X1416531Y131473D01*
G01X1413081Y131246D02*
X1413069Y131234D01*
G01X1426237Y136561D02*
X1425697Y136291D01*
G01X1426517Y136841D02*
X1426237Y136561D01*
G01X1426787Y137661D02*
X1426517Y136841D01*
G01X1426787Y138511D02*
Y137661D01*
G01X1426517Y139331D02*
X1426787Y138511D01*
G01X1425967Y139881D02*
X1426517Y139331D01*
G01X1425147Y140191D02*
X1425967Y139881D01*
G01X1424517Y140191D02*
X1425147D01*
G01X1423697Y139881D02*
X1424517Y140191D01*
G01X1423427Y139611D02*
X1423697Y139881D01*
G01X1423147Y139061D02*
X1423427Y139611D01*
G01X1423147Y138201D02*
Y139061D01*
G01X1420877Y139881D02*
X1423147Y138201D01*
G01X1420877Y136841D02*
Y139881D01*
G01Y132791D02*
Y131661D01*
G01X1421147Y133611D02*
X1420877Y132791D01*
G01X1421697Y133881D02*
X1421147Y133611D01*
G01X1422237Y133881D02*
X1421697D01*
G01X1422877Y133611D02*
X1422237Y133881D01*
G01X1423147Y133061D02*
X1422877Y133611D01*
G01X1423427Y131931D02*
X1423147Y133061D01*
G01X1423697Y131111D02*
X1423427Y131931D01*
G01X1424237Y130561D02*
X1423697Y131111D01*
G01X1424787Y130291D02*
X1424237Y130561D01*
G01X1425697Y130291D02*
X1424787D01*
G01X1426237Y130561D02*
X1425697Y130291D01*
G01X1426517Y130841D02*
X1426237Y130561D01*
G01X1426787Y131661D02*
X1426517Y130841D01*
G01X1426787Y132791D02*
Y131661D01*
G01X1426517Y133611D02*
X1426787Y132791D01*
G01X1426237Y133881D02*
X1426517Y133611D01*
G01X1425697Y134191D02*
X1426237Y133881D01*
G01X1424787Y134191D02*
X1425697D01*
G01X1424237Y133881D02*
X1424787Y134191D01*
G01X1423697Y133331D02*
X1424237Y133881D01*
G01X1423427Y132511D02*
X1423697Y133331D01*
G01X1423147Y131381D02*
X1423427Y132511D01*
G01X1422877Y130841D02*
X1423147Y131381D01*
G01X1422237Y130561D02*
X1422877Y130841D01*
G01X1421697Y130561D02*
X1422237D01*
G01X1421147Y130841D02*
X1421697Y130561D01*
G01X1420877Y131661D02*
X1421147Y130841D01*
G01X1424787Y124291D02*
Y128191D01*
G01X1420877Y126861D02*
X1424787Y124291D01*
G01X1420877Y126861D02*
X1426787D01*
G01X1426237Y118561D02*
X1425697Y118291D01*
G01X1426517Y118841D02*
X1426237Y118561D01*
G01X1426787Y119661D02*
X1426517Y118841D01*
G01X1426787Y120471D02*
Y119661D01*
G01X1426517Y121331D02*
X1426787Y120471D01*
G01X1425967Y121881D02*
X1426517Y121331D01*
G01X1425147Y122191D02*
X1425967Y121881D01*
G01X1424517Y122191D02*
X1425147D01*
G01X1423697Y121881D02*
X1424517Y122191D01*
G01X1423147Y121331D02*
X1423697Y121881D01*
G01X1422877Y120471D02*
X1423147Y121331D01*
G01X1422877Y119661D02*
Y120471D01*
G01X1423147Y118841D02*
X1422877Y119661D01*
G01X1423427Y118561D02*
X1423147Y118841D01*
G01X1420877D02*
X1423427Y118561D01*
G01X1420877Y121611D02*
Y118841D01*
G01X1424787Y112291D02*
Y116191D01*
G01X1420877Y114861D02*
X1424787Y112291D01*
G01X1420877Y114861D02*
X1426787D01*
G01X1420877Y108591D02*
X1426787D01*
G01X1421697Y108121D02*
X1420877Y108591D01*
G01X1421967Y107811D02*
X1421697Y108121D01*
G01X1423697Y100291D02*
Y102671D01*
G01X1426787Y100291D02*
Y104191D01*
G01X1420787Y100291D02*
X1426787D01*
G01X1420787Y104191D02*
Y100291D01*
G01X1465933Y588753D02*
X1464833D01*
G01X1512900Y64600D02*
X1512700D01*
G01X1508700Y63900D02*
X1513900D01*
G01Y63200D02*
X1507200D01*
G01X1506100Y62500D02*
X1513900D01*
G01Y61800D02*
X1505200D01*
G01X1512700Y61100D02*
X1513900D01*
G01X1504400D02*
X1512700D01*
G01X1509500Y60400D02*
X1503700D01*
G01X1503200Y59700D02*
X1508300D01*
G01X1507300Y59000D02*
X1502700D01*
G01X1502300Y58300D02*
X1506600D01*
G01X1506000Y57600D02*
X1501900D01*
G01X1501600Y56900D02*
X1505600D01*
G01X1505200Y56200D02*
X1501400D01*
G01X1501200Y55500D02*
X1504900D01*
G01X1504700Y54800D02*
X1501000D01*
G01Y54100D02*
X1504500D01*
G01X1504400Y53400D02*
X1500900D01*
G01Y52700D02*
X1504400D01*
G01X1504500Y52000D02*
X1501000D01*
G01X1501100Y51300D02*
X1504600D01*
G01X1504800Y50600D02*
X1501100D01*
G01X1501300Y49900D02*
X1505000D01*
G01X1505300Y49200D02*
X1501500D01*
G01X1501700Y48500D02*
X1505600D01*
G01X1506100Y47800D02*
X1502100D01*
G01X1502400Y47100D02*
X1506700D01*
G01X1507400Y46400D02*
X1502800D01*
G01X1503400Y45700D02*
X1508400D01*
G01X1510200Y45000D02*
X1503900D01*
G01X1504600Y44300D02*
X1513900D01*
G01Y43600D02*
X1505400D01*
G01X1506300Y42900D02*
X1513900D01*
G01Y42200D02*
X1507600D01*
G01X1509400Y41500D02*
X1513900D01*
G01Y64500D02*
Y61000D01*
G01X1512900Y64600D02*
X1513900Y64500D01*
G01X1512700Y64600D02*
X1512900D01*
G01X1510700Y64400D02*
X1512700Y64600D01*
G01X1508700Y63900D02*
X1510700Y64400D01*
G01X1506800Y63000D02*
X1508700Y63900D01*
G01X1505200Y61800D02*
X1506800Y63000D01*
G01X1503700Y60400D02*
X1505200Y61800D01*
G01X1502500Y58700D02*
X1503700Y60400D01*
G01X1501600Y56800D02*
X1502500Y58700D01*
G01X1501100Y54900D02*
X1501600Y56800D01*
G01X1500900Y52800D02*
X1501100Y54900D01*
G01X1500900Y52600D02*
Y52800D01*
G01X1501100Y50600D02*
X1500900Y52600D01*
G01X1501600Y48700D02*
X1501100Y50600D01*
G01X1502500Y46800D02*
X1501600Y48700D01*
G01X1503700Y45200D02*
X1502500Y46800D01*
G01X1505100Y43800D02*
X1503700Y45200D01*
G01X1506700Y42600D02*
X1505100Y43800D01*
G01X1508600Y41700D02*
X1506700Y42600D01*
G01X1510500Y41200D02*
X1508600Y41700D01*
G01X1512500Y41000D02*
X1510500Y41200D01*
G01X1512900Y41000D02*
X1512500D01*
G01X1513900Y41100D02*
X1512900Y41000D01*
G01X1513900Y44600D02*
Y41100D01*
G01X1513100Y44500D02*
X1513900Y44600D01*
G01X1512500Y44500D02*
X1513100D01*
G01X1511100Y44700D02*
X1512500Y44500D01*
G01X1509800Y45100D02*
X1511100Y44700D01*
G01X1508500Y45600D02*
X1509800Y45100D01*
G01X1507400Y46400D02*
X1508500Y45600D01*
G01X1506300Y47500D02*
X1507400Y46400D01*
G01X1505500Y48600D02*
X1506300Y47500D01*
G01X1505000Y49900D02*
X1505500Y48600D01*
G01X1504600Y51200D02*
X1505000Y49900D01*
G01X1504400Y52600D02*
X1504600Y51200D01*
G01X1504400Y52800D02*
Y52600D01*
G01X1504600Y54200D02*
X1504400Y52800D01*
G01X1505000Y55600D02*
X1504600Y54200D01*
G01X1505600Y56900D02*
X1505000Y55600D01*
G01X1506400Y58100D02*
X1505600Y56900D01*
G01X1507400Y59100D02*
X1506400Y58100D01*
G01X1508600Y59900D02*
X1507400Y59100D01*
G01X1509900Y60600D02*
X1508600Y59900D01*
G01X1511300Y60900D02*
X1509900Y60600D01*
G01X1512700Y61100D02*
X1511300Y60900D01*
G01X1513900Y61000D02*
X1512700Y61100D01*
G01X1531600Y54400D02*
X1523300D01*
G01Y53700D02*
X1531600D01*
G01Y53000D02*
X1523300D01*
G01Y52300D02*
X1531600D01*
G01Y51600D02*
X1523300D01*
G01Y54400D02*
X1531600D01*
G01X1523300Y51200D02*
Y54400D01*
G01X1531600Y51200D02*
X1523300D01*
G01X1526100Y62500D02*
X1534000D01*
G01Y61800D02*
X1525200D01*
G01X1524500Y61100D02*
X1532800D01*
G01X1529600Y60400D02*
X1523800D01*
G01X1523300Y59700D02*
X1528400D01*
G01X1527400Y59000D02*
X1522800D01*
G01X1522400Y58300D02*
X1526700D01*
G01X1526100Y57600D02*
X1522000D01*
G01X1521700Y56900D02*
X1525700D01*
G01X1525300Y56200D02*
X1521500D01*
G01X1521300Y55500D02*
X1524900D01*
G01X1524800Y54800D02*
X1521100D01*
G01Y54100D02*
X1524600D01*
G01X1524500Y53400D02*
X1521000D01*
G01Y52700D02*
X1524500D01*
G01X1524600Y52000D02*
X1521100D01*
G01X1521200Y51300D02*
X1524700D01*
G01X1524900Y50600D02*
X1521200D01*
G01X1521400Y49900D02*
X1525000D01*
G01X1525400Y49200D02*
X1521600D01*
G01X1521800Y48500D02*
X1525700D01*
G01X1526200Y47800D02*
X1522200D01*
G01X1522500Y47100D02*
X1526800D01*
G01X1527400Y46400D02*
X1522900D01*
G01X1523400Y45700D02*
X1528500D01*
G01X1530200Y45000D02*
X1524000D01*
G01X1524700Y44300D02*
X1534000D01*
G01Y43600D02*
X1525500D01*
G01X1526400Y42900D02*
X1534000D01*
G01X1526900Y63000D02*
X1528800Y63900D01*
G01X1525200Y61800D02*
X1526900Y63000D01*
G01X1523800Y60400D02*
X1525200Y61800D01*
G01X1522600Y58700D02*
X1523800Y60400D01*
G01X1521700Y56800D02*
X1522600Y58700D01*
G01X1521200Y54900D02*
X1521700Y56800D01*
G01X1521000Y52800D02*
X1521200Y54900D01*
G01X1521000Y52600D02*
Y52800D01*
G01X1521200Y50600D02*
X1521000Y52600D01*
G01X1521700Y48700D02*
X1521200Y50600D01*
G01X1522600Y46800D02*
X1521700Y48700D01*
G01X1523700Y45200D02*
X1522600Y46800D01*
G01X1525200Y43800D02*
X1523700Y45200D01*
G01X1526800Y42600D02*
X1525200Y43800D01*
G01X1528700Y41700D02*
X1526800Y42600D01*
G01X1526400Y47500D02*
X1527400Y46400D01*
G01X1525600Y48600D02*
X1526400Y47500D01*
G01X1525000Y49900D02*
X1525600Y48600D01*
G01X1524700Y51200D02*
X1525000Y49900D01*
G01X1524500Y52600D02*
X1524700Y51200D01*
G01X1524500Y52800D02*
Y52600D01*
G01X1524700Y54200D02*
X1524500Y52800D01*
G01X1525000Y55600D02*
X1524700Y54200D01*
G01X1525700Y56900D02*
X1525000Y55600D01*
G01X1526500Y58100D02*
X1525700Y56900D01*
G01X1527500Y59100D02*
X1526500Y58100D01*
G01X1501230Y594354D02*
X1500130D01*
G01X1503930D02*
X1502830D01*
G01X1468633Y588753D02*
X1467533D01*
G01X1531600Y54400D02*
Y51200D01*
G01X1533000Y64600D02*
X1532800D01*
G01X1528800Y63900D02*
X1534000D01*
G01Y63200D02*
X1527300D01*
G01X1532800Y61100D02*
X1534000D01*
G01Y42200D02*
X1527700D01*
G01X1529500Y41500D02*
X1534000D01*
G01Y64500D02*
Y61000D01*
G01X1533000Y64600D02*
X1534000Y64500D01*
G01X1532800Y64600D02*
X1533000D01*
G01X1530700Y64400D02*
X1532800Y64600D01*
G01X1528800Y63900D02*
X1530700Y64400D01*
G01X1530600Y41200D02*
X1528700Y41700D01*
G01X1532600Y41000D02*
X1530600Y41200D01*
G01X1533000Y41000D02*
X1532600D01*
G01X1534000Y41100D02*
X1533000Y41000D01*
G01X1534000Y44600D02*
Y41100D01*
G01X1533200Y44500D02*
X1534000Y44600D01*
G01X1532600Y44500D02*
X1533200D01*
G01X1531200Y44700D02*
X1532600Y44500D01*
G01X1529800Y45100D02*
X1531200Y44700D01*
G01X1528600Y45600D02*
X1529800Y45100D01*
G01X1527400Y46400D02*
X1528600Y45600D01*
G01X1528700Y59900D02*
X1527500Y59100D01*
G01X1530000Y60600D02*
X1528700Y59900D01*
G01X1531400Y60900D02*
X1530000Y60600D01*
G01X1532800Y61100D02*
X1531400Y60900D01*
G01X1534000Y61000D02*
X1532800Y61100D01*
G01X1743609Y170294D02*
X1739609D01*
G54D15*
G01X46989Y446306D02*
Y441106D01*
G01X1499891Y39126D02*
X1497391D01*
G01X1502694Y83061D02*
Y84461D01*
G01X1886750Y564950D02*
X1882900D01*
Y568750D01*
G01X1893750Y552350D02*
Y548500D01*
X1889950D01*
G01X1955437Y141595D02*
X1951087D01*
Y145345D01*
G01X1957891Y483819D02*
Y482319D01*
G54D25*
G01X1708528Y183480D02*
Y192157D01*
G01X1718142Y183480D02*
X1708528D01*
G01Y199205D02*
Y207642D01*
X1718240D01*
G01X1848232Y207693D02*
X1857937D01*
Y199646D01*
G01Y191575D02*
Y183481D01*
X1848492D01*
G54D16*
G01X22835Y-23622D02*
X-7874D01*
G01Y626378D02*
X22835D01*
G01X137797Y-23620D02*
X168506D01*
G01X137797Y626380D02*
X168506D01*
G01X341734Y-23620D02*
X372443D01*
G01X341734Y626380D02*
X372443D01*
G01X560632Y-23620D02*
X529923D01*
G01Y626380D02*
X560632D01*
G01X819687Y-23620D02*
X788979D01*
G01Y626380D02*
X819687D01*
G01X961023Y-23622D02*
X991732D01*
G01X1006301Y-23620D02*
X975593D01*
G01Y626380D02*
X1006301D01*
G01X1162207Y-23620D02*
X1192916D01*
G01Y626380D02*
X1162207D01*
G01X1429134Y-23622D02*
X1398425D01*
G01X1425199Y626380D02*
X1394490D01*
G01X1881890Y-23622D02*
X1851181D01*
G01X1881892Y626380D02*
X1851183D01*
G54D17*
G01X188619Y9368D02*
Y17368D01*
X190953D01*
X191886Y16968D01*
X192586Y16435D01*
X193169Y15635D01*
X193636Y14701D01*
X193753Y13368D01*
X193636Y12035D01*
X193169Y11101D01*
X192586Y10301D01*
X191886Y9768D01*
X190953Y9368D01*
X188619D01*
G01X199286Y17368D02*
X202086D01*
G01X200686D02*
Y9368D01*
G01X199286D02*
X202086D01*
G01X207153D02*
Y17368D01*
X210186Y10701D01*
X213219Y17368D01*
Y9368D01*
G01X216653D02*
Y17368D01*
X219686Y10701D01*
X222719Y17368D01*
Y9368D01*
G01X241253Y16701D02*
X240553Y17101D01*
X239736Y17368D01*
X238803D01*
X237753Y16968D01*
X236936Y16301D01*
X236353Y15501D01*
X235886Y14168D01*
X235769Y12968D01*
X236003Y11768D01*
X236353Y10968D01*
X237053Y10168D01*
X237869Y9635D01*
X238686Y9368D01*
X239503D01*
X240319Y9635D01*
X241019Y10035D01*
X241603Y10568D01*
G01X245969Y16035D02*
X246669Y16835D01*
X247486Y17235D01*
X248419Y17368D01*
X249586Y17101D01*
X250403Y16435D01*
X250636Y15635D01*
X250519Y14834D01*
X250053Y14168D01*
X247719Y12835D01*
X246669Y11901D01*
X245969Y10568D01*
X245736Y9368D01*
X250636D01*
G01X192383Y46735D02*
Y54735D01*
X194717D01*
X195650Y54335D01*
X196350Y53802D01*
X196933Y53002D01*
X197400Y52068D01*
X197517Y50735D01*
X197400Y49402D01*
X196933Y48468D01*
X196350Y47668D01*
X195650Y47135D01*
X194717Y46735D01*
X192383D01*
G01X203050Y54735D02*
X205850D01*
G01X204450D02*
Y46735D01*
G01X203050D02*
X205850D01*
G01X210917D02*
Y54735D01*
X213950Y48068D01*
X216983Y54735D01*
Y46735D01*
G01X220417D02*
Y54735D01*
X223450Y48068D01*
X226483Y54735D01*
Y46735D01*
G01X245017Y54068D02*
X244317Y54468D01*
X243500Y54735D01*
X242567D01*
X241517Y54335D01*
X240700Y53668D01*
X240117Y52868D01*
X239650Y51535D01*
X239533Y50335D01*
X239767Y49135D01*
X240117Y48335D01*
X240817Y47535D01*
X241633Y47002D01*
X242450Y46735D01*
X243267D01*
X244083Y47002D01*
X244783Y47402D01*
X245367Y47935D01*
G01X251950Y46735D02*
Y54735D01*
X250550Y53135D01*
G01Y46735D02*
X253350D01*
G01X192787Y95662D02*
Y103662D01*
X195121D01*
X196054Y103262D01*
X196754Y102729D01*
X197337Y101929D01*
X197804Y100995D01*
X197921Y99662D01*
X197804Y98329D01*
X197337Y97395D01*
X196754Y96595D01*
X196054Y96062D01*
X195121Y95662D01*
X192787D01*
G01X203454Y103662D02*
X206254D01*
G01X204854D02*
Y95662D01*
G01X203454D02*
X206254D01*
G01X211321D02*
Y103662D01*
X214354Y96995D01*
X217387Y103662D01*
Y95662D01*
G01X220821D02*
Y103662D01*
X223854Y96995D01*
X226887Y103662D01*
Y95662D01*
G01X245421Y102995D02*
X244721Y103395D01*
X243904Y103662D01*
X242971D01*
X241921Y103262D01*
X241104Y102595D01*
X240521Y101795D01*
X240054Y100462D01*
X239937Y99262D01*
X240171Y98062D01*
X240521Y97262D01*
X241221Y96462D01*
X242037Y95929D01*
X242854Y95662D01*
X243671D01*
X244487Y95929D01*
X245187Y96329D01*
X245771Y96862D01*
G01X252354Y103662D02*
X251421Y103395D01*
X250721Y102729D01*
X250254Y101929D01*
X249904Y100862D01*
X249787Y99662D01*
X249904Y98462D01*
X250254Y97395D01*
X250721Y96595D01*
X251421Y95929D01*
X252354Y95662D01*
X253287Y95929D01*
X253987Y96595D01*
X254454Y97395D01*
X254804Y98462D01*
X254921Y99662D01*
X254804Y100862D01*
X254454Y101929D01*
X253987Y102729D01*
X253287Y103395D01*
X252354Y103662D01*
G01X210395Y500515D02*
Y508515D01*
X212729D01*
X213662Y508115D01*
X214362Y507582D01*
X214945Y506782D01*
X215412Y505848D01*
X215529Y504515D01*
X215412Y503182D01*
X214945Y502248D01*
X214362Y501448D01*
X213662Y500915D01*
X212729Y500515D01*
X210395D01*
G01X221062Y508515D02*
X223862D01*
G01X222462D02*
Y500515D01*
G01X221062D02*
X223862D01*
G01X228929D02*
Y508515D01*
X231962Y501848D01*
X234995Y508515D01*
Y500515D01*
G01X238429D02*
Y508515D01*
X241462Y501848D01*
X244495Y508515D01*
Y500515D01*
G01X257895D02*
Y508515D01*
X260229D01*
X261162Y508115D01*
X261862Y507582D01*
X262445Y506782D01*
X262912Y505848D01*
X263029Y504515D01*
X262912Y503182D01*
X262445Y502248D01*
X261862Y501448D01*
X261162Y500915D01*
X260229Y500515D01*
X257895D01*
G01X269962Y508515D02*
X269029Y508248D01*
X268329Y507582D01*
X267862Y506782D01*
X267512Y505715D01*
X267395Y504515D01*
X267512Y503315D01*
X267862Y502248D01*
X268329Y501448D01*
X269029Y500782D01*
X269962Y500515D01*
X270895Y500782D01*
X271595Y501448D01*
X272062Y502248D01*
X272412Y503315D01*
X272529Y504515D01*
X272412Y505715D01*
X272062Y506782D01*
X271595Y507582D01*
X270895Y508248D01*
X269962Y508515D01*
G01X208244Y547829D02*
Y555829D01*
X210578D01*
X211511Y555429D01*
X212211Y554896D01*
X212794Y554096D01*
X213261Y553162D01*
X213378Y551829D01*
X213261Y550496D01*
X212794Y549562D01*
X212211Y548762D01*
X211511Y548229D01*
X210578Y547829D01*
X208244D01*
G01X218911Y555829D02*
X221711D01*
G01X220311D02*
Y547829D01*
G01X218911D02*
X221711D01*
G01X226778D02*
Y555829D01*
X229811Y549162D01*
X232844Y555829D01*
Y547829D01*
G01X236278D02*
Y555829D01*
X239311Y549162D01*
X242344Y555829D01*
Y547829D01*
G01X255744D02*
Y555829D01*
X258078D01*
X259011Y555429D01*
X259711Y554896D01*
X260294Y554096D01*
X260761Y553162D01*
X260878Y551829D01*
X260761Y550496D01*
X260294Y549562D01*
X259711Y548762D01*
X259011Y548229D01*
X258078Y547829D01*
X255744D01*
G01X267811D02*
Y555829D01*
X266411Y554229D01*
G01Y547829D02*
X269211D01*
G01X211739Y585465D02*
Y593465D01*
X214073D01*
X215006Y593065D01*
X215706Y592532D01*
X216289Y591732D01*
X216756Y590798D01*
X216873Y589465D01*
X216756Y588132D01*
X216289Y587198D01*
X215706Y586398D01*
X215006Y585865D01*
X214073Y585465D01*
X211739D01*
G01X222406Y593465D02*
X225206D01*
G01X223806D02*
Y585465D01*
G01X222406D02*
X225206D01*
G01X230273D02*
Y593465D01*
X233306Y586798D01*
X236339Y593465D01*
Y585465D01*
G01X239773D02*
Y593465D01*
X242806Y586798D01*
X245839Y593465D01*
Y585465D01*
G01X259239D02*
Y593465D01*
X261573D01*
X262506Y593065D01*
X263206Y592532D01*
X263789Y591732D01*
X264256Y590798D01*
X264373Y589465D01*
X264256Y588132D01*
X263789Y587198D01*
X263206Y586398D01*
X262506Y585865D01*
X261573Y585465D01*
X259239D01*
G01X269089Y592132D02*
X269789Y592932D01*
X270606Y593332D01*
X271539Y593465D01*
X272706Y593198D01*
X273523Y592532D01*
X273756Y591732D01*
X273639Y590931D01*
X273173Y590265D01*
X270839Y588932D01*
X269789Y587998D01*
X269089Y586665D01*
X268856Y585465D01*
X273756D01*
G01X875473Y500246D02*
Y508246D01*
X877807D01*
X878740Y507846D01*
X879440Y507313D01*
X880023Y506513D01*
X880490Y505579D01*
X880607Y504246D01*
X880490Y502913D01*
X880023Y501979D01*
X879440Y501179D01*
X878740Y500646D01*
X877807Y500246D01*
X875473D01*
G01X886140Y508246D02*
X888940D01*
G01X887540D02*
Y500246D01*
G01X886140D02*
X888940D01*
G01X894007D02*
Y508246D01*
X897040Y501579D01*
X900073Y508246D01*
Y500246D01*
G01X903507D02*
Y508246D01*
X906540Y501579D01*
X909573Y508246D01*
Y500246D01*
G01X926473Y504513D02*
X926940Y504913D01*
X927290Y505579D01*
X927523Y506513D01*
X927290Y507313D01*
X926823Y507846D01*
X926007Y508246D01*
X922857D01*
Y500246D01*
X926707D01*
X927523Y500779D01*
X927990Y501579D01*
X928223Y502513D01*
X927990Y503446D01*
X927290Y504246D01*
X926473Y504513D01*
X922857D01*
G01X935040Y508246D02*
X934107Y507979D01*
X933407Y507313D01*
X932940Y506513D01*
X932590Y505446D01*
X932473Y504246D01*
X932590Y503046D01*
X932940Y501979D01*
X933407Y501179D01*
X934107Y500513D01*
X935040Y500246D01*
X935973Y500513D01*
X936673Y501179D01*
X937140Y501979D01*
X937490Y503046D01*
X937607Y504246D01*
X937490Y505446D01*
X937140Y506513D01*
X936673Y507313D01*
X935973Y507979D01*
X935040Y508246D01*
G01X865931Y547563D02*
Y555563D01*
X868265D01*
X869198Y555163D01*
X869898Y554630D01*
X870481Y553830D01*
X870948Y552896D01*
X871065Y551563D01*
X870948Y550230D01*
X870481Y549296D01*
X869898Y548496D01*
X869198Y547963D01*
X868265Y547563D01*
X865931D01*
G01X876598Y555563D02*
X879398D01*
G01X877998D02*
Y547563D01*
G01X876598D02*
X879398D01*
G01X884465D02*
Y555563D01*
X887498Y548896D01*
X890531Y555563D01*
Y547563D01*
G01X893965D02*
Y555563D01*
X896998Y548896D01*
X900031Y555563D01*
Y547563D01*
G01X916931Y551830D02*
X917398Y552230D01*
X917748Y552896D01*
X917981Y553830D01*
X917748Y554630D01*
X917281Y555163D01*
X916465Y555563D01*
X913315D01*
Y547563D01*
X917165D01*
X917981Y548096D01*
X918448Y548896D01*
X918681Y549830D01*
X918448Y550763D01*
X917748Y551563D01*
X916931Y551830D01*
X913315D01*
G01X925498Y547563D02*
Y555563D01*
X924098Y553963D01*
G01Y547563D02*
X926898D01*
G01X865797Y585601D02*
Y593601D01*
X868131D01*
X869064Y593201D01*
X869764Y592668D01*
X870347Y591868D01*
X870814Y590934D01*
X870931Y589601D01*
X870814Y588268D01*
X870347Y587334D01*
X869764Y586534D01*
X869064Y586001D01*
X868131Y585601D01*
X865797D01*
G01X876464Y593601D02*
X879264D01*
G01X877864D02*
Y585601D01*
G01X876464D02*
X879264D01*
G01X884331D02*
Y593601D01*
X887364Y586934D01*
X890397Y593601D01*
Y585601D01*
G01X893831D02*
Y593601D01*
X896864Y586934D01*
X899897Y593601D01*
Y585601D01*
G01X916797Y589868D02*
X917264Y590268D01*
X917614Y590934D01*
X917847Y591868D01*
X917614Y592668D01*
X917147Y593201D01*
X916331Y593601D01*
X913181D01*
Y585601D01*
X917031D01*
X917847Y586134D01*
X918314Y586934D01*
X918547Y587868D01*
X918314Y588801D01*
X917614Y589601D01*
X916797Y589868D01*
X913181D01*
G01X923147Y592268D02*
X923847Y593068D01*
X924664Y593468D01*
X925597Y593601D01*
X926764Y593334D01*
X927581Y592668D01*
X927814Y591868D01*
X927697Y591067D01*
X927231Y590401D01*
X924897Y589068D01*
X923847Y588134D01*
X923147Y586801D01*
X922914Y585601D01*
X927814D01*
G01X1158548Y9099D02*
Y17099D01*
X1160882D01*
X1161815Y16699D01*
X1162515Y16166D01*
X1163098Y15366D01*
X1163565Y14432D01*
X1163682Y13099D01*
X1163565Y11766D01*
X1163098Y10832D01*
X1162515Y10032D01*
X1161815Y9499D01*
X1160882Y9099D01*
X1158548D01*
G01X1169215Y17099D02*
X1172015D01*
G01X1170615D02*
Y9099D01*
G01X1169215D02*
X1172015D01*
G01X1177082D02*
Y17099D01*
X1180115Y10432D01*
X1183148Y17099D01*
Y9099D01*
G01X1186582D02*
Y17099D01*
X1189615Y10432D01*
X1192648Y17099D01*
Y9099D01*
G01X1205698D02*
X1208615Y17099D01*
X1211532Y9099D01*
G01X1210482Y11899D02*
X1206748D01*
G01X1215898Y15766D02*
X1216598Y16566D01*
X1217415Y16966D01*
X1218348Y17099D01*
X1219515Y16832D01*
X1220332Y16166D01*
X1220565Y15366D01*
X1220448Y14565D01*
X1219982Y13899D01*
X1217648Y12566D01*
X1216598Y11632D01*
X1215898Y10299D01*
X1215665Y9099D01*
X1220565D01*
G01X1158682Y47004D02*
Y55004D01*
X1161016D01*
X1161949Y54604D01*
X1162649Y54071D01*
X1163232Y53271D01*
X1163699Y52337D01*
X1163816Y51004D01*
X1163699Y49671D01*
X1163232Y48737D01*
X1162649Y47937D01*
X1161949Y47404D01*
X1161016Y47004D01*
X1158682D01*
G01X1169349Y55004D02*
X1172149D01*
G01X1170749D02*
Y47004D01*
G01X1169349D02*
X1172149D01*
G01X1177216D02*
Y55004D01*
X1180249Y48337D01*
X1183282Y55004D01*
Y47004D01*
G01X1186716D02*
Y55004D01*
X1189749Y48337D01*
X1192782Y55004D01*
Y47004D01*
G01X1205832D02*
X1208749Y55004D01*
X1211666Y47004D01*
G01X1210616Y49804D02*
X1206882D01*
G01X1218249Y47004D02*
Y55004D01*
X1216849Y53404D01*
G01Y47004D02*
X1219649D01*
G01X1158414Y94586D02*
Y102586D01*
X1160748D01*
X1161681Y102186D01*
X1162381Y101653D01*
X1162964Y100853D01*
X1163431Y99919D01*
X1163548Y98586D01*
X1163431Y97253D01*
X1162964Y96319D01*
X1162381Y95519D01*
X1161681Y94986D01*
X1160748Y94586D01*
X1158414D01*
G01X1169081Y102586D02*
X1171881D01*
G01X1170481D02*
Y94586D01*
G01X1169081D02*
X1171881D01*
G01X1176948D02*
Y102586D01*
X1179981Y95919D01*
X1183014Y102586D01*
Y94586D01*
G01X1186448D02*
Y102586D01*
X1189481Y95919D01*
X1192514Y102586D01*
Y94586D01*
G01X1205564D02*
X1208481Y102586D01*
X1211398Y94586D01*
G01X1210348Y97386D02*
X1206614D01*
G01X1217981Y102586D02*
X1217048Y102319D01*
X1216348Y101653D01*
X1215881Y100853D01*
X1215531Y99786D01*
X1215414Y98586D01*
X1215531Y97386D01*
X1215881Y96319D01*
X1216348Y95519D01*
X1217048Y94853D01*
X1217981Y94586D01*
X1218914Y94853D01*
X1219614Y95519D01*
X1220081Y96319D01*
X1220431Y97386D01*
X1220548Y98586D01*
X1220431Y99786D01*
X1220081Y100853D01*
X1219614Y101653D01*
X1218914Y102319D01*
X1217981Y102586D01*
G54D18*
G01X17012Y421634D02*
X22012D01*
Y426634D01*
G01X121480Y133071D02*
X126480D01*
Y138071D01*
G01X471746Y-42801D02*
Y-37801D01*
X466746D01*
G01X491746Y-42801D02*
Y-37801D01*
X486746D01*
G01X511746Y-42801D02*
Y-37801D01*
X506746D01*
G01X531746Y-42801D02*
Y-37801D01*
X526746D01*
G01X551746Y-42801D02*
Y-37801D01*
X546746D01*
G01X571746Y-42801D02*
Y-37801D01*
X566746D01*
G01X803484Y-42557D02*
Y-37557D01*
X798484D01*
G01X823484Y-42557D02*
Y-37557D01*
X818484D01*
G01X843484Y-42557D02*
Y-37557D01*
X838484D01*
G01X863484Y-42557D02*
Y-37557D01*
X858484D01*
G01X883484Y-42557D02*
Y-37557D01*
X878484D01*
G01X903484Y-42557D02*
Y-37557D01*
X898484D01*
G01X1140083Y-42785D02*
Y-37785D01*
X1135083D01*
G01X1160083Y-42785D02*
Y-37785D01*
X1155083D01*
G01X1396758Y-42757D02*
Y-37757D01*
X1391758D01*
G01X1416758Y-42757D02*
Y-37757D01*
X1411758D01*
G01X1436758Y-42757D02*
Y-37757D01*
X1431758D01*
G01X1456758Y-42757D02*
Y-37757D01*
X1451758D01*
G01X1830665Y612263D02*
X1835665D01*
Y617263D01*
G54D19*
G01X819400Y172900D02*
G03I-10900J0D01*
M02*
